G04 ================== begin FILE IDENTIFICATION RECORD ==================*
G04 Layout Name:  9324_DA0F0TMBIJ0_F0T_Motherboard_J_v01_20230324_0910.brd*
G04 Film Name:    in3*
G04 File Format:  Gerber RS274X*
G04 File Origin:  Cadence Allegro 17.2-S081*
G04 Origin Date:  Sat Mar 25 08:44:57 2023*
G04 *
G04 Layer:  PIN/SPECIAL_DRILL*
G04 Layer:  DRAWING FORMAT/TITLE_BLOCK_A*
G04 Layer:  VIA CLASS/IN3*
G04 Layer:  PIN/IN3*
G04 Layer:  MANUFACTURING/PHOTOPLOT_OUTLINE*
G04 Layer:  ETCH/IN3*
G04 Layer:  DRAWING FORMAT/TITLE_BLOCK*
G04 Layer:  DRAWING FORMAT/TITLE_DATA_IN3*
G04 *
G04 Offset:    (0.00 0.00)*
G04 Mirror:    No*
G04 Mode:      Positive*
G04 Rotation:  0*
G04 FullContactRelief:  No*
G04 UndefLineWidth:     6.00*
G04 ================== end FILE IDENTIFICATION RECORD ====================*
%FSLAX25Y25*MOIN*%
%IR0*IPPOS*OFA0.00000B0.00000*MIA0B0*SFA1.00000B1.00000*%
%ADD10C,.02*%
%ADD15C,.06*%
%ADD16C,.061*%
%ADD17C,.062*%
%ADD19C,.0315*%
%ADD11C,.018*%
%ADD13C,.03017*%
%ADD20C,.085*%
%ADD12C,.0193*%
%ADD18C,.06574*%
%ADD14C,.197*%
%ADD21C,.01*%
%ADD22C,.04*%
%ADD23C,.015*%
%ADD24C,.004*%
%ADD25C,.005*%
%ADD26C,.006*%
%ADD27C,.0051*%
%ADD28C,.0035*%
%ADD29C,.009*%
%ADD30C,.0072*%
%ADD31C,.0049*%
%ADD32C,.0058*%
%ADD33C,.00349*%
%ADD34C,.03004*%
%ADD46C,.02502*%
%ADD37C,.03006*%
%ADD49C,.03214*%
%ADD36C,.02602*%
%ADD38C,.07004*%
%ADD47C,.03234*%
%ADD43C,.07104*%
%ADD42C,.03018*%
%ADD40C,.07204*%
%ADD35C,.02804*%
%ADD45C,.02934*%
%ADD39C,.06804*%
%ADD48C,.03498*%
%ADD44C,.30104*%
%ADD41C,.1751*%
%ADD50C,.43376*%
G75*
%LPD*%
G75*
G36*
G01X2114Y70133D02*
X2470Y70329D01*
X2578Y70325D01*
X2625Y70295D01*
G03X3903Y69543I11157J17498D01*
G01X4006Y69370D01*
Y54252D01*
G03X7874Y50384I3868J0D01*
G01X43711D01*
G02X55590Y38504I-1J-11880D01*
G01Y15533D01*
X55515Y15385D01*
G03X54043Y12480I2131J-2905D01*
G03X55510Y9579I3602J0D01*
G01X55590Y9421D01*
Y4000D01*
X317654D01*
Y9415D01*
X317736Y9575D01*
G03Y15379I-2133J2902D01*
G01X317654Y15539D01*
Y38504D01*
G02X329535Y50384I11881J-1D01*
G01X362534D01*
G02X362710Y50186I-23J-198D01*
G01Y49212D01*
G03X362748Y48880I1451J-2D01*
G01Y48879D01*
G02X362710Y48709I-195J-46D01*
G01X362515Y48464D01*
G02X362358Y48388I-157J124D01*
G01X329535D01*
G03X319651Y38504I0J-9884D01*
G01Y5060D01*
X319660D01*
Y3937D01*
G02X317724Y2001I-1936J0D01*
G01X55520D01*
G02X53584Y3937I0J1936D01*
G01Y5060D01*
X53593D01*
Y38504D01*
G03X43709Y48388I-9884J0D01*
G01X7874D01*
G02X2010Y54252I0J5864D01*
G01Y69958D01*
G02X2114Y70133I200J0D01*
G37*
G36*
G01X6989Y313202D02*
G03X9884Y320190I-6988J6989D01*
G01Y1588078D01*
G02X11601Y1592224I5864J0D01*
G01X24705Y1605328D01*
G03X27601Y1612316I-6987J6990D01*
G01Y1732244D01*
G02X33465Y1738108I5864J0D01*
G01X765526D01*
G02X765726Y1737908I0J-200D01*
G01Y1736890D01*
G03X769705Y1732911I3979J0D01*
G01X1087854D01*
G03X1091833Y1736890I0J3979D01*
G01Y1737908D01*
G02X1092033Y1738108I200J0D01*
G01X1824016D01*
G02X1829880Y1732244I0J-5864D01*
G01Y1612316D01*
G03X1832775Y1605328I9883J1D01*
G01X1839974Y1598129D01*
G02X1841691Y1593983I-4147J-4146D01*
G01Y1316933D01*
X1841560Y1316802D01*
X1840220D01*
X1839694Y1317328D01*
Y1413131D01*
G02X1839705Y1413197I200J1D01*
G03X1840910Y1420330I-20497J7131D01*
G03X1839705Y1427463I-21702J2D01*
G02X1839694Y1427529I189J65D01*
G01Y1593984D01*
G03X1838562Y1596717I-3867J-1D01*
G01X1831363Y1603916D01*
G02X1827882Y1612316I8399J8402D01*
G01Y1732244D01*
G03X1824016Y1736110I-3866J0D01*
G01X1617787D01*
X1617756Y1736121D01*
G03X1617126Y1736222I-629J-1909D01*
G03X1616496Y1736121I-1J-2010D01*
G01X1616465Y1736110D01*
X1602039D01*
X1602008Y1736121D01*
G03X1601378Y1736222I-629J-1909D01*
G03X1600748Y1736121I-1J-2010D01*
G01X1600717Y1736110D01*
X1586291D01*
X1586260Y1736121D01*
G03X1585630Y1736222I-629J-1909D01*
G03X1585000Y1736121I-1J-2010D01*
G01X1584969Y1736110D01*
X1570543D01*
X1570512Y1736121D01*
G03X1569882Y1736222I-629J-1909D01*
G03X1569252Y1736121I-1J-2010D01*
G01X1569221Y1736110D01*
X1550858D01*
X1550827Y1736121D01*
G03X1550197Y1736222I-629J-1909D01*
G03X1549567Y1736121I-1J-2010D01*
G01X1549536Y1736110D01*
X1535110D01*
X1535079Y1736121D01*
G03X1534449Y1736222I-629J-1909D01*
G03X1533819Y1736121I-1J-2010D01*
G01X1533788Y1736110D01*
X1519362D01*
X1519331Y1736121D01*
G03X1518701Y1736222I-629J-1909D01*
G03X1518071Y1736121I-1J-2010D01*
G01X1518040Y1736110D01*
X1503614D01*
X1503583Y1736121D01*
G03X1502953Y1736222I-629J-1909D01*
G03X1502323Y1736121I-1J-2010D01*
G01X1502292Y1736110D01*
X1353614D01*
X1353583Y1736121D01*
G03X1352953Y1736222I-629J-1909D01*
G03X1352323Y1736121I-1J-2010D01*
G01X1352292Y1736110D01*
X1337866D01*
X1337835Y1736121D01*
G03X1337205Y1736222I-629J-1909D01*
G03X1336575Y1736121I-1J-2010D01*
G01X1336544Y1736110D01*
X1322118D01*
X1322087Y1736121D01*
G03X1321457Y1736222I-629J-1909D01*
G03X1320827Y1736121I-1J-2010D01*
G01X1320796Y1736110D01*
X1306370D01*
X1306339Y1736121D01*
G03X1305709Y1736222I-629J-1909D01*
G03X1305079Y1736121I-1J-2010D01*
G01X1305048Y1736110D01*
X1286685D01*
X1286654Y1736121D01*
G03X1286024Y1736222I-629J-1909D01*
G03X1285394Y1736121I-1J-2010D01*
G01X1285363Y1736110D01*
X1270937D01*
X1270906Y1736121D01*
G03X1270276Y1736222I-629J-1909D01*
G03X1269646Y1736121I-1J-2010D01*
G01X1269615Y1736110D01*
X1255189D01*
X1255158Y1736121D01*
G03X1254528Y1736222I-629J-1909D01*
G03X1253898Y1736121I-1J-2010D01*
G01X1253867Y1736110D01*
X1239441D01*
X1239410Y1736121D01*
G03X1238780Y1736222I-629J-1909D01*
G03X1238150Y1736121I-1J-2010D01*
G01X1238119Y1736110D01*
X1093780D01*
G02X1087854Y1730914I-5926J781D01*
G01X769705D01*
G02X763779Y1736110I0J5977D01*
G01X609913D01*
X609882Y1736121D01*
G03X609252Y1736222I-629J-1909D01*
G03X608622Y1736121I-1J-2010D01*
G01X608591Y1736110D01*
X594165D01*
X594134Y1736121D01*
G03X593504Y1736222I-629J-1909D01*
G03X592874Y1736121I-1J-2010D01*
G01X592843Y1736110D01*
X578417D01*
X578386Y1736121D01*
G03X577756Y1736222I-629J-1909D01*
G03X577126Y1736121I-1J-2010D01*
G01X577095Y1736110D01*
X562669D01*
X562638Y1736121D01*
G03X562008Y1736222I-629J-1909D01*
G03X561378Y1736121I-1J-2010D01*
G01X561347Y1736110D01*
X542984D01*
X542953Y1736121D01*
G03X542323Y1736222I-629J-1909D01*
G03X541693Y1736121I-1J-2010D01*
G01X541662Y1736110D01*
X527236D01*
X527205Y1736121D01*
G03X526575Y1736222I-629J-1909D01*
G03X525945Y1736121I-1J-2010D01*
G01X525914Y1736110D01*
X511488D01*
X511457Y1736121D01*
G03X510827Y1736222I-629J-1909D01*
G03X510197Y1736121I-1J-2010D01*
G01X510166Y1736110D01*
X495740D01*
X495709Y1736121D01*
G03X495079Y1736222I-629J-1909D01*
G03X494449Y1736121I-1J-2010D01*
G01X494418Y1736110D01*
X345740D01*
X345709Y1736121D01*
G03X345079Y1736222I-629J-1909D01*
G03X344449Y1736121I-1J-2010D01*
G01X344418Y1736110D01*
X329992D01*
X329961Y1736121D01*
G03X329331Y1736222I-629J-1909D01*
G03X328701Y1736121I-1J-2010D01*
G01X328670Y1736110D01*
X314244D01*
X314213Y1736121D01*
G03X313583Y1736222I-629J-1909D01*
G03X312953Y1736121I-1J-2010D01*
G01X312922Y1736110D01*
X298496D01*
X298465Y1736121D01*
G03X297835Y1736222I-629J-1909D01*
G03X297205Y1736121I-1J-2010D01*
G01X297174Y1736110D01*
X278811D01*
X278780Y1736121D01*
G03X278150Y1736222I-629J-1909D01*
G03X277520Y1736121I-1J-2010D01*
G01X277489Y1736110D01*
X263063D01*
X263032Y1736121D01*
G03X262402Y1736222I-629J-1909D01*
G03X261772Y1736121I-1J-2010D01*
G01X261741Y1736110D01*
X247315D01*
X247284Y1736121D01*
G03X246654Y1736222I-629J-1909D01*
G03X246024Y1736121I-1J-2010D01*
G01X245993Y1736110D01*
X231567D01*
X231536Y1736121D01*
G03X230906Y1736222I-629J-1909D01*
G03X230276Y1736121I-1J-2010D01*
G01X230245Y1736110D01*
X33465D01*
G03X29598Y1732244I0J-3867D01*
G01Y1612316D01*
G02X26117Y1603916I-11880J2D01*
G01X13013Y1590812D01*
G03X11882Y1588080I2736J-2733D01*
G01Y320190D01*
G02X8401Y311790I-11880J2D01*
G01X5139Y308528D01*
G03X4008Y305796I2736J-2733D01*
G01Y166318D01*
G02X3937Y166165I-200J0D01*
G03Y164021I902J-1072D01*
G02X4008Y163868I-129J-153D01*
G01Y162293D01*
G02X3937Y162140I-200J0D01*
G03Y159996I902J-1072D01*
G02X4008Y159843I-129J-153D01*
G01Y158141D01*
G02X3929Y157982I-200J0D01*
G03Y155594I910J-1194D01*
G02X4008Y155435I-121J-159D01*
G01Y153937D01*
G02X3937Y153784I-200J0D01*
G03Y151640I902J-1072D01*
G02X4008Y151487I-129J-153D01*
G01Y150041D01*
G02X3910Y149870I-200J1D01*
G03Y147290I770J-1290D01*
G02X4008Y147119I-102J-172D01*
G01Y145934D01*
G02X3910Y145763I-200J1D01*
G03Y143183I770J-1290D01*
G02X4008Y143012I-102J-172D01*
G01Y141682D01*
G02X3910Y141511I-200J1D01*
G03Y138931I770J-1290D01*
G02X4008Y138760I-102J-172D01*
G01Y106223D01*
G02X3903Y106047I-200J0D01*
G03X2625Y105295I9879J-18250D01*
G01X2578Y105265D01*
X2470Y105261D01*
X2114Y105457D01*
G02X2010Y105632I96J175D01*
G01Y305794D01*
G02X3727Y309940I5864J0D01*
G01X6989Y313202D01*
G37*
G36*
G01X23280Y399132D02*
X39180D01*
X40770Y397542D01*
Y396602D01*
G03Y394702I1162J-950D01*
G01Y393855D01*
G02X40149Y393521I-400J0D01*
G03X39320Y393771I-830J-1252D01*
G03Y390767I0J-1502D01*
G03X40149Y391017I-1J1502D01*
G02X40770Y390683I221J-334D01*
G01Y388803D01*
X40613Y388768D01*
G03Y385836I327J-1466D01*
G01X40770Y385801D01*
Y384692D01*
X38290Y382212D01*
X23730D01*
X21440Y384502D01*
Y397292D01*
X23280Y399132D01*
G37*
G36*
G01X406156Y930130D02*
X410189D01*
X411069Y929250D01*
Y926288D01*
G03Y924240I804J-1024D01*
G01Y923406D01*
G02X410495Y923046I-400J0D01*
G03X409929Y923176I-567J-1171D01*
G03Y920574I0J-1301D01*
G03X410495Y920704I-1J1301D01*
G02X411069Y920344I174J-360D01*
G01Y919760D01*
G03Y917580I710J-1090D01*
G01Y916997D01*
G02X410495Y916637I-400J0D01*
G03X409929Y916767I-567J-1171D01*
G03Y914165I0J-1301D01*
G03X410495Y914295I-1J1301D01*
G02X411069Y913935I174J-360D01*
G01Y913353D01*
G03X410477Y912262I709J-1091D01*
G03X410990Y911227I1301J0D01*
G01X411069Y911167D01*
Y911130D01*
X412493Y909706D01*
X412438Y909581D01*
G03X412328Y909058I1191J-524D01*
G01Y909057D01*
G03X412599Y908262I1302J0D01*
G01Y905240D01*
X410897Y903538D01*
X410756Y903653D01*
G03X409929Y903950I-827J-1003D01*
G03X408635Y902780I0J-1301D01*
G02X408237Y902420I-398J40D01*
G01X407921D01*
G02X407523Y902780I0J400D01*
G03X406229Y903950I-1294J-131D01*
G03X404930Y902721I0J-1301D01*
G02X404512Y902344I-399J23D01*
G03X404246I-133J-2899D01*
G02X403828Y902721I-19J400D01*
G03X402529Y903950I-1299J-72D01*
G03X401228Y902649I0J-1301D01*
G03X401817Y901560I1301J0D01*
G02X401935Y901010I-219J-335D01*
G03X401801Y900779I2441J-1570D01*
G02X401265Y900606I-355J184D01*
G03X400678Y900746I-587J-1161D01*
G03X399377Y899445I0J-1301D01*
G03X399966Y898356I1301J0D01*
G02X400084Y897806I-219J-335D01*
G03X399951Y897575I2447J-1563D01*
G02X399415Y897401I-356J183D01*
G03X398829Y897541I-587J-1161D01*
G03X397528Y896240I0J-1301D01*
G03X397915Y895315I1301J1D01*
G02X397916Y894747I-281J-284D01*
G01X397431Y894262D01*
X397319Y894292D01*
G03X396981Y894337I-339J-1256D01*
G01X396979D01*
G03X395678Y893036I0J-1301D01*
G03X396267Y891947I1301J0D01*
G02X396385Y891397I-219J-335D01*
G03X396252Y891166I2446J-1562D01*
G02X395716Y890993I-355J184D01*
G03X395129Y891133I-587J-1161D01*
G03X393828Y889832I0J-1301D01*
G03X394417Y888743I1301J0D01*
G02X394534Y888193I-219J-334D01*
G03X394401Y887961I2449J-1558D01*
G02X393865Y887788I-355J184D01*
G03X393278Y887928I-587J-1161D01*
G03X391977Y886627I0J-1301D01*
G03X392566Y885538I1301J0D01*
G02X392684Y884987I-219J-335D01*
G03X392552Y884757I2448J-1558D01*
G02X392016Y884584I-355J184D01*
G03X391429Y884724I-587J-1161D01*
G03X390128Y883423I0J-1301D01*
G03X391189Y882144I1301J0D01*
G01X391279Y882127D01*
X392081Y880737D01*
X392051Y880651D01*
G03X391977Y880219I1227J-433D01*
G03X392092Y879684I1302J0D01*
G01X392110Y879644D01*
Y878972D01*
X391455Y878317D01*
X391377Y878314D01*
G03X390255Y877576I51J-1300D01*
G01X390201Y877462D01*
X388957D01*
X388903Y877576D01*
G03X386555I-1174J-563D01*
G01X386501Y877462D01*
X385257D01*
X385203Y877576D01*
G03X384029Y878315I-1174J-563D01*
G03X382728Y877014I0J-1301D01*
G03X383111Y876093I1301J1D01*
G01X382130Y875112D01*
X382058Y875105D01*
G03X380883Y873930I120J-1295D01*
G01X380876Y873858D01*
X380460Y873442D01*
G02X379777Y873745I-283J282D01*
G03X379779Y873810I-1299J72D01*
G03X378478Y872509I-1301J0D01*
G03X378543Y872511I-7J1301D01*
G02X378846Y871828I21J-400D01*
G01X378310Y871292D01*
G02X377698Y871347I-283J283D01*
G03X376629Y871907I-1069J-740D01*
G03X375328Y870606I0J-1301D01*
G03X375888Y869537I1300J0D01*
G02X375943Y868925I-228J-329D01*
G01X375507Y868489D01*
X375377Y868556D01*
G03X374779Y868702I-599J-1155D01*
G03X373478Y867401I0J-1301D01*
G01Y867182D01*
X372379D01*
Y867401D01*
G03X371318Y868680I-1301J0D01*
G01X371228Y868697D01*
X370426Y870087D01*
X370456Y870174D01*
G03X370530Y870606I-1227J433D01*
G03X367928I-1301J0D01*
G03X368989Y869327I1301J0D01*
G01X369079Y869310D01*
X369881Y867920D01*
X369851Y867833D01*
G03X369777Y867401I1227J-433D01*
G01Y867182D01*
X368680D01*
Y867401D01*
G03X366078I-1301J0D01*
G01Y867182D01*
X364979D01*
Y867401D01*
G03X363918Y868680I-1301J0D01*
G01X363828Y868697D01*
X363026Y870087D01*
X363056Y870174D01*
G03X363130Y870606I-1227J433D01*
G03X360528I-1301J0D01*
G03X361589Y869327I1301J0D01*
G01X361679Y869310D01*
X362481Y867920D01*
X362451Y867833D01*
G03X362377Y867401I1227J-433D01*
G01Y867182D01*
X361280D01*
Y867401D01*
G03X358678I-1301J0D01*
G01Y867182D01*
X357579D01*
Y867401D01*
G03X356518Y868680I-1301J0D01*
G01X356428Y868697D01*
X355626Y870087D01*
X355656Y870174D01*
G03X355730Y870606I-1227J433D01*
G03X353128I-1301J0D01*
G03X354189Y869327I1301J0D01*
G01X354279Y869310D01*
X355081Y867920D01*
X355051Y867833D01*
G03X354977Y867401I1227J-433D01*
G01Y867182D01*
X353880D01*
Y867401D01*
G03X351278I-1301J0D01*
G01Y867182D01*
X350180D01*
Y867401D01*
G03X347578I-1301J0D01*
G01Y867182D01*
X343154D01*
X342920Y866948D01*
X342710Y867158D01*
X342721Y867254D01*
G03X342730Y867401I-1242J150D01*
G03X340228I-1251J0D01*
G03X341255Y866170I1251J0D01*
G02X341466Y865494I-72J-393D01*
G01X335627Y859655D01*
X335393Y858979D01*
X335323Y858943D01*
G03X334623Y857789I601J-1154D01*
G03X334738Y857254I1302J0D01*
G01X334771Y857181D01*
X332483Y850571D01*
X331590Y849677D01*
G03X331468Y849530I706J-710D01*
G01X331457Y849514D01*
X309192Y827248D01*
G03X309075Y827108I707J-710D01*
G01X309064Y827092D01*
X306427Y824455D01*
X281314Y767305D01*
X268060Y754052D01*
X265630D01*
G03X264922Y753758I1J-1002D01*
G01X259534Y748370D01*
X243772D01*
X238213Y742811D01*
X227853D01*
X215818Y730776D01*
X211494D01*
G02X211121Y731320I0J400D01*
G03X211222Y731861I-1401J541D01*
G01Y731862D01*
G03X209720Y733364I-1502J0D01*
G03X208535Y732785I0J-1502D01*
G02X207905I-315J246D01*
G03X206720Y733364I-1185J-923D01*
G03X205494Y732730I0J-1502D01*
G02X204851Y732717I-326J231D01*
G03X203660Y733304I-1191J-915D01*
G03X202158Y731802I0J-1502D01*
G03X202242Y731308I1502J1D01*
G02X201865Y730776I-378J-132D01*
G01X92068D01*
Y730987D01*
X92069Y730997D01*
G03X92076Y731131I-1244J132D01*
G01Y735205D01*
G03X91710Y736089I-1251J0D01*
G01X86034Y741765D01*
X86019Y741803D01*
G03X84623Y742751I-1396J-554D01*
G03X83121Y741249I0J-1502D01*
G03X84441Y739758I1502J0D01*
G01X84509Y739750D01*
X87831Y736428D01*
X87609Y736206D01*
X87498Y736235D01*
G03X87189Y736274I-310J-1213D01*
G01X83608D01*
Y736971D01*
X83638Y737019D01*
G03X83859Y737803I-1280J784D01*
G03X80855I-1502J0D01*
G03X81106Y736972I1501J0D01*
G01Y735661D01*
G03X81472Y734777I1251J0D01*
G01X82112Y734137D01*
G03X82997Y733770I886J885D01*
G01X86671D01*
X87058Y733383D01*
Y733349D01*
X84485Y730776D01*
X65862D01*
Y731992D01*
X67085Y733215D01*
G03X67452Y734100I-885J886D01*
G01Y737030D01*
G03X67085Y737915I-1252J-1D01*
G01X65404Y739596D01*
X65390Y739651D01*
G03X63930Y740802I-1460J-350D01*
G03X62428Y739300I0J-1502D01*
G03X63579Y737840I1501J0D01*
G01X63634Y737826D01*
X64948Y736512D01*
Y734618D01*
X63725Y733395D01*
G03X63358Y732510I885J-886D01*
G01Y727434D01*
X52676Y716751D01*
Y658655D01*
X45982Y651961D01*
X45872Y651990D01*
G03X40708Y652642I-5161J-20100D01*
G03X34030Y651539I-2J-20752D01*
G01X33999Y651528D01*
X32158D01*
X30700Y650070D01*
X30675Y650056D01*
G03X19956Y631890I10034J-18166D01*
G01Y631888D01*
G03X24168Y619356I20752J1D01*
G01Y523891D01*
X92049Y456010D01*
X182198D01*
X196880Y470692D01*
X206668D01*
X211117Y466243D01*
Y463759D01*
G02X210478Y463438I-400J0D01*
G03X209579Y463737I-899J-1202D01*
G03Y460733I0J-1502D01*
G03X210478Y461032I0J1501D01*
G02X211117Y460711I239J-321D01*
G01Y458746D01*
G02X210478Y458425I-400J0D01*
G03X209579Y458724I-899J-1202D01*
G03Y455720I0J-1502D01*
G03X210478Y456019I0J1501D01*
G02X211117Y455698I239J-321D01*
G01Y439103D01*
X202664Y430650D01*
Y415523D01*
X199327Y412186D01*
X196555D01*
X196523Y412347D01*
G03X195050Y413557I-1473J-292D01*
G03X193970Y413099I0J-1502D01*
G02X193375Y413122I-287J278D01*
G03X192220Y413664I-1155J-960D01*
G03X190731Y412360I0J-1502D01*
G01X190708Y412186D01*
X148162D01*
X139041Y421307D01*
X133329D01*
G03X132490Y421564I-840J-1245D01*
G03X131651Y421307I1J-1502D01*
G01X113681D01*
X98109Y405735D01*
Y361466D01*
X91436Y354793D01*
X48835D01*
X47056Y356572D01*
Y359368D01*
X47206Y359407D01*
G03X48336Y360862I-372J1455D01*
G03X47949Y361868I-1501J0D01*
G01X47822Y362009D01*
X49615Y363802D01*
X70303D01*
X74863Y368362D01*
Y413854D01*
X64389Y424328D01*
X26328D01*
X13585Y437071D01*
Y657574D01*
X24986Y668975D01*
G02X25552I283J-283D01*
G03X26615Y668534I1063J1061D01*
G03X28117Y670036I0J1502D01*
G03X27676Y671099I-1502J0D01*
G02Y671665I283J283D01*
G01X31943Y675932D01*
X36910D01*
X40365Y679387D01*
Y703089D01*
X29783Y713671D01*
Y751288D01*
X35364Y756869D01*
Y768458D01*
G02X35905Y768832I400J0D01*
G03X36399Y768742I494J1311D01*
G03Y771546I0J1402D01*
G03X35411Y771139I0J-1403D01*
G02X34846Y771140I-282J284D01*
G01X33648Y772338D01*
Y778870D01*
X37085Y782307D01*
X37107Y782320D01*
G03X37609Y782822I-708J1210D01*
G01X37622Y782844D01*
X40040Y785262D01*
X56186D01*
G02X56455Y784566I0J-400D01*
G03X55997Y783530I943J-1036D01*
G03X58801I1402J0D01*
G03X58343Y784566I-1401J0D01*
G02X58612Y785262I269J296D01*
G01X64886D01*
G02X65155Y784566I0J-400D01*
G03X64697Y783530I943J-1036D01*
G03X67501I1402J0D01*
G03X67043Y784566I-1401J0D01*
G02X67312Y785262I269J296D01*
G01X81028D01*
G02X81297Y784566I0J-400D01*
G03X80839Y783530I943J-1036D01*
G03X83643I1402J0D01*
G03X83185Y784566I-1401J0D01*
G02X83454Y785262I269J296D01*
G01X85886D01*
G02X86155Y784566I0J-400D01*
G03X85697Y783530I943J-1036D01*
G03X88501I1402J0D01*
G03X88043Y784566I-1401J0D01*
G02X88312Y785262I269J296D01*
G01X94586D01*
G02X94855Y784566I0J-400D01*
G03X94397Y783530I943J-1036D01*
G03X97201I1402J0D01*
G03X96743Y784566I-1401J0D01*
G02X97012Y785262I269J296D01*
G01X101820D01*
X111613Y775469D01*
G02X111466Y774810I-283J-283D01*
G03X110539Y773491I475J-1319D01*
G03X111941Y772089I1402J0D01*
G03X113260Y773016I0J1402D01*
G02X113919Y773163I376J-136D01*
G01X115871Y771211D01*
X115747Y771070D01*
G03X115397Y770144I1052J-927D01*
G03X116799Y768742I1402J0D01*
G03X117725Y769092I-1J1402D01*
G01X117866Y769216D01*
X131732Y755350D01*
X191404D01*
X191417Y755348D01*
G03X191602Y755337I181J1491D01*
G03X191787Y755348I4J1502D01*
G01X191800Y755350D01*
X195404D01*
X195417Y755348D01*
G03X195602Y755337I181J1491D01*
G03X195787Y755348I4J1502D01*
G01X195800Y755350D01*
X219878D01*
X219888Y755349D01*
G03X220033Y755342I145J1495D01*
G03X220178Y755349I0J1502D01*
G01X220188Y755350D01*
X232369D01*
X233195Y756177D01*
X237249D01*
X252647Y771575D01*
X262487D01*
X288228Y797316D01*
X299287Y824925D01*
X330657Y855795D01*
X332512Y864330D01*
X340884Y872702D01*
X341007Y872652D01*
G03X341479Y872559I473J1158D01*
G03X342730Y873810I0J1251D01*
G03X342637Y874282I-1251J-1D01*
G01X342587Y874405D01*
X344037Y875855D01*
X346436D01*
X346477Y875836D01*
G03X347581I552J1177D01*
G01X347622Y875855D01*
X348817D01*
X349153Y876191D01*
G02X349740Y876169I283J-282D01*
G03X350729Y875713I989J845D01*
G03X352030Y877014I0J1301D01*
G03X351641Y877942I-1301J0D01*
G02X351620Y878203I140J143D01*
G03X351994Y878853I-2744J2012D01*
G02X352231Y878965I183J-81D01*
G03X352576Y878918I347J1254D01*
G01X352579D01*
G03X353855Y879964I0J1301D01*
G01X353887Y880125D01*
X354970D01*
X355002Y879964D01*
G03X356278Y878918I1276J255D01*
G03X357538Y879893I0J1302D01*
G02X357753Y880042I194J-50D01*
G03X358504I375J3381D01*
G02X358719Y879893I21J-199D01*
G03X359979Y878918I1260J327D01*
G03X361255Y879964I0J1301D01*
G01X361287Y880125D01*
X362370D01*
X362402Y879964D01*
G03X363678Y878918I1276J255D01*
G03X364938Y879893I0J1302D01*
G02X365153Y880042I194J-50D01*
G03X365904I375J3381D01*
G02X366119Y879893I21J-199D01*
G03X367379Y878918I1260J327D01*
G03X368680Y880219I0J1301D01*
G01Y880222D01*
G03X368592Y880691I-1301J-1D01*
G01X368544Y880812D01*
X368996Y881264D01*
G02X369625Y881181I283J-283D01*
G01X369881Y880737D01*
X369851Y880651D01*
G03X369777Y880219I1227J-433D01*
G03X372379I1301J0D01*
G03X371318Y881498I-1301J0D01*
G01X371227Y881515D01*
X370426Y882904D01*
X370456Y882991D01*
G03X370530Y883423I-1227J433D01*
G03X370359Y884068I-1302J0D01*
G01X370283Y884201D01*
X371467Y885385D01*
X371509Y885400D01*
G03X372305Y886196I-431J1227D01*
G01X372320Y886238D01*
X372514Y886432D01*
X372800D01*
X372804Y886431D01*
G03X373055I126J3401D01*
G01X373059Y886432D01*
X373483D01*
X373523Y886284D01*
G03X373551Y886195I1254J346D01*
G01X373581Y886108D01*
X372779Y884719D01*
X372689Y884702D01*
G03X371628Y883423I240J-1279D01*
G03X374230I1301J0D01*
G03X374156Y883855I-1301J-1D01*
G01X374126Y883942D01*
X374928Y885331D01*
X375018Y885348D01*
G03X376079Y886627I-240J1279D01*
G03X375702Y887543I-1301J0D01*
G01X375595Y887651D01*
X375803Y888012D01*
X375805Y888016D01*
G03X375878Y888136I-2869J1828D01*
G01X375891Y888159D01*
X376301Y888569D01*
X376403Y888551D01*
G03X376629Y888531I227J1281D01*
G03X377629Y889000I0J1301D01*
G01X379329D01*
G03X380329Y888531I1000J832D01*
G03X381596Y889536I0J1301D01*
G01X381609Y889592D01*
X382047Y890030D01*
G02X382730Y889767I283J-282D01*
G03X384029Y888531I1299J65D01*
G03X385330Y889832I0J1301D01*
G03X384094Y891131I-1301J0D01*
G02X383831Y891814I19J400D01*
G01X384233Y892216D01*
G03X385217Y891915I1646J3621D01*
G03X385877Y891735I660J1121D01*
G01X385878D01*
G03X387179Y893036I0J1301D01*
G03X386693Y894050I-1301J0D01*
G02X386661Y894644I251J311D01*
G01X387107Y895090D01*
X387230Y895038D01*
G03X387727Y894939I498J1202D01*
G01X387729D01*
G03X389030Y896240I0J1301D01*
G03X388739Y897060I-1301J0D01*
G01Y897802D01*
G02X389242Y898188I400J0D01*
G03X389577Y898144I335J1257D01*
G01X389578D01*
G03Y900746I0J1301D01*
G03X389024Y900622I0J-1301D01*
G01X388984Y900603D01*
X388739D01*
Y900960D01*
X389746Y901967D01*
G02X390358Y901911I283J-283D01*
G03X391429Y901348I1071J737D01*
G03X392730Y902649I0J1301D01*
G03X392167Y903720I-1300J0D01*
G02X392111Y904332I227J329D01*
G01X392546Y904767D01*
X392676Y904699D01*
G03X393276Y904552I601J1154D01*
G01X393278D01*
G03X394579Y905853I0J1301D01*
G01Y905855D01*
G03X394432Y906455I-1301J-1D01*
G01X394364Y906585D01*
X394909Y907130D01*
X395521D01*
G02X395863Y906524I-1J-400D01*
G03X395677Y905854I1115J-670D01*
G01Y905853D01*
G03X398279I1301J0D01*
G01Y905854D01*
G03X398093Y906524I-1301J0D01*
G02X398435Y907130I343J206D01*
G01X398659D01*
X399434Y907905D01*
X399458Y907918D01*
G03X400130Y909057I-629J1139D01*
G03X399869Y909839I-1302J0D01*
G01Y910611D01*
G02X400365Y910999I400J0D01*
G03X400676Y910961I312J1263D01*
G01X400678D01*
G03Y913563I0J1301D01*
G01X400676D01*
G03X400365Y913525I1J-1301D01*
G02X399869Y913913I-96J388D01*
G01Y921095D01*
G03X400129Y921875I-1040J780D01*
G03X399869Y922655I-1300J0D01*
G01Y923428D01*
G02X400365Y923816I400J0D01*
G03X400676Y923778I312J1263D01*
G01X400678D01*
G03X401979Y925079I0J1301D01*
G01Y925080D01*
G03X401661Y925932I-1301J0D01*
G01X402724Y926995D01*
X402784Y927007D01*
G03X403805Y928028I-255J1276D01*
G01X403817Y928088D01*
X405255Y929526D01*
X405314Y929538D01*
G03X406156Y930130I-266J1274D01*
G37*
G36*
G01X27115Y670036D02*
G03I-500J0D01*
G37*
G36*
G01X38720Y595862D02*
G03I-500J0D01*
G37*
G36*
G01X39960Y1675830D02*
X62240D01*
X80490Y1657580D01*
Y1613819D01*
X80479Y1613787D01*
G03X80398Y1613300I1421J-487D01*
G03X80479Y1612813I1502J0D01*
G01X80490Y1612781D01*
Y1608250D01*
X85900Y1602840D01*
X103080D01*
G03X105556I1238J849D01*
G01X126250D01*
X144810Y1584280D01*
X157490D01*
X163370Y1578400D01*
Y1566340D01*
X169400Y1560310D01*
X191520D01*
X198160Y1553670D01*
Y1537890D01*
X187640Y1527370D01*
X99932D01*
X99893Y1527388D01*
G03X99274Y1527521I-618J-1369D01*
G03X98655Y1527388I-1J-1502D01*
G01X98616Y1527370D01*
X77380D01*
X65780Y1515770D01*
X53110D01*
X34860Y1534020D01*
Y1670730D01*
X39960Y1675830D01*
G37*
G36*
G01X77150Y703012D02*
G02X76509Y703331I-241J319D01*
G01Y712998D01*
X80159Y716648D01*
X80194Y716663D01*
G03X80921Y717390I-559J1286D01*
G01X80936Y717425D01*
X84359Y720848D01*
X84484Y720792D01*
G03X85095Y720662I611J1371D01*
G03X86597Y722164I0J1502D01*
G03X86467Y722775I-1501J0D01*
G01X86411Y722900D01*
X89178Y725667D01*
X104780D01*
G02X105062Y724984I-1J-400D01*
G01X97487Y717409D01*
G02X96924Y717407I-283J283D01*
G03X95849Y717860I-1075J-1049D01*
G03X94347Y716358I0J-1502D01*
G03X94801Y715282I1502J0D01*
G02X94798Y714720I-286J-279D01*
G01X87970Y707892D01*
Y697580D01*
X91740Y693810D01*
Y691420D01*
X92790Y690370D01*
X99180D01*
X99908Y691098D01*
X100939D01*
G03X102059Y690597I1120J1002D01*
G01X102060D01*
G03Y693603I0J1503D01*
G01X102059D01*
G03X100939Y693102I0J-1503D01*
G01X98995D01*
X92056Y700040D01*
Y705739D01*
X111984Y725667D01*
X129131D01*
X131535Y723263D01*
Y690241D01*
X135456Y686320D01*
X171615D01*
X188840Y703545D01*
X231241D01*
X233706Y701080D01*
Y666229D01*
X233543Y666198D01*
G03Y663442I260J-1378D01*
G01X233706Y663411D01*
Y632229D01*
X233543Y632198D01*
G03X232401Y630820I260J-1378D01*
G03X232841Y629800I1402J0D01*
G02Y629240I-286J-280D01*
G03X232401Y628220I962J-1020D01*
G03X233543Y626842I1402J0D01*
G01X233706Y626811D01*
Y598229D01*
X233543Y598198D01*
G03X232401Y596820I260J-1378D01*
G03X232841Y595800I1402J0D01*
G02Y595240I-286J-280D01*
G03X232401Y594220I962J-1020D01*
G03X233543Y592842I1402J0D01*
G01X233706Y592811D01*
Y564256D01*
X200848Y531398D01*
X167400D01*
X162300Y526298D01*
Y525384D01*
X153256D01*
G03X152018Y524871I0J-1750D01*
G01X148266Y521119D01*
G03X147752Y519881I1237J-1239D01*
G01Y519864D01*
G03X147862Y519268I1751J15D01*
G01X147863Y519266D01*
G03X148889Y518241I1640J615D01*
G03X149501Y518130I614J1640D01*
G01X149504D01*
G03X150742Y518643I0J1750D01*
G01X152707Y520607D01*
X152747Y520647D01*
G02X153330Y520628I283J-283D01*
G03X154645Y520032I1316J1155D01*
G01X161147D01*
G02X161430Y519349I0J-400D01*
G01X161378Y519297D01*
X158762Y516680D01*
G03X158248Y515442I1237J-1239D01*
G01Y510052D01*
G03X161752I1752J0D01*
G01Y511105D01*
G02X161999Y511299I200J0D01*
G01X162046Y511288D01*
X162070Y511275D01*
G03X162207Y511209I676J1229D01*
G01X162300Y511168D01*
Y504936D01*
G02X161780Y504555I-400J1D01*
G03X161301Y504645I-513J-1412D01*
G01X161255D01*
G03Y501641I12J-1502D01*
G01X161269D01*
G03X161780Y501731I-1J1502D01*
G02X162300Y501350I120J-382D01*
G01Y497210D01*
X160251Y490913D01*
X148100Y478762D01*
X139610D01*
G02X139273Y479375I1J400D01*
G01X139292Y479404D01*
X139303Y479421D01*
X139322Y479451D01*
G03X139544Y480231I-1280J786D01*
G01Y480259D01*
G03X136540I-1502J-21D01*
G01Y480236D01*
G03X136803Y479388I1502J1D01*
G02X136474Y478762I-330J-226D01*
G01X134401D01*
G02X134064Y479375I1J400D01*
G01X134083Y479404D01*
X134094Y479421D01*
X134113Y479451D01*
G03X134335Y480231I-1280J786D01*
G01Y480259D01*
G03X131331I-1502J-21D01*
G01Y480236D01*
G03X131594Y479388I1502J1D01*
G02X131265Y478762I-330J-226D01*
G01X124741D01*
X121206Y482297D01*
G03X120321Y482664I-886J-885D01*
G01X106703D01*
X76509Y512857D01*
Y697840D01*
X76666Y697875D01*
G03X77767Y699244I-301J1369D01*
G03X77656Y699791I-1403J0D01*
G02X78041Y700330I375J139D01*
G01X78080D01*
G03Y703334I0J1502D01*
G01X78050D01*
G03X77150Y703012I30J-1502D01*
G37*
G36*
G01X414547Y932365D02*
X428647D01*
G02X429030Y931853I-1J-400D01*
G03X428978Y931487I1249J-364D01*
G03X430279Y930186I1301J0D01*
G03X431555Y931236I0J1300D01*
G02X432231Y931441I393J-77D01*
G01X432881Y930791D01*
G03X432887Y930781I1118J664D01*
G01Y929946D01*
G02X432403Y929555I-400J0D01*
G03X432130Y929584I-273J-1272D01*
G03Y926982I0J-1301D01*
G03X432403Y927011I0J1301D01*
G02X432887Y926620I84J-391D01*
G01Y925785D01*
G03X432679Y925079I1094J-706D01*
G03X433980Y923778I1301J0D01*
G03X434323Y923824I0J1302D01*
G01X434435Y923854D01*
X434919Y923370D01*
G02X434916Y922802I-283J-283D01*
G03X434528Y921875I913J-927D01*
G03X435829Y920574I1301J0D01*
G03X436296Y920661I-1J1301D01*
G02X436839Y920287I143J-374D01*
G01Y919664D01*
G03Y917676I838J-994D01*
G01Y917054D01*
G02X436296Y916680I-400J0D01*
G03X435829Y916767I-468J-1214D01*
G03Y914165I0J-1301D01*
G03X436296Y914252I-1J1301D01*
G02X436839Y913878I143J-374D01*
G01Y913256D01*
G03Y911268I838J-994D01*
G01Y910645D01*
G02X436296Y910271I-400J0D01*
G03X435829Y910358I-468J-1214D01*
G03Y907756I0J-1301D01*
G03X436296Y907843I-1J1301D01*
G02X436839Y907469I143J-374D01*
G01Y906846D01*
G03Y904860I839J-993D01*
G01Y904237D01*
G02X436296Y903863I-400J0D01*
G03X435829Y903950I-468J-1214D01*
G03Y901348I0J-1301D01*
G03X436296Y901435I-1J1301D01*
G02X436839Y901061I143J-374D01*
G01Y900438D01*
G03Y898452I839J-993D01*
G01Y897828D01*
G02X436296Y897454I-400J0D01*
G03X435829Y897541I-468J-1214D01*
G03Y894939I0J-1301D01*
G03X436296Y895026I-1J1301D01*
G02X436839Y894652I143J-374D01*
G01Y894030D01*
G03Y892042I838J-994D01*
G01Y891420D01*
G02X436296Y891046I-400J0D01*
G03X435829Y891133I-468J-1214D01*
G03Y888531I0J-1301D01*
G03X436296Y888618I-1J1301D01*
G02X436839Y888244I143J-374D01*
G01Y887621D01*
G03Y885633I838J-994D01*
G01Y885011D01*
G02X436296Y884637I-400J0D01*
G03X435829Y884724I-468J-1214D01*
G03X434528Y883423I0J-1301D01*
G03X435589Y882144I1301J0D01*
G01X435679Y882127D01*
X436481Y880737D01*
X436451Y880651D01*
G03X436377Y880219I1227J-433D01*
G03X436839Y879225I1300J0D01*
G01Y878602D01*
G02X436296Y878228I-400J0D01*
G03X435829Y878315I-468J-1214D01*
G03X434528Y877014I0J-1301D01*
G03X434782Y876241I1301J-1D01*
G02X434461Y875604I-322J-237D01*
G01X433497D01*
G02X433176Y876241I1J400D01*
G03X433430Y877014I-1047J772D01*
G03X430828I-1301J0D01*
G03X431082Y876241I1301J-1D01*
G02X430761Y875604I-322J-237D01*
G01X429797D01*
G02X429476Y876241I1J400D01*
G03X429730Y877014I-1047J772D01*
G03X427128I-1301J0D01*
G03X427382Y876241I1301J-1D01*
G02X427061Y875604I-322J-237D01*
G01X426097D01*
G02X425776Y876241I1J400D01*
G03X426030Y877014I-1047J772D01*
G03X423428I-1301J0D01*
G03X423682Y876241I1301J-1D01*
G02X423361Y875604I-322J-237D01*
G01X422397D01*
G02X422076Y876241I1J400D01*
G03X422330Y877014I-1047J772D01*
G03X419728I-1301J0D01*
G03X419982Y876241I1301J-1D01*
G02X419661Y875604I-322J-237D01*
G01X418697D01*
G02X418376Y876241I1J400D01*
G03X418630Y877014I-1047J772D01*
G03X416028I-1301J0D01*
G03X416282Y876241I1301J-1D01*
G02X415961Y875604I-322J-237D01*
G01X414997D01*
G02X414676Y876241I1J400D01*
G03X414930Y877014I-1047J772D01*
G03X412328I-1301J0D01*
G03X412582Y876241I1301J-1D01*
G02X412261Y875604I-322J-237D01*
G01X411045D01*
X409828Y874387D01*
G02X409200Y874468I-283J283D01*
G03X408078Y875111I-1122J-657D01*
G03X406777Y873810I0J-1301D01*
G03X407420Y872688I1300J0D01*
G02X407501Y872060I-202J-345D01*
G01X407060Y871619D01*
X406925Y871705D01*
G03X406229Y871907I-696J-1098D01*
G03X404928Y870606I0J-1301D01*
G03X405223Y869782I1301J1D01*
G01X404118Y868677D01*
X404064Y868663D01*
G03X403117Y867716I315J-1262D01*
G01X403103Y867662D01*
X402659Y867218D01*
G02X401977Y867477I-283J283D01*
G03X400918Y868680I-1299J-76D01*
G01X400828Y868697D01*
X400026Y870087D01*
X400056Y870174D01*
G03X400130Y870606I-1227J433D01*
G03X397528I-1301J0D01*
G03X398589Y869327I1301J0D01*
G01X398679Y869310D01*
X399481Y867920D01*
X399451Y867833D01*
G03X399377Y867401I1227J-433D01*
G03X400602Y866102I1301J0D01*
G02X400861Y865420I-24J-399D01*
G01X400423Y864982D01*
X399867D01*
G03X398829Y865498I-1038J-786D01*
G03X397528Y864197I0J-1301D01*
G03X398300Y863008I1302J0D01*
G01X398418Y862956D01*
Y862339D01*
G02X397774Y862022I-400J0D01*
G03X396978Y862294I-796J-1029D01*
G03X395677Y860993I0J-1301D01*
G03X395751Y860561I1301J1D01*
G01X395781Y860474D01*
X394979Y859085D01*
X394889Y859068D01*
G03X393828Y857789I240J-1279D01*
G03X396430I1301J0D01*
G03X396356Y858221I-1301J-1D01*
G01X396326Y858308D01*
X397128Y859697D01*
X397218Y859714D01*
G03X397774Y859964I-241J1279D01*
G02X398418Y859647I244J-317D01*
G01Y859030D01*
X398300Y858978D01*
G03Y856600I530J-1189D01*
G01X398418Y856548D01*
Y855930D01*
G02X397774Y855614I-400J0D01*
G03X396979Y855885I-795J-1031D01*
G03Y853283I0J-1301D01*
G03X397774Y853554I0J1302D01*
G02X398418Y853238I244J-316D01*
G01Y852621D01*
X398300Y852569D01*
G03X397542Y851571I529J-1189D01*
G01X397517Y851400D01*
X396441D01*
X396416Y851571D01*
G03X393842I-1287J-191D01*
G01X393817Y851400D01*
X392741D01*
X392716Y851571D01*
G03X390142I-1287J-191D01*
G01X390117Y851400D01*
X389041D01*
X389016Y851571D01*
G03X386442I-1287J-191D01*
G01X386417Y851400D01*
X385341D01*
X385316Y851571D01*
G03X382742I-1287J-191D01*
G01X382717Y851400D01*
X381641D01*
X381616Y851571D01*
G03X379042I-1287J-191D01*
G01X379017Y851400D01*
X377941D01*
X377916Y851571D01*
G03X375342I-1287J-191D01*
G01X375317Y851400D01*
X374241D01*
X374216Y851571D01*
G03X371642I-1287J-191D01*
G01X371617Y851400D01*
X370541D01*
X370516Y851571D01*
G03X367942I-1287J-191D01*
G01X367917Y851400D01*
X366841D01*
X366816Y851571D01*
G03X364242I-1287J-191D01*
G01X364217Y851400D01*
X363141D01*
X363116Y851571D01*
G03X360542I-1287J-191D01*
G01X360517Y851400D01*
X359441D01*
X359416Y851571D01*
G03X356842I-1287J-191D01*
G01X356817Y851400D01*
X355741D01*
X355716Y851571D01*
G03X354429Y852681I-1287J-191D01*
G03X353892Y852565I0J-1301D01*
G02X353372Y852746I-165J364D01*
G03X353233Y852986I-2643J-1370D01*
G02X353337Y853527I337J216D01*
G03X353880Y854584I-757J1057D01*
G03X352579Y855885I-1301J0D01*
G03X351284Y854713I0J-1301D01*
G02X350868Y854353I-398J39D01*
G03X350727Y854356I-134J-2973D01*
G03X350589Y854353I-4J-2976D01*
G02X350173Y854713I-18J400D01*
G03X348878Y855885I-1295J-129D01*
G03X347577Y854584I0J-1301D01*
G03X348118Y853528I1301J0D01*
G02X348222Y852987I-233J-325D01*
G03X348149Y852868I2500J-1615D01*
G01X348070Y852732D01*
G02X347560Y852567I-346J200D01*
G03X347027Y852681I-533J-1187D01*
G03X345726Y851380I0J-1301D01*
G03X346266Y850325I1301J0D01*
G02X346379Y849800I-234J-325D01*
G01X346300Y849664D01*
G03X346234Y849542I2584J-1477D01*
G02X345714Y849362I-355J184D01*
G03X345178Y849477I-535J-1186D01*
G03Y846875I0J-1301D01*
G03X345296Y846880I4J1301D01*
G02X345718Y846374I37J-398D01*
G03X345526Y845102I5008J-1406D01*
G01Y845027D01*
G03X345527Y844921I2976J-25D01*
G01X345528Y844918D01*
Y842331D01*
G03X346399Y840226I2976J-1D01*
G01X346656Y839970D01*
X346632Y839863D01*
G03X346562Y839219I2906J-642D01*
G01Y838169D01*
G03X346706Y837253I2976J-1D01*
G03X346562Y836337I2832J-915D01*
G01Y835287D01*
G03X346875Y833957I2976J-1D01*
G03X346837Y833850I2894J-1088D01*
G01X346822Y833806D01*
X335204Y822188D01*
G03X334586Y821305I2185J-2187D01*
G01X332406Y816613D01*
G03X332120Y815409I2804J-1302D01*
G01X331970Y810727D01*
G03X331968Y810628I3090J-112D01*
G03X332018Y810076I3092J2D01*
G01X333166Y803747D01*
G03X333843Y802308I3042J552D01*
G01X347897Y785607D01*
Y756870D01*
X347733Y756840D01*
G03Y753884I267J-1478D01*
G01X347897Y753854D01*
Y752185D01*
X329040Y733328D01*
G02X328410Y733412I-283J283D01*
G03X327821Y733986I-1303J-747D01*
G02X327819Y734689I190J352D01*
G03X328598Y736005I-722J1316D01*
G03X325594I-1502J0D01*
G03X326382Y734684I1501J0D01*
G02X326384Y733981I-190J-352D01*
G03X325605Y732665I722J-1316D01*
G03X326360Y731362I1502J0D01*
G02X326444Y730732I-199J-347D01*
G01X310875Y715163D01*
X300168D01*
G02X299769Y715529I0J400D01*
G03X296777I-1496J-129D01*
G02X296378Y715163I-399J34D01*
G01X286134D01*
G02X285746Y715658I0J400D01*
G03X285789Y716015I-1459J357D01*
G03X282785I-1502J0D01*
G03X282828Y715658I1502J0D01*
G02X282440Y715163I-388J-95D01*
G01X271488D01*
G02X271091Y715611I0J400D01*
G03X271102Y715792I-1491J181D01*
G03X268098I-1502J0D01*
G03X268109Y715611I1502J0D01*
G02X267712Y715163I-397J-48D01*
G01X244019D01*
G02X243691Y715792I0J400D01*
G03X243962Y716652I-1231J861D01*
G03X240958I-1502J0D01*
G03X241229Y715792I1502J1D01*
G02X240901Y715163I-328J-229D01*
G01X240422D01*
X230309Y705050D01*
X204206D01*
G03X200735Y705971I-3471J-6080D01*
G03X199485Y705859I-3J-7002D01*
G03X198235Y705971I-1247J-6890D01*
G03X194809Y705076I-1J-7002D01*
G01X194763Y705050D01*
X191313D01*
X191293Y705228D01*
G03X188307I-1493J-166D01*
G01X188287Y705050D01*
X187126D01*
X171052Y688976D01*
X151408D01*
G02X151144Y689677I0J400D01*
G03X151657Y690807I-988J1130D01*
G03X150155Y692309I-1502J0D01*
G03X149081Y691857I0J-1502D01*
G02X148509I-286J280D01*
G03X147435Y692309I-1074J-1050D01*
G03X145933Y690807I0J-1502D01*
G03X146446Y689677I1501J0D01*
G02X146182Y688976I-264J-301D01*
G01X138618D01*
X136341Y691253D01*
Y722499D01*
X137859Y724017D01*
X220981D01*
X230863Y733899D01*
X257911D01*
X269688Y745676D01*
G02X270307Y745609I282J-283D01*
G03X271570Y744920I1263J813D01*
G03X272706Y745440I0J1501D01*
G02X273274Y745478I303J-262D01*
G03X274270Y745100I996J1123D01*
G03X275403Y745616I0J1502D01*
G02X275987Y745637I302J-263D01*
G03X277046Y745200I1059J1065D01*
G03Y748204I0J1502D01*
G03X275913Y747688I0J-1502D01*
G02X275329Y747667I-302J263D01*
G03X274270Y748104I-1059J-1065D01*
G03X273134Y747584I0J-1501D01*
G02X272566Y747546I-303J262D01*
G03X272383Y747685I-997J-1123D01*
G02X272316Y748304I216J337D01*
G01X290887Y766875D01*
X313407Y825425D01*
X315947Y828035D01*
X336907Y848995D01*
G02X337180Y849003I141J-142D01*
G03X338042Y848677I861J975D01*
G03Y851279I0J1301D01*
G03X337992Y851278I1J-1301D01*
G02X337577Y851678I-15J400D01*
G01Y853283D01*
X337778D01*
G03X339079Y854584I0J1301D01*
G03X338599Y855593I-1301J0D01*
G02X338568Y856186I252J310D01*
G01X339016Y856634D01*
X339138Y856584D01*
G03X339628Y856488I490J1205D01*
G03X340929Y857789I0J1301D01*
G03X340131Y858989I-1301J0D01*
G02X340003Y859641I154J369D01*
G01X344294Y863932D01*
X345747D01*
X345792Y863794D01*
G03X348266I1237J403D01*
G01X348311Y863932D01*
X349447D01*
X349492Y863794D01*
G03X351966I1237J403D01*
G01X352011Y863932D01*
X353147D01*
X353192Y863794D01*
G03X355666I1237J403D01*
G01X355711Y863932D01*
X356847D01*
X356892Y863794D01*
G03X359366I1237J403D01*
G01X359411Y863932D01*
X360547D01*
X360592Y863794D01*
G03X363066I1237J403D01*
G01X363111Y863932D01*
X364247D01*
X364292Y863794D01*
G03X366766I1237J403D01*
G01X366811Y863932D01*
X367947D01*
X367992Y863794D01*
G03X370466I1237J403D01*
G01X370511Y863932D01*
X371647D01*
X371692Y863794D01*
G03X374166I1237J403D01*
G01X374211Y863932D01*
X375347D01*
X375392Y863794D01*
G03X377866I1237J403D01*
G01X377911Y863932D01*
X379047D01*
X379092Y863794D01*
G03X380329Y862896I1237J403D01*
G03X381630Y864197I0J1301D01*
G03X381128Y865224I-1302J0D01*
G02X381090Y865822I245J316D01*
G01X381532Y866264D01*
X381657Y866209D01*
G03X382179Y866100I521J1192D01*
G03X383480Y867401I0J1301D01*
G03X383463Y867612I-1301J1D01*
G02X383857Y868077I395J65D01*
G01X384200D01*
G02X384594Y867612I-1J-400D01*
G03X384577Y867401I1284J-210D01*
G03X387179I1301J0D01*
G03X386626Y868465I-1300J0D01*
G02X386573Y869075I230J327D01*
G01X387010Y869512D01*
X387139Y869446D01*
G03X387729Y869305I589J1160D01*
G03X389030Y870606I0J1301D01*
G03X388956Y871038I-1301J-1D01*
G01X388926Y871125D01*
X389339Y871841D01*
X390129Y872631D01*
X390158Y872646D01*
G03X390742Y873230I-580J1164D01*
G01X390757Y873259D01*
X391585Y874087D01*
X391979D01*
Y873877D01*
G03X391977Y873810I1299J-72D01*
G03X394579I1301J0D01*
G03X394087Y874829I-1301J0D01*
G02X394053Y875425I249J313D01*
G01X394497Y875869D01*
X394621Y875816D01*
G03X395129Y875713I507J1198D01*
G03X396430Y877014I0J1301D01*
G03X396029Y877953I-1300J0D01*
G02X396023Y878525I277J289D01*
G01X396501Y879003D01*
X396615Y878970D01*
G03X396979Y878918I364J1248D01*
G03Y881520I0J1301D01*
G03X396716Y881493I1J-1301D01*
G01X396611Y881471D01*
X396247Y881835D01*
X396882Y883020D01*
G02X397609Y882970I352J-189D01*
G03X398589Y882144I1220J453D01*
G01X398679Y882127D01*
X399481Y880737D01*
X399451Y880651D01*
G03X399377Y880219I1227J-433D01*
G03X401979I1301J0D01*
G03X400918Y881498I-1301J0D01*
G01X400827Y881515D01*
X400026Y882904D01*
X400056Y882991D01*
G03X400130Y883423I-1227J433D01*
G03X398829Y884724I-1301J0D01*
G03X398531Y884689I2J-1301D01*
G02X398087Y885268I-91J390D01*
G01X398682Y886377D01*
G02X399421Y886292I353J-189D01*
G03X400678Y885326I1257J335D01*
G03Y887928I0J1301D01*
G03X400261Y887860I-2J-1301D01*
G02X399781Y888427I-127J379D01*
G01X403512Y895387D01*
X403525Y895403D01*
G03X403777Y895874I-997J836D01*
G01X403783Y895894D01*
X404328Y896910D01*
X407570Y900152D01*
X408630D01*
X409377Y899405D01*
X410467D01*
X410494Y899237D01*
G03X413062I1284J208D01*
G01X413089Y899405D01*
X414227D01*
X415102Y900280D01*
X415942D01*
X416927Y899295D01*
X417876D01*
X417913Y899142D01*
G03X420443I1265J303D01*
G01X420480Y899295D01*
X421457D01*
X422297Y900135D01*
X422397Y900205D01*
X422487Y900255D01*
X422607Y900305D01*
X422687Y900325D01*
X422757Y900335D01*
X422857Y900345D01*
X422927D01*
X423047Y900325D01*
X423159Y900300D01*
X423231Y900255D01*
X423327D01*
X423427Y900155D01*
X423677D01*
X424007Y900485D01*
Y900853D01*
X424288Y900929D01*
G03X424699Y901244I-175J653D01*
G01X424757Y901344D01*
X424859Y901354D01*
G03X426030Y902649I-131J1295D01*
G03X424729Y903950I-1301J0D01*
G03X423430Y902722I0J-1301D01*
G02X423012Y902345I-399J22D01*
G01X422758D01*
X422670Y902342D01*
X422332Y902680D01*
X422326Y902754D01*
G03X422301Y902920I-1296J-110D01*
G01X422297Y902941D01*
Y903505D01*
X420725Y905077D01*
X420365D01*
Y905317D01*
X420380Y905354D01*
G03X420480Y905853I-1201J500D01*
G03X417878I-1301J0D01*
G03X417910Y905565I1301J-1D01*
G02X417520Y905077I-390J-88D01*
G01X416787D01*
X416630Y905234D01*
X416681Y905357D01*
G03X416779Y905853I-1203J495D01*
G03X415478Y907154I-1301J0D01*
G03X415310Y907143I1J-1301D01*
G02X414859Y907540I-51J397D01*
G01Y908632D01*
X414868Y908662D01*
G03X414930Y909057I-1239J397D01*
G03X414868Y909452I-1301J-2D01*
G01X414859Y909482D01*
Y909830D01*
X413279Y911410D01*
Y913766D01*
G02X413667Y914166I400J0D01*
G03Y916766I-38J1300D01*
G02X413279Y917166I12J400D01*
G01Y931097D01*
X414547Y932365D01*
G37*
G36*
G01X158200Y1466362D02*
X225500D01*
X227743Y1464119D01*
Y1440369D01*
X227802Y1440310D01*
Y1421499D01*
X227799Y1421453D01*
X227480Y1420682D01*
X226710Y1418825D01*
Y1418824D01*
X226464Y1418230D01*
X223007Y1409884D01*
X220829Y1404625D01*
G03X220811Y1404579I1380J-566D01*
G03X220716Y1404057I1396J-524D01*
G01Y1387978D01*
X219000Y1386262D01*
Y1324735D01*
X194927Y1300662D01*
X141200D01*
X137441Y1304421D01*
Y1317634D01*
X137411Y1317708D01*
Y1335051D01*
X131500Y1340962D01*
Y1439662D01*
X158200Y1466362D01*
G37*
G36*
G01X233328Y134370D02*
X315012D01*
X327920Y121462D01*
Y72762D01*
X321071Y65914D01*
X320010D01*
G03X318984Y65488I1J-1451D01*
G01X312869Y59374D01*
X307097D01*
G02X306813Y60055I0J400D01*
G03X307249Y61113I-1066J1058D01*
G03X306719Y62258I-1502J0D01*
G02Y62868I259J305D01*
G03X307249Y64013I-972J1145D01*
G03X304245I-1502J0D01*
G03X304775Y62868I1502J0D01*
G02Y62258I-259J-305D01*
G03X304245Y61113I972J-1145D01*
G03X304681Y60055I1502J0D01*
G02X304397Y59374I-284J-281D01*
G01X284459D01*
X278400Y65432D01*
Y100852D01*
X275680Y103572D01*
X235410D01*
X231620Y107362D01*
Y132662D01*
X233328Y134370D01*
G37*
G36*
G01X280626Y682878D02*
X268694D01*
X261890Y676075D01*
X259290Y673475D01*
X240721D01*
X240591Y673605D01*
X240401D01*
X238826Y675180D01*
Y711315D01*
X240742Y713231D01*
X278555D01*
X282360Y709426D01*
Y684612D01*
X280626Y682878D01*
G37*
G36*
G01X253537Y102012D02*
X274240D01*
X276930Y99322D01*
Y67062D01*
X265820Y55952D01*
Y47032D01*
X264530Y45742D01*
X245220D01*
Y58575D01*
G03Y60949I-919J1187D01*
G01Y66350D01*
X245396Y66370D01*
G03Y69354I-176J1492D01*
G01X245220Y69374D01*
Y100322D01*
X245712Y100814D01*
G02X246395Y100534I283J-283D01*
G03X247897Y99041I1502J9D01*
G03X249399Y100543I0J1502D01*
G03X249139Y101387I-1502J-1D01*
G02X249470Y102012I331J225D01*
G01X250057D01*
G02X250423Y101450I0J-400D01*
G03X250295Y100843I1375J-607D01*
G03X253299I1502J0D01*
G03X253171Y101450I-1503J0D01*
G02X253537Y102012I366J162D01*
G37*
G36*
G01X273100Y636272D02*
X277560D01*
X282920Y630912D01*
X285075D01*
X285080Y630749D01*
G03X288084I1502J8D01*
G01X288089Y630912D01*
X289940D01*
X299020Y621832D01*
Y589688D01*
G02X298490Y589310I-400J0D01*
G01X298475Y589315D01*
G03X298000Y589392I-475J-1425D01*
G01X297985D01*
G03X296498Y587890I15J-1502D01*
G03X298000Y586388I1502J0D01*
G03X298475Y586465I0J1502D01*
G01X298490Y586470D01*
G02X299020Y586092I130J-378D01*
G01Y571717D01*
X298868Y571565D01*
X295881D01*
G03X293805Y572399I-2076J-2167D01*
G03X290803Y569397I0J-3002D01*
G03X291331Y567697I3001J0D01*
G03X290803Y565997I2473J-1700D01*
G03X296807I3002J0D01*
G03X296635Y566998I-3002J-1D01*
G02X297012Y567531I377J133D01*
G01X298868D01*
X299020Y567379D01*
Y561082D01*
X297300Y559362D01*
X249300D01*
X248518Y560144D01*
Y632086D01*
X249152Y632720D01*
X269548D01*
X273100Y636272D01*
G37*
G36*
G01X280513Y679872D02*
X288590D01*
X299000Y669462D01*
Y664986D01*
X299020Y664899D01*
Y642392D01*
X295610Y638982D01*
X295474Y639070D01*
G03X294658Y639311I-816J-1261D01*
G03X293156Y637809I0J-1502D01*
G03X293491Y636863I1503J0D01*
G01X289840Y633212D01*
X284170D01*
X279176Y638206D01*
X271494D01*
X267278Y633990D01*
X249097D01*
X248518Y634569D01*
Y666086D01*
X249152Y666720D01*
X255900D01*
X266084Y676904D01*
G02X266765Y676584I283J-283D01*
G03X266750Y676260I3487J-324D01*
G03X273754I3502J0D01*
G03X272240Y679143I-3502J0D01*
G02X272467Y679872I227J329D01*
G01X275739D01*
G02X275977Y679151I0J-400D01*
G03X274524Y676260I2150J-2891D01*
G03X281728I3602J0D01*
G03X280275Y679151I-3603J0D01*
G02X280513Y679872I238J321D01*
G37*
G36*
G01X350000Y749862D02*
X368000D01*
X370500Y747362D01*
Y684201D01*
X370496Y684182D01*
G03X370468Y683892I1474J-289D01*
G03X370496Y683602I1502J-1D01*
G01X370500Y683583D01*
Y624362D01*
X365000Y618862D01*
X303500D01*
X302000Y620362D01*
Y632862D01*
X304500Y635362D01*
Y704362D01*
X350000Y749862D01*
G37*
G36*
G01X303041Y1310063D02*
X330044D01*
X332736Y1307371D01*
Y1303211D01*
X339609Y1296338D01*
X361629D01*
X374509Y1283458D01*
X488559D01*
X501859Y1296758D01*
X519999D01*
X527359Y1304118D01*
Y1307273D01*
X528705Y1308619D01*
X583863D01*
X587080Y1305402D01*
Y1194392D01*
X532751Y1140063D01*
X526365D01*
X526210Y1140355D01*
X526250Y1140444D01*
G03X526362Y1140973I-1189J528D01*
G03X523760I-1301J0D01*
G03X523820Y1140583I1301J1D01*
G02X523438Y1140063I-382J-120D01*
G01X522984D01*
G02X522602Y1140583I0J400D01*
G03X522662Y1140973I-1241J391D01*
G03X520060I-1301J0D01*
G03X520120Y1140583I1301J1D01*
G02X519738Y1140063I-382J-120D01*
G01X518965D01*
X518810Y1140355D01*
X518850Y1140444D01*
G03X518962Y1140973I-1189J528D01*
G03X516360I-1301J0D01*
G03X516420Y1140583I1301J1D01*
G02X516038Y1140063I-382J-120D01*
G01X515584D01*
G02X515202Y1140583I0J400D01*
G03X515262Y1140973I-1241J391D01*
G03X512660I-1301J0D01*
G03X512720Y1140583I1301J1D01*
G02X512338Y1140063I-382J-120D01*
G01X511565D01*
X511410Y1140355D01*
X511450Y1140444D01*
G03X511562Y1140973I-1189J528D01*
G03X508960I-1301J0D01*
G03X509020Y1140583I1301J1D01*
G02X508638Y1140063I-382J-120D01*
G01X508184D01*
G02X507802Y1140583I0J400D01*
G03X507862Y1140973I-1241J391D01*
G03X505260I-1301J0D01*
G03X505320Y1140583I1301J1D01*
G02X504938Y1140063I-382J-120D01*
G01X504165D01*
X504010Y1140355D01*
X504050Y1140444D01*
G03X504162Y1140973I-1189J528D01*
G03X501560I-1301J0D01*
G03X501620Y1140583I1301J1D01*
G02X501238Y1140063I-382J-120D01*
G01X500784D01*
G02X500402Y1140583I0J400D01*
G03X500462Y1140973I-1241J391D01*
G03X497860I-1301J0D01*
G03X497920Y1140583I1301J1D01*
G02X497538Y1140063I-382J-120D01*
G01X496765D01*
X496610Y1140355D01*
X496650Y1140444D01*
G03X496762Y1140973I-1189J528D01*
G03X494160I-1301J0D01*
G03X494220Y1140583I1301J1D01*
G02X493838Y1140063I-382J-120D01*
G01X493384D01*
G02X493002Y1140583I0J400D01*
G03X493062Y1140973I-1241J391D01*
G03X490460I-1301J0D01*
G03X490520Y1140583I1301J1D01*
G02X490138Y1140063I-382J-120D01*
G01X489365D01*
X489210Y1140355D01*
X489250Y1140444D01*
G03X489362Y1140973I-1189J528D01*
G03X486760I-1301J0D01*
G03X486820Y1140583I1301J1D01*
G02X486438Y1140063I-382J-120D01*
G01X485984D01*
G02X485602Y1140583I0J400D01*
G03X485662Y1140973I-1241J391D01*
G03X483060I-1301J0D01*
G03X483120Y1140583I1301J1D01*
G02X482738Y1140063I-382J-120D01*
G01X481965D01*
X481810Y1140355D01*
X481850Y1140444D01*
G03X481962Y1140973I-1189J528D01*
G03X479360I-1301J0D01*
G03X480428Y1139693I1301J0D01*
G01X480523Y1139676D01*
X480692Y1139357D01*
X479736Y1138401D01*
X479597Y1138506D01*
G03X478812Y1138770I-786J-1037D01*
G03X477511Y1137469I0J-1301D01*
G03X477585Y1137037I1301J1D01*
G01X477615Y1136950D01*
X476813Y1135560D01*
X476722Y1135543D01*
G03X475668Y1134396I240J-1279D01*
G01X475661Y1134326D01*
X475243Y1133908D01*
G02X474561Y1134208I-282J283D01*
G03X474562Y1134264I-1300J51D01*
G03X473261Y1132963I-1301J0D01*
G03X473317Y1132964I5J1301D01*
G02X473617Y1132282I17J-400D01*
G01X473088Y1131753D01*
G02X472478Y1131806I-283J283D01*
G03X471412Y1132361I-1066J-746D01*
G03X470111Y1131060I0J-1301D01*
G03X470666Y1129994I1301J0D01*
G02X470719Y1129384I-230J-327D01*
G01X470283Y1128948D01*
X470154Y1129015D01*
G03X469562Y1129157I-591J-1159D01*
G03X468261Y1127856I0J-1301D01*
G03X468403Y1127264I1301J-1D01*
G01X468470Y1127135D01*
X467169Y1125834D01*
X467139Y1125819D01*
G03X466544Y1125224I573J-1168D01*
G01X466529Y1125194D01*
X464826Y1123491D01*
Y1122234D01*
G03Y1120660I1036J-787D01*
G01Y1115826D01*
G03Y1114252I1036J-787D01*
G01Y1113484D01*
G02X464329Y1113096I-400J0D01*
G03X464012Y1113135I-316J-1262D01*
G03Y1110533I0J-1301D01*
G03X464329Y1110572I1J1301D01*
G02X464826Y1110184I97J-388D01*
G01Y1109418D01*
G03Y1107842I1034J-788D01*
G01Y1107076D01*
G02X464329Y1106688I-400J0D01*
G03X464012Y1106727I-316J-1262D01*
G03Y1104125I0J-1301D01*
G03X464329Y1104164I1J1301D01*
G02X464826Y1103776I97J-388D01*
G01Y1103009D01*
G03Y1101433I1034J-788D01*
G01Y1100667D01*
G02X464329Y1100279I-400J0D01*
G03X464012Y1100318I-316J-1262D01*
G03Y1097716I0J-1301D01*
G03X464329Y1097755I1J1301D01*
G02X464826Y1097367I97J-388D01*
G01Y1096600D01*
G03Y1095024I1034J-788D01*
G01Y1094257D01*
G02X464329Y1093869I-400J0D01*
G03X464012Y1093908I-316J-1262D01*
G03Y1091306I0J-1301D01*
G03X464329Y1091345I1J1301D01*
G02X464826Y1090957I97J-388D01*
G01Y1090191D01*
G03Y1088615I1034J-788D01*
G01Y1087850D01*
G02X464328Y1087462I-400J0D01*
G03X464011Y1087501I-316J-1262D01*
G03Y1084899I0J-1301D01*
G03X464328Y1084938I1J1301D01*
G02X464826Y1084550I98J-388D01*
G01Y1083782D01*
G03Y1082208I1036J-787D01*
G01Y1081441D01*
G02X464329Y1081053I-400J0D01*
G03X464012Y1081092I-316J-1262D01*
G03Y1078490I0J-1301D01*
G03X464329Y1078529I1J1301D01*
G02X464826Y1078141I97J-388D01*
G01Y1077374D01*
G03Y1075800I1036J-787D01*
G01Y1075033D01*
G02X464328Y1074645I-400J0D01*
G03X464011Y1074684I-316J-1262D01*
G03Y1072082I0J-1301D01*
G03X464328Y1072121I1J1301D01*
G02X464826Y1071733I98J-388D01*
G01Y1070968D01*
G03Y1069388I1035J-790D01*
G01Y1068624D01*
G02X464328Y1068236I-400J0D01*
G03X464011Y1068275I-316J-1262D01*
G03Y1065673I0J-1301D01*
G03X464328Y1065712I1J1301D01*
G02X464826Y1065324I98J-388D01*
G01Y1064557D01*
G03Y1062983I1036J-787D01*
G01Y1062215D01*
G02X464329Y1061827I-400J0D01*
G03X464012Y1061866I-316J-1262D01*
G03Y1059264I0J-1301D01*
G03X464329Y1059303I1J1301D01*
G02X464826Y1058915I97J-388D01*
G01Y1058148D01*
G03Y1056574I1036J-787D01*
G01Y1055807D01*
G02X464328Y1055419I-400J0D01*
G03X464011Y1055458I-316J-1262D01*
G03Y1052856I0J-1301D01*
G03X464328Y1052895I1J1301D01*
G02X464826Y1052507I98J-388D01*
G01Y1051742D01*
G03Y1050162I1035J-790D01*
G01Y1049399D01*
G02X464328Y1049011I-400J0D01*
G03X464011Y1049050I-316J-1262D01*
G03Y1046448I0J-1301D01*
G03X464328Y1046487I1J1301D01*
G02X464826Y1046099I98J-388D01*
G01Y1045332D01*
G03X464560Y1044544I1034J-788D01*
G03X465218Y1043413I1301J0D01*
G01X465320Y1043355D01*
Y1043105D01*
X466528Y1041896D01*
X466486Y1041777D01*
G03X466410Y1041340I1225J-438D01*
G03X467711Y1040039I1301J0D01*
G03X467832Y1040045I-4J1301D01*
G02X468269Y1039646I37J-398D01*
G01Y1038501D01*
G02X467752Y1038118I-400J0D01*
G03X467372Y1038175I-381J-1244D01*
G03Y1035573I0J-1301D01*
G03X467752Y1035630I-1J1301D01*
G02X468269Y1035247I117J-383D01*
G01Y1024383D01*
X472397Y1020255D01*
Y1016045D01*
G02X471811Y1015691I-400J0D01*
G03X471204Y1015841I-606J-1151D01*
G03X470325Y1015499I0J-1301D01*
G02X469782Y1015502I-270J295D01*
G03X468895Y1015851I-887J-953D01*
G03X467889Y1015375I0J-1301D01*
G02X467272Y1015372I-310J253D01*
G03X466272Y1015841I-1000J-832D01*
G03X465355Y1015463I0J-1301D01*
G02X464791I-282J284D01*
G03X463874Y1015841I-917J-923D01*
G03Y1013239I0J-1301D01*
G03X464791Y1013617I0J1301D01*
G02X465355I282J-284D01*
G03X466272Y1013239I917J923D01*
G03X467278Y1013715I0J1301D01*
G02X467895Y1013718I310J-253D01*
G03X468895Y1013249I1000J832D01*
G03X469774Y1013591I0J1301D01*
G02X470317Y1013588I270J-295D01*
G03X471204Y1013239I887J953D01*
G03X471811Y1013389I1J1301D01*
G02X472397Y1013035I186J-354D01*
G01Y983825D01*
X466147Y977575D01*
Y972405D01*
X465990Y972370D01*
G03X465370Y972038I281J-1270D01*
G02X464806Y972047I-277J288D01*
G03X463874Y972441I-933J-907D01*
G03Y969839I0J-1301D01*
G03X464776Y970202I0J1302D01*
G02X465340Y970193I277J-288D01*
G03X465990Y969830I933J907D01*
G01X466147Y969795D01*
Y968145D01*
X472718Y961574D01*
Y943670D01*
G02X472137Y943313I-400J0D01*
G03X471550Y943453I-587J-1161D01*
G03X470710Y943145I0J-1301D01*
G02X470169Y943168I-258J306D01*
G03X469251Y943547I-918J-922D01*
G03X468301Y943134I1J-1301D01*
G02X467739Y943112I-292J274D01*
G03X466861Y943453I-878J-960D01*
G03X465981Y943111I-1J-1301D01*
G02X465441I-270J294D01*
G03X464561Y943453I-879J-959D01*
G03X463681Y943111I-1J-1301D01*
G02X463141I-270J294D01*
G03X462261Y943453I-879J-959D01*
G03Y940851I0J-1301D01*
G03X463141Y941193I1J1301D01*
G02X463681I270J-294D01*
G03X464561Y940851I879J959D01*
G03X465441Y941193I1J1301D01*
G02X465981I270J-294D01*
G03X466861Y940851I879J959D01*
G03X467811Y941264I-1J1301D01*
G02X468373Y941286I292J-274D01*
G03X469251Y940945I878J960D01*
G03X470091Y941253I0J1301D01*
G02X470632Y941230I258J-306D01*
G03X471550Y940851I918J922D01*
G03X472137Y940991I0J1301D01*
G02X472718Y940634I181J-357D01*
G01Y936924D01*
X470958Y935164D01*
X448149D01*
X448093Y935274D01*
G03X445767I-1163J-581D01*
G01X445711Y935164D01*
X444449D01*
X444393Y935274D01*
G03X442067I-1163J-581D01*
G01X442011Y935164D01*
X440749D01*
X440693Y935274D01*
G03X438367I-1163J-581D01*
G01X438311Y935164D01*
X437049D01*
X436993Y935274D01*
G03X434667I-1163J-581D01*
G01X434611Y935164D01*
X433349D01*
X433293Y935274D01*
G03X430967I-1163J-581D01*
G01X430911Y935164D01*
X429315D01*
G02X428976Y935777I0J400D01*
G03X429173Y936378I-1101J694D01*
G02X429738Y936714I399J-28D01*
G03X430279Y936596I541J1183D01*
G03Y939198I0J1301D01*
G03X428981Y937989I0J-1301D01*
G02X428416Y937653I-399J28D01*
G03X427875Y937771I-541J-1183D01*
G03X426574Y936470I0J-1301D01*
G03X426774Y935777I1301J0D01*
G02X426435Y935164I-339J-213D01*
G01X410207D01*
X408057Y937314D01*
Y940944D01*
X408168Y940999D01*
G03X408469Y941205I-577J1166D01*
G02X409009I270J-294D01*
G03X409889Y940863I879J959D01*
G03Y943465I0J1301D01*
G03X409009Y943123I-1J-1301D01*
G02X408469I-270J294D01*
G03X408168Y943329I-878J-960D01*
G01X408057Y943384D01*
Y957865D01*
X414107Y963915D01*
Y969445D01*
G02X414474Y969844I400J0D01*
G03X415279Y970214I-108J1296D01*
G02X415841I281J-284D01*
G03X416755Y969839I914J926D01*
G03Y972441I0J1301D01*
G03X415841Y972066I0J-1301D01*
G02X415279I-281J284D01*
G03X414474Y972436I-913J-926D01*
G02X414107Y972835I33J399D01*
G01Y980225D01*
X408837Y985495D01*
Y1012845D01*
G02X409272Y1013244I400J1D01*
G03X409385Y1013239I114J1296D01*
G03X410265Y1013581I1J1301D01*
G02X410805I270J-294D01*
G03X411685Y1013239I879J959D01*
G03Y1015841I0J1301D01*
G03X410805Y1015499I-1J-1301D01*
G02X410265I-270J294D01*
G03X409385Y1015841I-879J-959D01*
G03X409272Y1015836I1J-1301D01*
G02X408837Y1016235I-35J398D01*
G01Y1027603D01*
X404155Y1032285D01*
Y1037616D01*
X404169Y1037651D01*
G03X404263Y1038136I-1207J486D01*
G03X404169Y1038621I-1301J-1D01*
G01X404155Y1038656D01*
Y1039658D01*
G02X404615Y1040054I400J1D01*
G03X404811Y1040039I197J1286D01*
G03Y1042641I0J1301D01*
G03X404615Y1042626I1J-1301D01*
G02X404155Y1043022I-60J395D01*
G01Y1044024D01*
X404169Y1044059D01*
G03X404263Y1044544I-1207J486D01*
G03X404169Y1045029I-1301J-1D01*
G01X404155Y1045064D01*
Y1046067D01*
G02X404615Y1046463I400J1D01*
G03X404811Y1046448I197J1286D01*
G03Y1049050I0J1301D01*
G03X404615Y1049035I1J-1301D01*
G02X404155Y1049431I-60J395D01*
G01Y1050432D01*
X404169Y1050467D01*
G03X404263Y1050952I-1207J486D01*
G03X404169Y1051437I-1301J-1D01*
G01X404155Y1051472D01*
Y1052475D01*
G02X404615Y1052871I400J1D01*
G03X404811Y1052856I197J1286D01*
G03Y1055458I0J1301D01*
G03X404615Y1055443I1J-1301D01*
G02X404155Y1055839I-60J395D01*
G01Y1056841D01*
X404169Y1056876D01*
G03X404263Y1057361I-1207J486D01*
G03X404169Y1057846I-1301J-1D01*
G01X404155Y1057881D01*
Y1058883D01*
G02X404615Y1059279I400J1D01*
G03X404811Y1059264I197J1286D01*
G03Y1061866I0J1301D01*
G03X404615Y1061851I1J-1301D01*
G02X404155Y1062247I-60J395D01*
G01Y1063250D01*
X404169Y1063285D01*
G03X404263Y1063770I-1207J486D01*
G03X404169Y1064255I-1301J-1D01*
G01X404155Y1064290D01*
Y1065292D01*
G02X404615Y1065688I400J1D01*
G03X404811Y1065673I197J1286D01*
G03Y1068275I0J1301D01*
G03X404615Y1068260I1J-1301D01*
G02X404155Y1068656I-60J395D01*
G01Y1069658D01*
X404169Y1069693D01*
G03X404263Y1070178I-1207J486D01*
G03X404169Y1070663I-1301J-1D01*
G01X404155Y1070698D01*
Y1071701D01*
G02X404615Y1072097I400J1D01*
G03X404811Y1072082I197J1286D01*
G03Y1074684I0J1301D01*
G03X404615Y1074669I1J-1301D01*
G02X404155Y1075065I-60J395D01*
G01Y1075454D01*
X404841Y1076140D01*
G02X405486Y1076029I283J-282D01*
G03X406661Y1075286I1175J558D01*
G03X407956Y1076458I0J1301D01*
G02X408372Y1076818I398J-40D01*
G03X408511Y1076814I155J2973D01*
G03X408651Y1076818I-15J2977D01*
G02X409067Y1076458I18J-399D01*
G03X410362Y1075286I1295J129D01*
G03X411663Y1076587I0J1301D01*
G03X411120Y1077644I-1300J0D01*
G02X411017Y1078185I234J325D01*
G03X411089Y1078303I-2504J1609D01*
G01X411168Y1078439D01*
G02X411678Y1078604I346J-200D01*
G03X412211Y1078490I533J1187D01*
G03X413506Y1079662I0J1301D01*
G02X413922Y1080022I398J-39D01*
G03X414062Y1080018I155J2973D01*
G03X414200Y1080022I-17J2977D01*
G02X414616Y1079662I18J-400D01*
G03X415911Y1078490I1295J129D01*
G03X417212Y1079791I0J1301D01*
G03X416974Y1080541I-1301J0D01*
G02X417202Y1081159I327J231D01*
G03X417761Y1081337I-1297J5039D01*
G03X418320Y1081159I1856J4861D01*
G02X418548Y1080541I-99J-388D01*
G03X418310Y1079791I1063J-750D01*
G03X419611Y1078490I1301J0D01*
G03X420793Y1079246I0J1302D01*
G02X421442Y1079359I363J-167D01*
G03X422558Y1078491I3722J3634D01*
G03X423871Y1077955I2604J4504D01*
G02X424099Y1077337I-99J-387D01*
G03X423861Y1076587I1063J-750D01*
G03X426463I1301J0D01*
G03X426225Y1077337I-1301J0D01*
G02X426453Y1077955I327J230D01*
G03X427012Y1078133I-1296J5038D01*
G03X427571Y1077956I1847J4863D01*
G02X427798Y1077337I-99J-388D01*
G03X427560Y1076587I1063J-750D01*
G03X430162I1301J0D01*
G03X430088Y1077018I-1301J-1D01*
G01X430058Y1077105D01*
X430661Y1078150D01*
X430818Y1078094D01*
G03X431271Y1077956I1741J4902D01*
G02X431498Y1077338I-100J-387D01*
G03X431260Y1076587I1063J-750D01*
G03X433862I1301J0D01*
G03X433624Y1077338I-1301J1D01*
G02X433851Y1077956I327J231D01*
G03X434411Y1078133I-1285J5041D01*
G03X438767Y1078435I1851J4862D01*
G03X438838Y1078475I-1425J2613D01*
G01X438873Y1078496D01*
G03X441397Y1082167I-2611J4499D01*
G03X443248Y1085371I-3284J4034D01*
G03X445097Y1088575I-3287J4033D01*
G03X447014Y1092608I-3284J4033D01*
G01Y1092664D01*
G03X447013Y1092739I-2977J-2D01*
G03X445909Y1095813I-5200J-132D01*
G03X446820Y1100419I-4098J3204D01*
G02X447242Y1100925I385J108D01*
G03X447361Y1100920I114J1296D01*
G03Y1103522I0J1301D01*
G03X446180Y1102766I0J-1300D01*
G02X445530Y1102654I-363J167D01*
G03X445098Y1103049I-3720J-3635D01*
G03X443247Y1106255I-5137J-828D01*
G03X442209Y1108630I-5135J-830D01*
G03X443314Y1111834I-4096J3205D01*
G01Y1111890D01*
G03X443313Y1111965I-2977J-2D01*
G03X441397Y1115867I-5200J-132D01*
G03X439547Y1119072I-5135J-828D01*
G03X437697Y1122276I-5136J-829D01*
G03X435847Y1125480I-5135J-829D01*
G03X433996Y1128685I-5136J-829D01*
G03X433870Y1129258I-5135J-829D01*
G02X434292Y1129764I385J108D01*
G03X434411Y1129759I114J1296D01*
G03Y1132361I0J1301D01*
G03X433230Y1131605I0J-1300D01*
G02X432580Y1131493I-363J167D01*
G03X432348Y1131716I-3719J-3637D01*
G01Y1137111D01*
G03X432582Y1137335I-3479J3869D01*
G02X433231Y1137224I286J-279D01*
G03X434412Y1136468I1181J544D01*
G03Y1139070I0J1301D01*
G03X434293Y1139065I-5J-1301D01*
G02X433871Y1139571I-37J398D01*
G03X434062Y1141121I-5010J1404D01*
G01Y1145957D01*
G03X433553Y1147621I-2977J-1D01*
G03X433612Y1148222I-3033J601D01*
G01Y1151005D01*
G03X433581Y1151435I-3092J-7D01*
G02X434039Y1151886I396J56D01*
G03X434272Y1151868I232J1484D01*
G03X435279Y1152255I1J1502D01*
G02X435815I268J-296D01*
G03X436822Y1151868I1006J1115D01*
G03Y1154872I0J1502D01*
G03X435815Y1154485I-1J-1502D01*
G02X435279I-268J296D01*
G03X434272Y1154872I-1006J-1115D01*
G03X433455Y1154630I1J-1502D01*
G02X432838Y1154966I-217J336D01*
G01Y1159974D01*
G02X433455Y1160310I400J0D01*
G03X434272Y1160068I818J1260D01*
G03X435279Y1160455I1J1502D01*
G02X435815I268J-296D01*
G03X436822Y1160068I1006J1115D01*
G03Y1163072I0J1502D01*
G03X435815Y1162685I-1J-1502D01*
G02X435279I-268J296D01*
G03X434272Y1163072I-1006J-1115D01*
G03X433455Y1162830I1J-1502D01*
G02X432838Y1163166I-217J336D01*
G01Y1168474D01*
G02X433455Y1168810I400J0D01*
G03X434272Y1168568I818J1260D01*
G03X435279Y1168955I1J1502D01*
G02X435815I268J-296D01*
G03X436822Y1168568I1006J1115D01*
G03Y1171572I0J1502D01*
G03X435815Y1171185I-1J-1502D01*
G02X435279I-268J296D01*
G03X434272Y1171572I-1006J-1115D01*
G03X433265Y1171185I-1J-1502D01*
G02X432729I-268J296D01*
G03X432601Y1171288I-1004J-1117D01*
G01X432555Y1171321D01*
X431258Y1174456D01*
G03X430884Y1175116I-2856J-1183D01*
G01X430819Y1175203D01*
X427729Y1182417D01*
X387304Y1222842D01*
X376302Y1229843D01*
X328099Y1269400D01*
X317908Y1279592D01*
X317902Y1279598D01*
G03X317730Y1279785I-2359J-1998D01*
G01X316703Y1280812D01*
G03X316516Y1280985I-2191J-2181D01*
G01X316509Y1280990D01*
X314218Y1283281D01*
X314213Y1283287D01*
G03X314040Y1283475I-2359J-1998D01*
G01X313013Y1284502D01*
G03X312825Y1284675I-2186J-2186D01*
G01X312819Y1284680D01*
X308644Y1288855D01*
X307460Y1291360D01*
X305451Y1295609D01*
X303576Y1302365D01*
X302839Y1309861D01*
X303041Y1310063D01*
G37*
G36*
G01X479036Y1465086D02*
X615416D01*
X743525Y1442497D01*
X743578Y1442464D01*
X750780Y1435262D01*
Y1414307D01*
G02X750097Y1414025I-400J1D01*
G01X725672Y1438449D01*
G03X725649Y1438472I-1250J-1227D01*
G01X725431Y1438690D01*
X725148Y1438808D01*
X725146Y1438809D01*
G03X725134Y1438814I-680J-1614D01*
G03X725121Y1438819I-635J-1632D01*
G03X725109Y1438824I-680J-1614D01*
G01X709368Y1445344D01*
X709335Y1445357D01*
G03X709325Y1445362I-785J-1558D01*
G01X709323D01*
X709049Y1445476D01*
X635858D01*
X635376Y1444994D01*
G03X635350Y1444968I1225J-1251D01*
G01X621883Y1431502D01*
X524814D01*
X516978Y1439338D01*
Y1449645D01*
G03X516977Y1449682I-1751J-29D01*
G01Y1450370D01*
X516495Y1450852D01*
G03X516466Y1450881I-1253J-1224D01*
G01X513421Y1453926D01*
G03X513392Y1453955I-1253J-1224D01*
G01X512910Y1454437D01*
X512222D01*
G03X512185Y1454438I-66J-1750D01*
G01X474878D01*
X472602Y1456713D01*
G03X472576Y1456739I-1251J-1225D01*
G01X472094Y1457221D01*
X471384D01*
G03X471369Y1457222I-124J-1746D01*
G01X445076D01*
G03X445061Y1457221I109J-1747D01*
G01X444351D01*
X443869Y1456739D01*
G03X443841Y1456711I1224J-1252D01*
G01X427979Y1440849D01*
G03X427954Y1440824I1226J-1251D01*
G01X427469Y1440339D01*
Y1439651D01*
G03X427468Y1439614I1750J-66D01*
G01Y1431042D01*
X423454Y1427028D01*
X421035D01*
G03X420998Y1427027I29J-1751D01*
G01X420310D01*
X419828Y1426545D01*
G03X419800Y1426517I1224J-1252D01*
G01X414554Y1421271D01*
G03X414529Y1421246I1226J-1251D01*
G01X414044Y1420761D01*
Y1405368D01*
X411112Y1402437D01*
X411097Y1402422D01*
G02X410415Y1402684I-283J283D01*
G03X408915Y1404108I-1500J-78D01*
G03X407413Y1402606I0J-1502D01*
G03X408837Y1401106I1502J0D01*
G02X409099Y1400424I-21J-399D01*
G01X401995Y1393320D01*
X395061D01*
X394801Y1393580D01*
X394698Y1393682D01*
Y1398552D01*
X394218Y1399032D01*
G03X394152Y1399098I-1271J-1205D01*
G01X393672Y1399578D01*
X390832D01*
X390358Y1400052D01*
Y1401033D01*
X391486Y1402160D01*
X391533Y1402175D01*
G03X392936Y1404085I-599J1910D01*
G01Y1407605D01*
G03X388932I-2002J0D01*
G01Y1404560D01*
X387369Y1402996D01*
G03X386856Y1401758I1237J-1238D01*
G01Y1399327D01*
G03X387369Y1398089I1750J0D01*
G01X388869Y1396589D01*
G03X390107Y1396076I1238J1237D01*
G01X391196D01*
Y1392232D01*
X391678Y1391750D01*
G03X391707Y1391721I1252J1224D01*
G01X393100Y1390328D01*
G03X393129Y1390299I1253J1224D01*
G01X393611Y1389817D01*
X394299D01*
G03X394336Y1389816I66J1750D01*
G01X402720D01*
G03X402757Y1389817I-29J1751D01*
G01X403445D01*
X403927Y1390299D01*
G03X403955Y1390327I-1224J1252D01*
G01X417036Y1403408D01*
G03X417061Y1403433I-1226J1251D01*
G01X417546Y1403918D01*
Y1419311D01*
X421760Y1423524D01*
X424179D01*
G03X424216Y1423525I-29J1751D01*
G01X424904D01*
X425386Y1424007D01*
G03X425414Y1424035I-1224J1252D01*
G01X430461Y1429082D01*
G03X430486Y1429107I-1226J1251D01*
G01X430971Y1429592D01*
Y1430280D01*
G03X430972Y1430317I-1750J66D01*
G01Y1438889D01*
X445801Y1453718D01*
X470644D01*
X472920Y1451443D01*
G03X472946Y1451417I1251J1225D01*
G01X473428Y1450935D01*
X474138D01*
G03X474153Y1450934I124J1746D01*
G01X481395D01*
G02X481794Y1450540I-1J-400D01*
G03X480959Y1449091I840J-1449D01*
G03X481863Y1447604I1675J0D01*
G02X481710Y1447276I-400J-13D01*
G03X481131Y1446091I923J-1185D01*
G03X484135I1502J0D01*
G03X483546Y1447284I-1503J0D01*
G02X483403Y1447604I257J307D01*
G03X484307Y1449091I-771J1487D01*
G03X483472Y1450539I-1673J0D01*
G02X483871Y1450934I400J-5D01*
G01X489851D01*
G02X490250Y1450540I-1J-400D01*
G03X489415Y1449091I840J-1449D01*
G03X490319Y1447604I1675J0D01*
G02X490166Y1447276I-400J-13D01*
G03X489587Y1446091I923J-1185D01*
G03X492591I1502J0D01*
G03X492002Y1447284I-1503J0D01*
G02X491859Y1447604I257J307D01*
G03X492763Y1449091I-771J1487D01*
G03X491928Y1450539I-1673J0D01*
G02X492327Y1450934I400J-5D01*
G01X498251D01*
G02X498650Y1450540I-1J-400D01*
G03X497815Y1449091I840J-1449D01*
G03X498719Y1447604I1675J0D01*
G02X498566Y1447276I-400J-13D01*
G03X497987Y1446091I923J-1185D01*
G03X500991I1502J0D01*
G03X500402Y1447284I-1503J0D01*
G02X500259Y1447604I257J307D01*
G03X501163Y1449091I-771J1487D01*
G03X500328Y1450539I-1673J0D01*
G02X500727Y1450934I400J-5D01*
G01X511460D01*
X513474Y1448920D01*
Y1438613D01*
G03X513475Y1438576I1751J29D01*
G01Y1437888D01*
X513957Y1437406D01*
G03X513986Y1437377I1253J1224D01*
G01X522853Y1428510D01*
G03X522882Y1428481I1253J1224D01*
G01X523364Y1427999D01*
X524052D01*
G03X524089Y1427998I66J1750D01*
G01X622608D01*
G03X622645Y1427999I-29J1751D01*
G01X623333D01*
X623815Y1428481D01*
G03X623844Y1428510I-1224J1253D01*
G01X637308Y1441974D01*
X708353D01*
X723447Y1435721D01*
X750780Y1408388D01*
Y1314742D01*
X746047Y1310009D01*
X526698D01*
G03X526556Y1309950I0J-200D01*
G01X525264Y1308658D01*
G03X525205Y1308516I141J-142D01*
G01Y1304365D01*
X518833Y1297994D01*
X501458D01*
G03X501316Y1297935I0J-200D01*
G01X487929Y1284548D01*
X375139D01*
X362258Y1297429D01*
G03X362116Y1297488I-142J-141D01*
G01X340389D01*
X334432Y1303445D01*
Y1308599D01*
G03X334373Y1308741I-200J0D01*
G01X331847Y1311267D01*
G03X331705Y1311326I-142J-141D01*
G01X303091D01*
X300868Y1313549D01*
X300859Y1313641D01*
X300854Y1313694D01*
X300833Y1313909D01*
X300815Y1314100D01*
Y1380900D01*
X300873Y1380960D01*
X301888Y1381974D01*
X312860Y1409562D01*
X327003Y1423705D01*
X397826Y1453039D01*
X479036Y1465086D01*
G37*
G36*
G01X333403Y882619D02*
X333588Y883219D01*
X334618D01*
X334803Y882619D01*
Y882444D01*
X333403D01*
Y882619D01*
G37*
G36*
G01X337055D02*
X337240Y883219D01*
X338270D01*
X338455Y882619D01*
Y882445D01*
X337055D01*
Y882619D01*
G37*
G36*
G01X333403D02*
X333588Y883219D01*
X334618D01*
X334803Y882619D01*
Y882444D01*
X333403D01*
Y882619D01*
G37*
G36*
G01X337055D02*
X337240Y883219D01*
X338270D01*
X338455Y882619D01*
Y882445D01*
X337055D01*
Y882619D01*
G37*
G36*
G01X338455Y877817D02*
X338270Y877217D01*
X337240D01*
X337055Y877817D01*
Y877992D01*
X338455D01*
Y877817D01*
G37*
G36*
G01D02*
X338270Y877217D01*
X337240D01*
X337055Y877817D01*
Y877992D01*
X338455D01*
Y877817D01*
G37*
G36*
G01X336662Y881023D02*
X336477Y880423D01*
X335447D01*
X335262Y881023D01*
Y881197D01*
X336662D01*
Y881023D01*
G37*
G36*
G01D02*
X336477Y880423D01*
X335447D01*
X335262Y881023D01*
Y881197D01*
X336662D01*
Y881023D01*
G37*
G36*
G01X333514Y877632D02*
X333087Y878092D01*
X333602Y878984D01*
X334214Y878844D01*
X334365Y878757D01*
X333665Y877545D01*
X333514Y877632D01*
G37*
G36*
G01X335262Y879415D02*
X335447Y880015D01*
X336477D01*
X336662Y879415D01*
Y879241D01*
X335262D01*
Y879415D01*
G37*
G36*
G01X333514Y877632D02*
X333087Y878092D01*
X333602Y878984D01*
X334214Y878844D01*
X334365Y878757D01*
X333665Y877545D01*
X333514Y877632D01*
G37*
G36*
G01X335262Y879415D02*
X335447Y880015D01*
X336477D01*
X336662Y879415D01*
Y879241D01*
X335262D01*
Y879415D01*
G37*
G36*
G01X338455Y884227D02*
X338270Y883627D01*
X337240D01*
X337055Y884227D01*
Y884401D01*
X338455D01*
Y884227D01*
G37*
G36*
G01D02*
X338270Y883627D01*
X337240D01*
X337055Y884227D01*
Y884401D01*
X338455D01*
Y884227D01*
G37*
G36*
G01X336652Y893839D02*
X336467Y893239D01*
X335437D01*
X335252Y893839D01*
Y894014D01*
X336652D01*
Y893839D01*
G37*
G36*
G01D02*
X336467Y893239D01*
X335437D01*
X335252Y893839D01*
Y894014D01*
X336652D01*
Y893839D01*
G37*
G36*
G01X335252Y892233D02*
X335437Y892833D01*
X336467D01*
X336652Y892233D01*
Y892058D01*
X335252D01*
Y892233D01*
G37*
G36*
G01D02*
X335437Y892833D01*
X336467D01*
X336652Y892233D01*
Y892058D01*
X335252D01*
Y892233D01*
G37*
G36*
G01X333402Y895435D02*
X333587Y896035D01*
X334617D01*
X334802Y895435D01*
Y895261D01*
X333402D01*
Y895435D01*
G37*
G36*
G01X337055Y895437D02*
X337240Y896037D01*
X338270D01*
X338455Y895437D01*
Y895262D01*
X337055D01*
Y895437D01*
G37*
G36*
G01X333402Y895435D02*
X333587Y896035D01*
X334617D01*
X334802Y895435D01*
Y895261D01*
X333402D01*
Y895435D01*
G37*
G36*
G01X337055Y895437D02*
X337240Y896037D01*
X338270D01*
X338455Y895437D01*
Y895262D01*
X337055D01*
Y895437D01*
G37*
G36*
G01X338455Y890635D02*
X338270Y890035D01*
X337240D01*
X337055Y890635D01*
Y890810D01*
X338455D01*
Y890635D01*
G37*
G36*
G01D02*
X338270Y890035D01*
X337240D01*
X337055Y890635D01*
Y890810D01*
X338455D01*
Y890635D01*
G37*
G36*
G01X336662Y887431D02*
X336477Y886831D01*
X335447D01*
X335262Y887431D01*
Y887605D01*
X336662D01*
Y887431D01*
G37*
G36*
G01D02*
X336477Y886831D01*
X335447D01*
X335262Y887431D01*
Y887605D01*
X336662D01*
Y887431D01*
G37*
G36*
G01X335262Y885823D02*
X335447Y886423D01*
X336477D01*
X336662Y885823D01*
Y885649D01*
X335262D01*
Y885823D01*
G37*
G36*
G01D02*
X335447Y886423D01*
X336477D01*
X336662Y885823D01*
Y885649D01*
X335262D01*
Y885823D01*
G37*
G36*
G01X333336Y889027D02*
X333521Y889627D01*
X334551D01*
X334736Y889027D01*
Y888852D01*
X333336D01*
Y889027D01*
G37*
G36*
G01X337055Y889029D02*
X337240Y889629D01*
X338270D01*
X338455Y889029D01*
Y888854D01*
X337055D01*
Y889029D01*
G37*
G36*
G01X333336Y889027D02*
X333521Y889627D01*
X334551D01*
X334736Y889027D01*
Y888852D01*
X333336D01*
Y889027D01*
G37*
G36*
G01X337055Y889029D02*
X337240Y889629D01*
X338270D01*
X338455Y889029D01*
Y888854D01*
X337055D01*
Y889029D01*
G37*
G36*
G01X336629Y900251D02*
X336444Y899651D01*
X335414D01*
X335229Y900251D01*
Y900425D01*
X336629D01*
Y900251D01*
G37*
G36*
G01D02*
X336444Y899651D01*
X335414D01*
X335229Y900251D01*
Y900425D01*
X336629D01*
Y900251D01*
G37*
G36*
G01X333514Y916084D02*
X333087Y916544D01*
X333602Y917436D01*
X334214Y917296D01*
X334365Y917209D01*
X333665Y915997D01*
X333514Y916084D01*
G37*
G36*
G01D02*
X333087Y916544D01*
X333602Y917436D01*
X334214Y917296D01*
X334365Y917209D01*
X333665Y915997D01*
X333514Y916084D01*
G37*
G36*
G01X338502Y916269D02*
X338317Y915669D01*
X337287D01*
X337102Y916269D01*
Y916444D01*
X338502D01*
Y916269D01*
G37*
G36*
G01D02*
X338317Y915669D01*
X337287D01*
X337102Y916269D01*
Y916444D01*
X338502D01*
Y916269D01*
G37*
G36*
G01X335229Y905049D02*
X335414Y905649D01*
X336444D01*
X336629Y905049D01*
Y904875D01*
X335229D01*
Y905049D01*
G37*
G36*
G01D02*
X335414Y905649D01*
X336444D01*
X336629Y905049D01*
Y904875D01*
X335229D01*
Y905049D01*
G37*
G36*
G01X333379Y901845D02*
X333564Y902445D01*
X334594D01*
X334779Y901845D01*
Y901671D01*
X333379D01*
Y901845D01*
G37*
G36*
G01X337079D02*
X337264Y902445D01*
X338294D01*
X338479Y901845D01*
Y901671D01*
X337079D01*
Y901845D01*
G37*
G36*
G01X333379D02*
X333564Y902445D01*
X334594D01*
X334779Y901845D01*
Y901671D01*
X333379D01*
Y901845D01*
G37*
G36*
G01X337079D02*
X337264Y902445D01*
X338294D01*
X338479Y901845D01*
Y901671D01*
X337079D01*
Y901845D01*
G37*
G36*
G01X334748Y903453D02*
X334563Y902853D01*
X333533D01*
X333348Y903453D01*
Y903628D01*
X334748D01*
Y903453D01*
G37*
G36*
G01X338479Y903455D02*
X338294Y902855D01*
X337264D01*
X337079Y903455D01*
Y903629D01*
X338479D01*
Y903455D01*
G37*
G36*
G01X334748Y903453D02*
X334563Y902853D01*
X333533D01*
X333348Y903453D01*
Y903628D01*
X334748D01*
Y903453D01*
G37*
G36*
G01X338479Y903455D02*
X338294Y902855D01*
X337264D01*
X337079Y903455D01*
Y903629D01*
X338479D01*
Y903455D01*
G37*
G36*
G01X334779Y909861D02*
X334594Y909261D01*
X333564D01*
X333379Y909861D01*
Y910036D01*
X334779D01*
Y909861D01*
G37*
G36*
G01X336489Y911636D02*
X336916Y911176D01*
X336401Y910284D01*
X335789Y910424D01*
X335638Y910511D01*
X336338Y911723D01*
X336489Y911636D01*
G37*
G36*
G01X334779Y909861D02*
X334594Y909261D01*
X333564D01*
X333379Y909861D01*
Y910036D01*
X334779D01*
Y909861D01*
G37*
G36*
G01X336489Y911636D02*
X336916Y911176D01*
X336401Y910284D01*
X335789Y910424D01*
X335638Y910511D01*
X336338Y911723D01*
X336489Y911636D01*
G37*
G36*
G01X333355Y908255D02*
X333540Y908855D01*
X334570D01*
X334755Y908255D01*
Y908080D01*
X333355D01*
Y908255D01*
G37*
G36*
G01X337211Y909668D02*
X336784Y910128D01*
X337299Y911020D01*
X337911Y910880D01*
X338062Y910793D01*
X337362Y909581D01*
X337211Y909668D01*
G37*
G36*
G01X333355Y908255D02*
X333540Y908855D01*
X334570D01*
X334755Y908255D01*
Y908080D01*
X333355D01*
Y908255D01*
G37*
G36*
G01X337211Y909668D02*
X336784Y910128D01*
X337299Y911020D01*
X337911Y910880D01*
X338062Y910793D01*
X337362Y909581D01*
X337211Y909668D01*
G37*
G36*
G01X331529Y911457D02*
X331714Y912057D01*
X332744D01*
X332929Y911457D01*
Y911283D01*
X331529D01*
Y911457D01*
G37*
G36*
G01X337055Y914663D02*
X337240Y915263D01*
X338270D01*
X338455Y914663D01*
Y914488D01*
X337055D01*
Y914663D01*
G37*
G36*
G01X335365Y912882D02*
X334938Y913342D01*
X335453Y914234D01*
X336065Y914094D01*
X336216Y914007D01*
X335516Y912795D01*
X335365Y912882D01*
G37*
G36*
G01X331529Y911457D02*
X331714Y912057D01*
X332744D01*
X332929Y911457D01*
Y911283D01*
X331529D01*
Y911457D01*
G37*
G36*
G01X337055Y914663D02*
X337240Y915263D01*
X338270D01*
X338455Y914663D01*
Y914488D01*
X337055D01*
Y914663D01*
G37*
G36*
G01X335365Y912882D02*
X334938Y913342D01*
X335453Y914234D01*
X336065Y914094D01*
X336216Y914007D01*
X335516Y912795D01*
X335365Y912882D01*
G37*
G36*
G01X336629Y906659D02*
X336444Y906059D01*
X335414D01*
X335229Y906659D01*
Y906833D01*
X336629D01*
Y906659D01*
G37*
G36*
G01X338347Y908448D02*
X338774Y907988D01*
X338259Y907096D01*
X337647Y907236D01*
X337496Y907323D01*
X338196Y908535D01*
X338347Y908448D01*
G37*
G36*
G01X336629Y906659D02*
X336444Y906059D01*
X335414D01*
X335229Y906659D01*
Y906833D01*
X336629D01*
Y906659D01*
G37*
G36*
G01X338347Y908448D02*
X338774Y907988D01*
X338259Y907096D01*
X337647Y907236D01*
X337496Y907323D01*
X338196Y908535D01*
X338347Y908448D01*
G37*
G36*
G01X333402Y927481D02*
X333587Y928081D01*
X334617D01*
X334802Y927481D01*
Y927306D01*
X333402D01*
Y927481D01*
G37*
G36*
G01X337080Y927479D02*
X337265Y928079D01*
X338295D01*
X338480Y927479D01*
Y927305D01*
X337080D01*
Y927479D01*
G37*
G36*
G01X333402Y927481D02*
X333587Y928081D01*
X334617D01*
X334802Y927481D01*
Y927306D01*
X333402D01*
Y927481D01*
G37*
G36*
G01X337080Y927479D02*
X337265Y928079D01*
X338295D01*
X338480Y927479D01*
Y927305D01*
X337080D01*
Y927479D01*
G37*
G36*
G01X331177Y924127D02*
X331255Y924750D01*
X332270Y924929D01*
X332556Y924370D01*
X332586Y924199D01*
X331208Y923955D01*
X331177Y924127D01*
G37*
G36*
G01X335206Y924277D02*
X335391Y924877D01*
X336421D01*
X336606Y924277D01*
Y924102D01*
X335206D01*
Y924277D01*
G37*
G36*
G01X331177Y924127D02*
X331255Y924750D01*
X332270Y924929D01*
X332556Y924370D01*
X332586Y924199D01*
X331208Y923955D01*
X331177Y924127D01*
G37*
G36*
G01X335206Y924277D02*
X335391Y924877D01*
X336421D01*
X336606Y924277D01*
Y924102D01*
X335206D01*
Y924277D01*
G37*
G36*
G01X336606Y925883D02*
X336421Y925283D01*
X335391D01*
X335206Y925883D01*
Y926058D01*
X336606D01*
Y925883D01*
G37*
G36*
G01D02*
X336421Y925283D01*
X335391D01*
X335206Y925883D01*
Y926058D01*
X336606D01*
Y925883D01*
G37*
G36*
G01X334792Y922679D02*
X334607Y922079D01*
X333577D01*
X333392Y922679D01*
Y922854D01*
X334792D01*
Y922679D01*
G37*
G36*
G01X338500D02*
X338315Y922079D01*
X337285D01*
X337100Y922679D01*
Y922854D01*
X338500D01*
Y922679D01*
G37*
G36*
G01X334792D02*
X334607Y922079D01*
X333577D01*
X333392Y922679D01*
Y922854D01*
X334792D01*
Y922679D01*
G37*
G36*
G01X338500D02*
X338315Y922079D01*
X337285D01*
X337100Y922679D01*
Y922854D01*
X338500D01*
Y922679D01*
G37*
G36*
G01X332953Y932293D02*
X332768Y931693D01*
X331738D01*
X331553Y932293D01*
Y932467D01*
X332953D01*
Y932293D01*
G37*
G36*
G01X336662Y932291D02*
X336477Y931691D01*
X335447D01*
X335262Y932291D01*
Y932466D01*
X336662D01*
Y932291D01*
G37*
G36*
G01X338375Y934130D02*
X338802Y933670D01*
X338287Y932778D01*
X337675Y932918D01*
X337524Y933005D01*
X338224Y934217D01*
X338375Y934130D01*
G37*
G36*
G01X332953Y932293D02*
X332768Y931693D01*
X331738D01*
X331553Y932293D01*
Y932467D01*
X332953D01*
Y932293D01*
G37*
G36*
G01X336662Y932291D02*
X336477Y931691D01*
X335447D01*
X335262Y932291D01*
Y932466D01*
X336662D01*
Y932291D01*
G37*
G36*
G01X338375Y934130D02*
X338802Y933670D01*
X338287Y932778D01*
X337675Y932918D01*
X337524Y933005D01*
X338224Y934217D01*
X338375Y934130D01*
G37*
G36*
G01X335196Y930685D02*
X335381Y931285D01*
X336411D01*
X336596Y930685D01*
Y930510D01*
X335196D01*
Y930685D01*
G37*
G36*
G01D02*
X335381Y931285D01*
X336411D01*
X336596Y930685D01*
Y930510D01*
X335196D01*
Y930685D01*
G37*
G36*
G01X334779Y929087D02*
X334594Y928487D01*
X333564D01*
X333379Y929087D01*
Y929262D01*
X334779D01*
Y929087D01*
G37*
G36*
G01X338513D02*
X338328Y928487D01*
X337298D01*
X337113Y929087D01*
Y929262D01*
X338513D01*
Y929087D01*
G37*
G36*
G01X334779D02*
X334594Y928487D01*
X333564D01*
X333379Y929087D01*
Y929262D01*
X334779D01*
Y929087D01*
G37*
G36*
G01X338513D02*
X338328Y928487D01*
X337298D01*
X337113Y929087D01*
Y929262D01*
X338513D01*
Y929087D01*
G37*
G36*
G01X333356Y921073D02*
X333541Y921673D01*
X334571D01*
X334756Y921073D01*
Y920898D01*
X333356D01*
Y921073D01*
G37*
G36*
G01X337058Y921071D02*
X337243Y921671D01*
X338273D01*
X338458Y921071D01*
Y920897D01*
X337058D01*
Y921071D01*
G37*
G36*
G01X333356Y921073D02*
X333541Y921673D01*
X334571D01*
X334756Y921073D01*
Y920898D01*
X333356D01*
Y921073D01*
G37*
G36*
G01X337058Y921071D02*
X337243Y921671D01*
X338273D01*
X338458Y921071D01*
Y920897D01*
X337058D01*
Y921071D01*
G37*
G36*
G01X335252Y917867D02*
X335437Y918467D01*
X336467D01*
X336652Y917867D01*
Y917692D01*
X335252D01*
Y917867D01*
G37*
G36*
G01D02*
X335437Y918467D01*
X336467D01*
X336652Y917867D01*
Y917692D01*
X335252D01*
Y917867D01*
G37*
G36*
G01X336650Y919475D02*
X336465Y918875D01*
X335435D01*
X335250Y919475D01*
Y919650D01*
X336650D01*
Y919475D01*
G37*
G36*
G01D02*
X336465Y918875D01*
X335435D01*
X335250Y919475D01*
Y919650D01*
X336650D01*
Y919475D01*
G37*
G36*
G01X334647Y940490D02*
X335074Y940030D01*
X334559Y939138D01*
X333947Y939278D01*
X333796Y939365D01*
X334496Y940577D01*
X334647Y940490D01*
G37*
G36*
G01X338512Y941903D02*
X338327Y941303D01*
X337297D01*
X337112Y941903D01*
Y942078D01*
X338512D01*
Y941903D01*
G37*
G36*
G01X334647Y940490D02*
X335074Y940030D01*
X334559Y939138D01*
X333947Y939278D01*
X333796Y939365D01*
X334496Y940577D01*
X334647Y940490D01*
G37*
G36*
G01X338512Y941903D02*
X338327Y941303D01*
X337297D01*
X337112Y941903D01*
Y942078D01*
X338512D01*
Y941903D01*
G37*
G36*
G01X334746Y935495D02*
X334561Y934895D01*
X333531D01*
X333346Y935495D01*
Y935670D01*
X334746D01*
Y935495D01*
G37*
G36*
G01X336515Y937314D02*
X336942Y936854D01*
X336427Y935962D01*
X335815Y936102D01*
X335664Y936189D01*
X336364Y937401D01*
X336515Y937314D01*
G37*
G36*
G01X334746Y935495D02*
X334561Y934895D01*
X333531D01*
X333346Y935495D01*
Y935670D01*
X334746D01*
Y935495D01*
G37*
G36*
G01X336515Y937314D02*
X336942Y936854D01*
X336427Y935962D01*
X335815Y936102D01*
X335664Y936189D01*
X336364Y937401D01*
X336515Y937314D01*
G37*
G36*
G01X333349Y946705D02*
X333534Y947305D01*
X334564D01*
X334749Y946705D01*
Y946531D01*
X333349D01*
Y946705D01*
G37*
G36*
G01X337050D02*
X337235Y947305D01*
X338265D01*
X338450Y946705D01*
Y946531D01*
X337050D01*
Y946705D01*
G37*
G36*
G01X333349D02*
X333534Y947305D01*
X334564D01*
X334749Y946705D01*
Y946531D01*
X333349D01*
Y946705D01*
G37*
G36*
G01X337050D02*
X337235Y947305D01*
X338265D01*
X338450Y946705D01*
Y946531D01*
X337050D01*
Y946705D01*
G37*
G36*
G01X338512Y948313D02*
X338327Y947713D01*
X337297D01*
X337112Y948313D01*
Y948487D01*
X338512D01*
Y948313D01*
G37*
G36*
G01D02*
X338327Y947713D01*
X337297D01*
X337112Y948313D01*
Y948487D01*
X338512D01*
Y948313D01*
G37*
G36*
G01X336647Y945107D02*
X336462Y944507D01*
X335432D01*
X335247Y945107D01*
Y945282D01*
X336647D01*
Y945107D01*
G37*
G36*
G01D02*
X336462Y944507D01*
X335432D01*
X335247Y945107D01*
Y945282D01*
X336647D01*
Y945107D01*
G37*
G36*
G01X333515Y941720D02*
X333088Y942180D01*
X333603Y943072D01*
X334215Y942932D01*
X334366Y942845D01*
X333666Y941633D01*
X333515Y941720D01*
G37*
G36*
G01X335195Y943501D02*
X335380Y944101D01*
X336410D01*
X336595Y943501D01*
Y943326D01*
X335195D01*
Y943501D01*
G37*
G36*
G01X333515Y941720D02*
X333088Y942180D01*
X333603Y943072D01*
X334215Y942932D01*
X334366Y942845D01*
X333666Y941633D01*
X333515Y941720D01*
G37*
G36*
G01X335195Y943501D02*
X335380Y944101D01*
X336410D01*
X336595Y943501D01*
Y943326D01*
X335195D01*
Y943501D01*
G37*
G36*
G01X337046Y940297D02*
X337231Y940897D01*
X338261D01*
X338446Y940297D01*
Y940122D01*
X337046D01*
Y940297D01*
G37*
G36*
G01D02*
X337231Y940897D01*
X338261D01*
X338446Y940297D01*
Y940122D01*
X337046D01*
Y940297D01*
G37*
G36*
G01X333345Y933889D02*
X333530Y934489D01*
X334560D01*
X334745Y933889D01*
Y933714D01*
X333345D01*
Y933889D01*
G37*
G36*
G01X337182Y935254D02*
X336755Y935714D01*
X337270Y936606D01*
X337882Y936466D01*
X338033Y936379D01*
X337333Y935167D01*
X337182Y935254D01*
G37*
G36*
G01X333345Y933889D02*
X333530Y934489D01*
X334560D01*
X334745Y933889D01*
Y933714D01*
X333345D01*
Y933889D01*
G37*
G36*
G01X337182Y935254D02*
X336755Y935714D01*
X337270Y936606D01*
X337882Y936466D01*
X338033Y936379D01*
X337333Y935167D01*
X337182Y935254D01*
G37*
G36*
G01X331528Y962725D02*
X331713Y963325D01*
X332743D01*
X332928Y962725D01*
Y962551D01*
X331528D01*
Y962725D01*
G37*
G36*
G01X335228D02*
X335413Y963325D01*
X336443D01*
X336628Y962725D01*
Y962551D01*
X335228D01*
Y962725D01*
G37*
G36*
G01X331528D02*
X331713Y963325D01*
X332743D01*
X332928Y962725D01*
Y962551D01*
X331528D01*
Y962725D01*
G37*
G36*
G01X335228D02*
X335413Y963325D01*
X336443D01*
X336628Y962725D01*
Y962551D01*
X335228D01*
Y962725D01*
G37*
G36*
G01X333345Y959523D02*
X333530Y960123D01*
X334560D01*
X334745Y959523D01*
Y959348D01*
X333345D01*
Y959523D01*
G37*
G36*
G01X337045D02*
X337230Y960123D01*
X338260D01*
X338445Y959523D01*
Y959348D01*
X337045D01*
Y959523D01*
G37*
G36*
G01X333345D02*
X333530Y960123D01*
X334560D01*
X334745Y959523D01*
Y959348D01*
X333345D01*
Y959523D01*
G37*
G36*
G01X337045D02*
X337230Y960123D01*
X338260D01*
X338445Y959523D01*
Y959348D01*
X337045D01*
Y959523D01*
G37*
G36*
G01X334778Y961131D02*
X334593Y960531D01*
X333563D01*
X333378Y961131D01*
Y961305D01*
X334778D01*
Y961131D01*
G37*
G36*
G01X338478D02*
X338293Y960531D01*
X337263D01*
X337078Y961131D01*
Y961305D01*
X338478D01*
Y961131D01*
G37*
G36*
G01X334778D02*
X334593Y960531D01*
X333563D01*
X333378Y961131D01*
Y961305D01*
X334778D01*
Y961131D01*
G37*
G36*
G01X338478D02*
X338293Y960531D01*
X337263D01*
X337078Y961131D01*
Y961305D01*
X338478D01*
Y961131D01*
G37*
G36*
G01X332962Y957925D02*
X332777Y957325D01*
X331747D01*
X331562Y957925D01*
Y958100D01*
X332962D01*
Y957925D01*
G37*
G36*
G01X336662D02*
X336477Y957325D01*
X335447D01*
X335262Y957925D01*
Y958100D01*
X336662D01*
Y957925D01*
G37*
G36*
G01X332962D02*
X332777Y957325D01*
X331747D01*
X331562Y957925D01*
Y958100D01*
X332962D01*
Y957925D01*
G37*
G36*
G01X336662D02*
X336477Y957325D01*
X335447D01*
X335262Y957925D01*
Y958100D01*
X336662D01*
Y957925D01*
G37*
G36*
G01X335195Y949909D02*
X335380Y950509D01*
X336410D01*
X336595Y949909D01*
Y949735D01*
X335195D01*
Y949909D01*
G37*
G36*
G01D02*
X335380Y950509D01*
X336410D01*
X336595Y949909D01*
Y949735D01*
X335195D01*
Y949909D01*
G37*
G36*
G01X334745Y954721D02*
X334560Y954121D01*
X333530D01*
X333345Y954721D01*
Y954895D01*
X334745D01*
Y954721D01*
G37*
G36*
G01X338455D02*
X338270Y954121D01*
X337240D01*
X337055Y954721D01*
Y954895D01*
X338455D01*
Y954721D01*
G37*
G36*
G01X334745D02*
X334560Y954121D01*
X333530D01*
X333345Y954721D01*
Y954895D01*
X334745D01*
Y954721D01*
G37*
G36*
G01X338455D02*
X338270Y954121D01*
X337240D01*
X337055Y954721D01*
Y954895D01*
X338455D01*
Y954721D01*
G37*
G36*
G01X337110Y953113D02*
X337295Y953713D01*
X338325D01*
X338510Y953113D01*
Y952939D01*
X337110D01*
Y953113D01*
G37*
G36*
G01D02*
X337295Y953713D01*
X338325D01*
X338510Y953113D01*
Y952939D01*
X337110D01*
Y953113D01*
G37*
G36*
G01X331562Y956319D02*
X331747Y956919D01*
X332777D01*
X332962Y956319D01*
Y956144D01*
X331562D01*
Y956319D01*
G37*
G36*
G01X335262D02*
X335447Y956919D01*
X336477D01*
X336662Y956319D01*
Y956144D01*
X335262D01*
Y956319D01*
G37*
G36*
G01X331562D02*
X331747Y956919D01*
X332777D01*
X332962Y956319D01*
Y956144D01*
X331562D01*
Y956319D01*
G37*
G36*
G01X335262D02*
X335447Y956919D01*
X336477D01*
X336662Y956319D01*
Y956144D01*
X335262D01*
Y956319D01*
G37*
G36*
G01X336573Y951517D02*
X336388Y950917D01*
X335358D01*
X335173Y951517D01*
Y951691D01*
X336573D01*
Y951517D01*
G37*
G36*
G01D02*
X336388Y950917D01*
X335358D01*
X335173Y951517D01*
Y951691D01*
X336573D01*
Y951517D01*
G37*
G36*
G01X332895Y964333D02*
X332710Y963733D01*
X331680D01*
X331495Y964333D01*
Y964508D01*
X332895D01*
Y964333D01*
G37*
G36*
G01X336595D02*
X336410Y963733D01*
X335380D01*
X335195Y964333D01*
Y964508D01*
X336595D01*
Y964333D01*
G37*
G36*
G01X332895D02*
X332710Y963733D01*
X331680D01*
X331495Y964333D01*
Y964508D01*
X332895D01*
Y964333D01*
G37*
G36*
G01X336595D02*
X336410Y963733D01*
X335380D01*
X335195Y964333D01*
Y964508D01*
X336595D01*
Y964333D01*
G37*
G36*
G01X338512Y980355D02*
X338327Y979755D01*
X337297D01*
X337112Y980355D01*
Y980530D01*
X338512D01*
Y980355D01*
G37*
G36*
G01D02*
X338327Y979755D01*
X337297D01*
X337112Y980355D01*
Y980530D01*
X338512D01*
Y980355D01*
G37*
G36*
G01X335229Y975543D02*
X335414Y976143D01*
X336444D01*
X336629Y975543D01*
Y975368D01*
X335229D01*
Y975543D01*
G37*
G36*
G01D02*
X335414Y976143D01*
X336444D01*
X336629Y975543D01*
Y975368D01*
X335229D01*
Y975543D01*
G37*
G36*
G01X334779Y973947D02*
X334594Y973347D01*
X333564D01*
X333379Y973947D01*
Y974122D01*
X334779D01*
Y973947D01*
G37*
G36*
G01X338479D02*
X338294Y973347D01*
X337264D01*
X337079Y973947D01*
Y974122D01*
X338479D01*
Y973947D01*
G37*
G36*
G01X334779D02*
X334594Y973347D01*
X333564D01*
X333379Y973947D01*
Y974122D01*
X334779D01*
Y973947D01*
G37*
G36*
G01X338479D02*
X338294Y973347D01*
X337264D01*
X337079Y973947D01*
Y974122D01*
X338479D01*
Y973947D01*
G37*
G36*
G01X333412Y965931D02*
X333597Y966531D01*
X334627D01*
X334812Y965931D01*
Y965757D01*
X333412D01*
Y965931D01*
G37*
G36*
G01X337112D02*
X337297Y966531D01*
X338327D01*
X338512Y965931D01*
Y965757D01*
X337112D01*
Y965931D01*
G37*
G36*
G01X333412D02*
X333597Y966531D01*
X334627D01*
X334812Y965931D01*
Y965757D01*
X333412D01*
Y965931D01*
G37*
G36*
G01X337112D02*
X337297Y966531D01*
X338327D01*
X338512Y965931D01*
Y965757D01*
X337112D01*
Y965931D01*
G37*
G36*
G01X331529Y969135D02*
X331714Y969735D01*
X332744D01*
X332929Y969135D01*
Y968960D01*
X331529D01*
Y969135D01*
G37*
G36*
G01X335229D02*
X335414Y969735D01*
X336444D01*
X336629Y969135D01*
Y968960D01*
X335229D01*
Y969135D01*
G37*
G36*
G01X331529D02*
X331714Y969735D01*
X332744D01*
X332929Y969135D01*
Y968960D01*
X331529D01*
Y969135D01*
G37*
G36*
G01X335229D02*
X335414Y969735D01*
X336444D01*
X336629Y969135D01*
Y968960D01*
X335229D01*
Y969135D01*
G37*
G36*
G01X334779Y967539D02*
X334594Y966939D01*
X333564D01*
X333379Y967539D01*
Y967714D01*
X334779D01*
Y967539D01*
G37*
G36*
G01X338479D02*
X338294Y966939D01*
X337264D01*
X337079Y967539D01*
Y967714D01*
X338479D01*
Y967539D01*
G37*
G36*
G01X334779D02*
X334594Y966939D01*
X333564D01*
X333379Y967539D01*
Y967714D01*
X334779D01*
Y967539D01*
G37*
G36*
G01X338479D02*
X338294Y966939D01*
X337264D01*
X337079Y967539D01*
Y967714D01*
X338479D01*
Y967539D01*
G37*
G36*
G01X337511Y1005289D02*
X337696Y1005889D01*
X338726D01*
X338911Y1005289D01*
Y1005114D01*
X337511D01*
Y1005289D01*
G37*
G36*
G01D02*
X337696Y1005889D01*
X338726D01*
X338911Y1005289D01*
Y1005114D01*
X337511D01*
Y1005289D01*
G37*
G36*
G01X333811Y1011697D02*
X333996Y1012297D01*
X335026D01*
X335211Y1011697D01*
Y1011522D01*
X333811D01*
Y1011697D01*
G37*
G36*
G01X337511D02*
X337696Y1012297D01*
X338726D01*
X338911Y1011697D01*
Y1011522D01*
X337511D01*
Y1011697D01*
G37*
G36*
G01X333811D02*
X333996Y1012297D01*
X335026D01*
X335211Y1011697D01*
Y1011522D01*
X333811D01*
Y1011697D01*
G37*
G36*
G01X337511D02*
X337696Y1012297D01*
X338726D01*
X338911Y1011697D01*
Y1011522D01*
X337511D01*
Y1011697D01*
G37*
G36*
G01X331961Y1008493D02*
X332146Y1009093D01*
X333176D01*
X333361Y1008493D01*
Y1008318D01*
X331961D01*
Y1008493D01*
G37*
G36*
G01X335661D02*
X335846Y1009093D01*
X336876D01*
X337061Y1008493D01*
Y1008318D01*
X335661D01*
Y1008493D01*
G37*
G36*
G01X331961D02*
X332146Y1009093D01*
X333176D01*
X333361Y1008493D01*
Y1008318D01*
X331961D01*
Y1008493D01*
G37*
G36*
G01X335661D02*
X335846Y1009093D01*
X336876D01*
X337061Y1008493D01*
Y1008318D01*
X335661D01*
Y1008493D01*
G37*
G36*
G01X333361Y1010101D02*
X333176Y1009501D01*
X332146D01*
X331961Y1010101D01*
Y1010276D01*
X333361D01*
Y1010101D01*
G37*
G36*
G01X337061D02*
X336876Y1009501D01*
X335846D01*
X335661Y1010101D01*
Y1010276D01*
X337061D01*
Y1010101D01*
G37*
G36*
G01X333361D02*
X333176Y1009501D01*
X332146D01*
X331961Y1010101D01*
Y1010276D01*
X333361D01*
Y1010101D01*
G37*
G36*
G01X337061D02*
X336876Y1009501D01*
X335846D01*
X335661Y1010101D01*
Y1010276D01*
X337061D01*
Y1010101D01*
G37*
G36*
G01X335211Y1006897D02*
X335026Y1006297D01*
X333996D01*
X333811Y1006897D01*
Y1007072D01*
X335211D01*
Y1006897D01*
G37*
G36*
G01X338911D02*
X338726Y1006297D01*
X337696D01*
X337511Y1006897D01*
Y1007072D01*
X338911D01*
Y1006897D01*
G37*
G36*
G01X335211D02*
X335026Y1006297D01*
X333996D01*
X333811Y1006897D01*
Y1007072D01*
X335211D01*
Y1006897D01*
G37*
G36*
G01X338911D02*
X338726Y1006297D01*
X337696D01*
X337511Y1006897D01*
Y1007072D01*
X338911D01*
Y1006897D01*
G37*
G36*
G01X333361Y1029327D02*
X333176Y1028727D01*
X332146D01*
X331961Y1029327D01*
Y1029502D01*
X333361D01*
Y1029327D01*
G37*
G36*
G01X337061D02*
X336876Y1028727D01*
X335846D01*
X335661Y1029327D01*
Y1029502D01*
X337061D01*
Y1029327D01*
G37*
G36*
G01X333361D02*
X333176Y1028727D01*
X332146D01*
X331961Y1029327D01*
Y1029502D01*
X333361D01*
Y1029327D01*
G37*
G36*
G01X337061D02*
X336876Y1028727D01*
X335846D01*
X335661Y1029327D01*
Y1029502D01*
X337061D01*
Y1029327D01*
G37*
G36*
G01X335211Y1019715D02*
X335026Y1019115D01*
X333996D01*
X333811Y1019715D01*
Y1019889D01*
X335211D01*
Y1019715D01*
G37*
G36*
G01X338911D02*
X338726Y1019115D01*
X337696D01*
X337511Y1019715D01*
Y1019889D01*
X338911D01*
Y1019715D01*
G37*
G36*
G01X335211D02*
X335026Y1019115D01*
X333996D01*
X333811Y1019715D01*
Y1019889D01*
X335211D01*
Y1019715D01*
G37*
G36*
G01X338911D02*
X338726Y1019115D01*
X337696D01*
X337511Y1019715D01*
Y1019889D01*
X338911D01*
Y1019715D01*
G37*
G36*
G01X337061Y1016509D02*
X336876Y1015909D01*
X335846D01*
X335661Y1016509D01*
Y1016684D01*
X337061D01*
Y1016509D01*
G37*
G36*
G01D02*
X336876Y1015909D01*
X335846D01*
X335661Y1016509D01*
Y1016684D01*
X337061D01*
Y1016509D01*
G37*
G36*
G01X335661Y1021309D02*
X335846Y1021909D01*
X336876D01*
X337061Y1021309D01*
Y1021135D01*
X335661D01*
Y1021309D01*
G37*
G36*
G01D02*
X335846Y1021909D01*
X336876D01*
X337061Y1021309D01*
Y1021135D01*
X335661D01*
Y1021309D01*
G37*
G36*
G01X333811Y1018105D02*
X333996Y1018705D01*
X335026D01*
X335211Y1018105D01*
Y1017931D01*
X333811D01*
Y1018105D01*
G37*
G36*
G01X337511D02*
X337696Y1018705D01*
X338726D01*
X338911Y1018105D01*
Y1017931D01*
X337511D01*
Y1018105D01*
G37*
G36*
G01X333811D02*
X333996Y1018705D01*
X335026D01*
X335211Y1018105D01*
Y1017931D01*
X333811D01*
Y1018105D01*
G37*
G36*
G01X337511D02*
X337696Y1018705D01*
X338726D01*
X338911Y1018105D01*
Y1017931D01*
X337511D01*
Y1018105D01*
G37*
G36*
G01X333361Y1022919D02*
X333176Y1022319D01*
X332146D01*
X331961Y1022919D01*
Y1023093D01*
X333361D01*
Y1022919D01*
G37*
G36*
G01X337061D02*
X336876Y1022319D01*
X335846D01*
X335661Y1022919D01*
Y1023093D01*
X337061D01*
Y1022919D01*
G37*
G36*
G01X333361D02*
X333176Y1022319D01*
X332146D01*
X331961Y1022919D01*
Y1023093D01*
X333361D01*
Y1022919D01*
G37*
G36*
G01X337061D02*
X336876Y1022319D01*
X335846D01*
X335661Y1022919D01*
Y1023093D01*
X337061D01*
Y1022919D01*
G37*
G36*
G01X331961Y1027719D02*
X332146Y1028319D01*
X333176D01*
X333361Y1027719D01*
Y1027544D01*
X331961D01*
Y1027719D01*
G37*
G36*
G01X335661D02*
X335846Y1028319D01*
X336876D01*
X337061Y1027719D01*
Y1027544D01*
X335661D01*
Y1027719D01*
G37*
G36*
G01X331961D02*
X332146Y1028319D01*
X333176D01*
X333361Y1027719D01*
Y1027544D01*
X331961D01*
Y1027719D01*
G37*
G36*
G01X335661D02*
X335846Y1028319D01*
X336876D01*
X337061Y1027719D01*
Y1027544D01*
X335661D01*
Y1027719D01*
G37*
G36*
G01X333811Y1024513D02*
X333996Y1025113D01*
X335026D01*
X335211Y1024513D01*
Y1024339D01*
X333811D01*
Y1024513D01*
G37*
G36*
G01X337511D02*
X337696Y1025113D01*
X338726D01*
X338911Y1024513D01*
Y1024339D01*
X337511D01*
Y1024513D01*
G37*
G36*
G01X333811D02*
X333996Y1025113D01*
X335026D01*
X335211Y1024513D01*
Y1024339D01*
X333811D01*
Y1024513D01*
G37*
G36*
G01X337511D02*
X337696Y1025113D01*
X338726D01*
X338911Y1024513D01*
Y1024339D01*
X337511D01*
Y1024513D01*
G37*
G36*
G01X335211Y1026123D02*
X335026Y1025523D01*
X333996D01*
X333811Y1026123D01*
Y1026297D01*
X335211D01*
Y1026123D01*
G37*
G36*
G01X338911D02*
X338726Y1025523D01*
X337696D01*
X337511Y1026123D01*
Y1026297D01*
X338911D01*
Y1026123D01*
G37*
G36*
G01X335211D02*
X335026Y1025523D01*
X333996D01*
X333811Y1026123D01*
Y1026297D01*
X335211D01*
Y1026123D01*
G37*
G36*
G01X338911D02*
X338726Y1025523D01*
X337696D01*
X337511Y1026123D01*
Y1026297D01*
X338911D01*
Y1026123D01*
G37*
G36*
G01X335211Y1032531D02*
X335026Y1031931D01*
X333996D01*
X333811Y1032531D01*
Y1032706D01*
X335211D01*
Y1032531D01*
G37*
G36*
G01X338911D02*
X338726Y1031931D01*
X337696D01*
X337511Y1032531D01*
Y1032706D01*
X338911D01*
Y1032531D01*
G37*
G36*
G01X335211D02*
X335026Y1031931D01*
X333996D01*
X333811Y1032531D01*
Y1032706D01*
X335211D01*
Y1032531D01*
G37*
G36*
G01X338911D02*
X338726Y1031931D01*
X337696D01*
X337511Y1032531D01*
Y1032706D01*
X338911D01*
Y1032531D01*
G37*
G36*
G01X335661Y1034127D02*
X335846Y1034727D01*
X336876D01*
X337061Y1034127D01*
Y1033952D01*
X335661D01*
Y1034127D01*
G37*
G36*
G01D02*
X335846Y1034727D01*
X336876D01*
X337061Y1034127D01*
Y1033952D01*
X335661D01*
Y1034127D01*
G37*
G36*
G01X333811Y1030923D02*
X333996Y1031523D01*
X335026D01*
X335211Y1030923D01*
Y1030748D01*
X333811D01*
Y1030923D01*
G37*
G36*
G01X337511D02*
X337696Y1031523D01*
X338726D01*
X338911Y1030923D01*
Y1030748D01*
X337511D01*
Y1030923D01*
G37*
G36*
G01X333811D02*
X333996Y1031523D01*
X335026D01*
X335211Y1030923D01*
Y1030748D01*
X333811D01*
Y1030923D01*
G37*
G36*
G01X337511D02*
X337696Y1031523D01*
X338726D01*
X338911Y1030923D01*
Y1030748D01*
X337511D01*
Y1030923D01*
G37*
G36*
G01X335661Y1040535D02*
X335846Y1041135D01*
X336876D01*
X337061Y1040535D01*
Y1040361D01*
X335661D01*
Y1040535D01*
G37*
G36*
G01D02*
X335846Y1041135D01*
X336876D01*
X337061Y1040535D01*
Y1040361D01*
X335661D01*
Y1040535D01*
G37*
G36*
G01X333811Y1037331D02*
X333996Y1037931D01*
X335026D01*
X335211Y1037331D01*
Y1037157D01*
X333811D01*
Y1037331D01*
G37*
G36*
G01X337511D02*
X337696Y1037931D01*
X338726D01*
X338911Y1037331D01*
Y1037157D01*
X337511D01*
Y1037331D01*
G37*
G36*
G01X333811D02*
X333996Y1037931D01*
X335026D01*
X335211Y1037331D01*
Y1037157D01*
X333811D01*
Y1037331D01*
G37*
G36*
G01X337511D02*
X337696Y1037931D01*
X338726D01*
X338911Y1037331D01*
Y1037157D01*
X337511D01*
Y1037331D01*
G37*
G36*
G01X335211Y1038941D02*
X335026Y1038341D01*
X333996D01*
X333811Y1038941D01*
Y1039115D01*
X335211D01*
Y1038941D01*
G37*
G36*
G01X338911D02*
X338726Y1038341D01*
X337696D01*
X337511Y1038941D01*
Y1039115D01*
X338911D01*
Y1038941D01*
G37*
G36*
G01X335211D02*
X335026Y1038341D01*
X333996D01*
X333811Y1038941D01*
Y1039115D01*
X335211D01*
Y1038941D01*
G37*
G36*
G01X338911D02*
X338726Y1038341D01*
X337696D01*
X337511Y1038941D01*
Y1039115D01*
X338911D01*
Y1038941D01*
G37*
G36*
G01X337061Y1035735D02*
X336876Y1035135D01*
X335846D01*
X335661Y1035735D01*
Y1035910D01*
X337061D01*
Y1035735D01*
G37*
G36*
G01D02*
X336876Y1035135D01*
X335846D01*
X335661Y1035735D01*
Y1035910D01*
X337061D01*
Y1035735D01*
G37*
G36*
G01X338911Y1045349D02*
X338726Y1044749D01*
X337696D01*
X337511Y1045349D01*
Y1045523D01*
X338911D01*
Y1045349D01*
G37*
G36*
G01D02*
X338726Y1044749D01*
X337696D01*
X337511Y1045349D01*
Y1045523D01*
X338911D01*
Y1045349D01*
G37*
G36*
G01X337511Y1043739D02*
X337696Y1044339D01*
X338726D01*
X338911Y1043739D01*
Y1043565D01*
X337511D01*
Y1043739D01*
G37*
G36*
G01D02*
X337696Y1044339D01*
X338726D01*
X338911Y1043739D01*
Y1043565D01*
X337511D01*
Y1043739D01*
G37*
G36*
G01X334643Y1042722D02*
X334031Y1042582D01*
X333516Y1043474D01*
X333943Y1043934D01*
X334094Y1044021D01*
X334794Y1042809D01*
X334643Y1042722D01*
G37*
G36*
G01X337061Y1042145D02*
X336876Y1041545D01*
X335846D01*
X335661Y1042145D01*
Y1042319D01*
X337061D01*
Y1042145D01*
G37*
G36*
G01X334643Y1042722D02*
X334031Y1042582D01*
X333516Y1043474D01*
X333943Y1043934D01*
X334094Y1044021D01*
X334794Y1042809D01*
X334643Y1042722D01*
G37*
G36*
G01X337061Y1042145D02*
X336876Y1041545D01*
X335846D01*
X335661Y1042145D01*
Y1042319D01*
X337061D01*
Y1042145D01*
G37*
G36*
G01X338343Y1055539D02*
X337731Y1055399D01*
X337216Y1056291D01*
X337643Y1056751D01*
X337794Y1056838D01*
X338494Y1055626D01*
X338343Y1055539D01*
G37*
G36*
G01D02*
X337731Y1055399D01*
X337216Y1056291D01*
X337643Y1056751D01*
X337794Y1056838D01*
X338494Y1055626D01*
X338343Y1055539D01*
G37*
G36*
G01X336229Y1055979D02*
X336841Y1056119D01*
X337356Y1055227D01*
X336929Y1054767D01*
X336778Y1054680D01*
X336078Y1055892D01*
X336229Y1055979D01*
G37*
G36*
G01D02*
X336841Y1056119D01*
X337356Y1055227D01*
X336929Y1054767D01*
X336778Y1054680D01*
X336078Y1055892D01*
X336229Y1055979D01*
G37*
G36*
G01X334371Y1052790D02*
X334983Y1052930D01*
X335498Y1052038D01*
X335071Y1051578D01*
X334920Y1051491D01*
X334220Y1052703D01*
X334371Y1052790D01*
G37*
G36*
G01X337511Y1050149D02*
X337696Y1050749D01*
X338726D01*
X338911Y1050149D01*
Y1049974D01*
X337511D01*
Y1050149D01*
G37*
G36*
G01X334371Y1052790D02*
X334983Y1052930D01*
X335498Y1052038D01*
X335071Y1051578D01*
X334920Y1051491D01*
X334220Y1052703D01*
X334371Y1052790D01*
G37*
G36*
G01X337511Y1050149D02*
X337696Y1050749D01*
X338726D01*
X338911Y1050149D01*
Y1049974D01*
X337511D01*
Y1050149D01*
G37*
G36*
G01X338911Y1051757D02*
X338726Y1051157D01*
X337696D01*
X337511Y1051757D01*
Y1051931D01*
X338911D01*
Y1051757D01*
G37*
G36*
G01X336501Y1052319D02*
X335889Y1052179D01*
X335374Y1053071D01*
X335801Y1053531D01*
X335952Y1053618D01*
X336652Y1052406D01*
X336501Y1052319D01*
G37*
G36*
G01X338911Y1051757D02*
X338726Y1051157D01*
X337696D01*
X337511Y1051757D01*
Y1051931D01*
X338911D01*
Y1051757D01*
G37*
G36*
G01X336501Y1052319D02*
X335889Y1052179D01*
X335374Y1053071D01*
X335801Y1053531D01*
X335952Y1053618D01*
X336652Y1052406D01*
X336501Y1052319D01*
G37*
G36*
G01X338945Y1077391D02*
X338760Y1076791D01*
X337730D01*
X337545Y1077391D01*
Y1077565D01*
X338945D01*
Y1077391D01*
G37*
G36*
G01D02*
X338760Y1076791D01*
X337730D01*
X337545Y1077391D01*
Y1077565D01*
X338945D01*
Y1077391D01*
G37*
G36*
G01X337038Y1074187D02*
X336853Y1073587D01*
X335823D01*
X335638Y1074187D01*
Y1074362D01*
X337038D01*
Y1074187D01*
G37*
G36*
G01D02*
X336853Y1073587D01*
X335823D01*
X335638Y1074187D01*
Y1074362D01*
X337038D01*
Y1074187D01*
G37*
G36*
G01X337545Y1075783D02*
X337730Y1076383D01*
X338760D01*
X338945Y1075783D01*
Y1075609D01*
X337545D01*
Y1075783D01*
G37*
G36*
G01D02*
X337730Y1076383D01*
X338760D01*
X338945Y1075783D01*
Y1075609D01*
X337545D01*
Y1075783D01*
G37*
G36*
G01X338347Y1068349D02*
X337735Y1068209D01*
X337220Y1069101D01*
X337647Y1069561D01*
X337798Y1069648D01*
X338498Y1068436D01*
X338347Y1068349D01*
G37*
G36*
G01D02*
X337735Y1068209D01*
X337220Y1069101D01*
X337647Y1069561D01*
X337798Y1069648D01*
X338498Y1068436D01*
X338347Y1068349D01*
G37*
G36*
G01X336229Y1068796D02*
X336841Y1068936D01*
X337356Y1068044D01*
X336929Y1067584D01*
X336778Y1067497D01*
X336078Y1068709D01*
X336229Y1068796D01*
G37*
G36*
G01D02*
X336841Y1068936D01*
X337356Y1068044D01*
X336929Y1067584D01*
X336778Y1067497D01*
X336078Y1068709D01*
X336229Y1068796D01*
G37*
G36*
G01X337544Y1088600D02*
X337729Y1089200D01*
X338759D01*
X338944Y1088600D01*
Y1088426D01*
X337544D01*
Y1088600D01*
G37*
G36*
G01D02*
X337729Y1089200D01*
X338759D01*
X338944Y1088600D01*
Y1088426D01*
X337544D01*
Y1088600D01*
G37*
G36*
G01X338325Y1081201D02*
X337713Y1081061D01*
X337198Y1081953D01*
X337625Y1082413D01*
X337776Y1082500D01*
X338476Y1081288D01*
X338325Y1081201D01*
G37*
G36*
G01D02*
X337713Y1081061D01*
X337198Y1081953D01*
X337625Y1082413D01*
X337776Y1082500D01*
X338476Y1081288D01*
X338325Y1081201D01*
G37*
G36*
G01X338343Y1100399D02*
X337731Y1100259D01*
X337216Y1101151D01*
X337643Y1101611D01*
X337794Y1101698D01*
X338494Y1100486D01*
X338343Y1100399D01*
G37*
G36*
G01D02*
X337731Y1100259D01*
X337216Y1101151D01*
X337643Y1101611D01*
X337794Y1101698D01*
X338494Y1100486D01*
X338343Y1100399D01*
G37*
G36*
G01X340779Y882619D02*
X340964Y883219D01*
X341994D01*
X342179Y882619D01*
Y882444D01*
X340779D01*
Y882619D01*
G37*
G36*
G01X344479D02*
X344664Y883219D01*
X345694D01*
X345879Y882619D01*
Y882444D01*
X344479D01*
Y882619D01*
G37*
G36*
G01X348311Y884033D02*
X347884Y884493D01*
X348399Y885385D01*
X349011Y885245D01*
X349162Y885158D01*
X348462Y883946D01*
X348311Y884033D01*
G37*
G36*
G01X340779Y882619D02*
X340964Y883219D01*
X341994D01*
X342179Y882619D01*
Y882444D01*
X340779D01*
Y882619D01*
G37*
G36*
G01X344479D02*
X344664Y883219D01*
X345694D01*
X345879Y882619D01*
Y882444D01*
X344479D01*
Y882619D01*
G37*
G36*
G01X348311Y884033D02*
X347884Y884493D01*
X348399Y885385D01*
X349011Y885245D01*
X349162Y885158D01*
X348462Y883946D01*
X348311Y884033D01*
G37*
G36*
G01X342179Y877819D02*
X341994Y877219D01*
X340964D01*
X340779Y877819D01*
Y877993D01*
X342179D01*
Y877819D01*
G37*
G36*
G01X345903Y877817D02*
X345718Y877217D01*
X344688D01*
X344503Y877817D01*
Y877992D01*
X345903D01*
Y877817D01*
G37*
G36*
G01X349612D02*
X349427Y877217D01*
X348397D01*
X348212Y877817D01*
Y877992D01*
X349612D01*
Y877817D01*
G37*
G36*
G01X353147Y882813D02*
X353574Y882353D01*
X353059Y881461D01*
X352447Y881601D01*
X352296Y881688D01*
X352996Y882900D01*
X353147Y882813D01*
G37*
G36*
G01X342179Y877819D02*
X341994Y877219D01*
X340964D01*
X340779Y877819D01*
Y877993D01*
X342179D01*
Y877819D01*
G37*
G36*
G01X345903Y877817D02*
X345718Y877217D01*
X344688D01*
X344503Y877817D01*
Y877992D01*
X345903D01*
Y877817D01*
G37*
G36*
G01X349612D02*
X349427Y877217D01*
X348397D01*
X348212Y877817D01*
Y877992D01*
X349612D01*
Y877817D01*
G37*
G36*
G01X353147Y882813D02*
X353574Y882353D01*
X353059Y881461D01*
X352447Y881601D01*
X352296Y881688D01*
X352996Y882900D01*
X353147Y882813D01*
G37*
G36*
G01X340329Y881023D02*
X340144Y880423D01*
X339114D01*
X338929Y881023D01*
Y881198D01*
X340329D01*
Y881023D01*
G37*
G36*
G01X344029D02*
X343844Y880423D01*
X342814D01*
X342629Y881023D01*
Y881198D01*
X344029D01*
Y881023D01*
G37*
G36*
G01X347705D02*
X347520Y880423D01*
X346490D01*
X346305Y881023D01*
Y881198D01*
X347705D01*
Y881023D01*
G37*
G36*
G01X340329D02*
X340144Y880423D01*
X339114D01*
X338929Y881023D01*
Y881198D01*
X340329D01*
Y881023D01*
G37*
G36*
G01X344029D02*
X343844Y880423D01*
X342814D01*
X342629Y881023D01*
Y881198D01*
X344029D01*
Y881023D01*
G37*
G36*
G01X347705D02*
X347520Y880423D01*
X346490D01*
X346305Y881023D01*
Y881198D01*
X347705D01*
Y881023D01*
G37*
G36*
G01X338929Y879415D02*
X339114Y880015D01*
X340144D01*
X340329Y879415D01*
Y879240D01*
X338929D01*
Y879415D01*
G37*
G36*
G01X342629D02*
X342814Y880015D01*
X343844D01*
X344029Y879415D01*
Y879240D01*
X342629D01*
Y879415D01*
G37*
G36*
G01X346296D02*
X346481Y880015D01*
X347511D01*
X347696Y879415D01*
Y879241D01*
X346296D01*
Y879415D01*
G37*
G36*
G01X352010Y884033D02*
X351583Y884493D01*
X352098Y885385D01*
X352710Y885245D01*
X352861Y885158D01*
X352161Y883946D01*
X352010Y884033D01*
G37*
G36*
G01X338929Y879415D02*
X339114Y880015D01*
X340144D01*
X340329Y879415D01*
Y879240D01*
X338929D01*
Y879415D01*
G37*
G36*
G01X342629D02*
X342814Y880015D01*
X343844D01*
X344029Y879415D01*
Y879240D01*
X342629D01*
Y879415D01*
G37*
G36*
G01X352010Y884033D02*
X351583Y884493D01*
X352098Y885385D01*
X352710Y885245D01*
X352861Y885158D01*
X352161Y883946D01*
X352010Y884033D01*
G37*
G36*
G01X350131Y880779D02*
X349704Y881239D01*
X350219Y882131D01*
X350831Y881991D01*
X350982Y881904D01*
X350282Y880692D01*
X350131Y880779D01*
G37*
G36*
G01X342179Y884227D02*
X341994Y883627D01*
X340964D01*
X340779Y884227D01*
Y884402D01*
X342179D01*
Y884227D01*
G37*
G36*
G01X345879D02*
X345694Y883627D01*
X344664D01*
X344479Y884227D01*
Y884402D01*
X345879D01*
Y884227D01*
G37*
G36*
G01X342179D02*
X341994Y883627D01*
X340964D01*
X340779Y884227D01*
Y884402D01*
X342179D01*
Y884227D01*
G37*
G36*
G01X345879D02*
X345694Y883627D01*
X344664D01*
X344479Y884227D01*
Y884402D01*
X345879D01*
Y884227D01*
G37*
G36*
G01X343892Y898827D02*
X344319Y898367D01*
X343804Y897475D01*
X343192Y897615D01*
X343041Y897702D01*
X343741Y898914D01*
X343892Y898827D01*
G37*
G36*
G01X347705Y900249D02*
X347520Y899649D01*
X346490D01*
X346305Y900249D01*
Y900424D01*
X347705D01*
Y900249D01*
G37*
G36*
G01X342064Y895658D02*
X342491Y895198D01*
X341976Y894306D01*
X341364Y894446D01*
X341213Y894533D01*
X341913Y895745D01*
X342064Y895658D01*
G37*
G36*
G01X351395Y900249D02*
X351210Y899649D01*
X350180D01*
X349995Y900249D01*
Y900423D01*
X351395D01*
Y900249D01*
G37*
G36*
G01X340305Y893841D02*
X340120Y893241D01*
X339090D01*
X338905Y893841D01*
Y894015D01*
X340305D01*
Y893841D01*
G37*
G36*
G01X355095Y900249D02*
X354910Y899649D01*
X353880D01*
X353695Y900249D01*
Y900423D01*
X355095D01*
Y900249D01*
G37*
G36*
G01X343892Y898827D02*
X344319Y898367D01*
X343804Y897475D01*
X343192Y897615D01*
X343041Y897702D01*
X343741Y898914D01*
X343892Y898827D01*
G37*
G36*
G01X347705Y900249D02*
X347520Y899649D01*
X346490D01*
X346305Y900249D01*
Y900424D01*
X347705D01*
Y900249D01*
G37*
G36*
G01X342064Y895658D02*
X342491Y895198D01*
X341976Y894306D01*
X341364Y894446D01*
X341213Y894533D01*
X341913Y895745D01*
X342064Y895658D01*
G37*
G36*
G01X351395Y900249D02*
X351210Y899649D01*
X350180D01*
X349995Y900249D01*
Y900423D01*
X351395D01*
Y900249D01*
G37*
G36*
G01X340305Y893841D02*
X340120Y893241D01*
X339090D01*
X338905Y893841D01*
Y894015D01*
X340305D01*
Y893841D01*
G37*
G36*
G01X355095Y900249D02*
X354910Y899649D01*
X353880D01*
X353695Y900249D01*
Y900423D01*
X355095D01*
Y900249D01*
G37*
G36*
G01X344608Y896847D02*
X344181Y897307D01*
X344696Y898199D01*
X345308Y898059D01*
X345459Y897972D01*
X344759Y896760D01*
X344608Y896847D01*
G37*
G36*
G01X346305Y898641D02*
X346490Y899241D01*
X347520D01*
X347705Y898641D01*
Y898466D01*
X346305D01*
Y898641D01*
G37*
G36*
G01X349995D02*
X350180Y899241D01*
X351210D01*
X351395Y898641D01*
Y898467D01*
X349995D01*
Y898641D01*
G37*
G36*
G01X342743Y893617D02*
X342316Y894077D01*
X342831Y894969D01*
X343443Y894829D01*
X343594Y894742D01*
X342894Y893530D01*
X342743Y893617D01*
G37*
G36*
G01X338905Y892231D02*
X339090Y892831D01*
X340120D01*
X340305Y892231D01*
Y892057D01*
X338905D01*
Y892231D01*
G37*
G36*
G01X353695Y898641D02*
X353880Y899241D01*
X354910D01*
X355095Y898641D01*
Y898467D01*
X353695D01*
Y898641D01*
G37*
G36*
G01X344608Y896847D02*
X344181Y897307D01*
X344696Y898199D01*
X345308Y898059D01*
X345459Y897972D01*
X344759Y896760D01*
X344608Y896847D01*
G37*
G36*
G01X346305Y898641D02*
X346490Y899241D01*
X347520D01*
X347705Y898641D01*
Y898466D01*
X346305D01*
Y898641D01*
G37*
G36*
G01X349995D02*
X350180Y899241D01*
X351210D01*
X351395Y898641D01*
Y898467D01*
X349995D01*
Y898641D01*
G37*
G36*
G01X342743Y893617D02*
X342316Y894077D01*
X342831Y894969D01*
X343443Y894829D01*
X343594Y894742D01*
X342894Y893530D01*
X342743Y893617D01*
G37*
G36*
G01X338905Y892231D02*
X339090Y892831D01*
X340120D01*
X340305Y892231D01*
Y892057D01*
X338905D01*
Y892231D01*
G37*
G36*
G01X353695Y898641D02*
X353880Y899241D01*
X354910D01*
X355095Y898641D01*
Y898467D01*
X353695D01*
Y898641D01*
G37*
G36*
G01X340914Y896858D02*
X340487Y897318D01*
X341002Y898210D01*
X341614Y898070D01*
X341765Y897983D01*
X341065Y896771D01*
X340914Y896858D01*
G37*
G36*
G01X342766Y900065D02*
X342339Y900525D01*
X342854Y901417D01*
X343466Y901277D01*
X343617Y901190D01*
X342917Y899978D01*
X342766Y900065D01*
G37*
G36*
G01X340914Y896858D02*
X340487Y897318D01*
X341002Y898210D01*
X341614Y898070D01*
X341765Y897983D01*
X341065Y896771D01*
X340914Y896858D01*
G37*
G36*
G01X342766Y900065D02*
X342339Y900525D01*
X342854Y901417D01*
X343466Y901277D01*
X343617Y901190D01*
X342917Y899978D01*
X342766Y900065D01*
G37*
G36*
G01X349612Y897043D02*
X349427Y896443D01*
X348397D01*
X348212Y897043D01*
Y897218D01*
X349612D01*
Y897043D01*
G37*
G36*
G01X345764Y895659D02*
X346191Y895199D01*
X345676Y894307D01*
X345064Y894447D01*
X344913Y894534D01*
X345613Y895746D01*
X345764Y895659D01*
G37*
G36*
G01X343921Y892466D02*
X344348Y892006D01*
X343833Y891114D01*
X343221Y891254D01*
X343070Y891341D01*
X343770Y892553D01*
X343921Y892466D01*
G37*
G36*
G01X342202Y890637D02*
X342017Y890037D01*
X340987D01*
X340802Y890637D01*
Y890811D01*
X342202D01*
Y890637D01*
G37*
G36*
G01X353312Y897043D02*
X353127Y896443D01*
X352097D01*
X351912Y897043D01*
Y897218D01*
X353312D01*
Y897043D01*
G37*
G36*
G01X349612D02*
X349427Y896443D01*
X348397D01*
X348212Y897043D01*
Y897218D01*
X349612D01*
Y897043D01*
G37*
G36*
G01X345764Y895659D02*
X346191Y895199D01*
X345676Y894307D01*
X345064Y894447D01*
X344913Y894534D01*
X345613Y895746D01*
X345764Y895659D01*
G37*
G36*
G01X343921Y892466D02*
X344348Y892006D01*
X343833Y891114D01*
X343221Y891254D01*
X343070Y891341D01*
X343770Y892553D01*
X343921Y892466D01*
G37*
G36*
G01X342202Y890637D02*
X342017Y890037D01*
X340987D01*
X340802Y890637D01*
Y890811D01*
X342202D01*
Y890637D01*
G37*
G36*
G01X353312Y897043D02*
X353127Y896443D01*
X352097D01*
X351912Y897043D01*
Y897218D01*
X353312D01*
Y897043D01*
G37*
G36*
G01X350164Y887245D02*
X349737Y887705D01*
X350252Y888597D01*
X350864Y888457D01*
X351015Y888370D01*
X350315Y887158D01*
X350164Y887245D01*
G37*
G36*
G01X351912Y889029D02*
X352097Y889629D01*
X353127D01*
X353312Y889029D01*
Y888854D01*
X351912D01*
Y889029D01*
G37*
G36*
G01X350164Y887245D02*
X349737Y887705D01*
X350252Y888597D01*
X350864Y888457D01*
X351015Y888370D01*
X350315Y887158D01*
X350164Y887245D01*
G37*
G36*
G01X351912Y889029D02*
X352097Y889629D01*
X353127D01*
X353312Y889029D01*
Y888854D01*
X351912D01*
Y889029D01*
G37*
G36*
G01X351297Y886017D02*
X351724Y885557D01*
X351209Y884665D01*
X350597Y884805D01*
X350446Y884892D01*
X351146Y886104D01*
X351297Y886017D01*
G37*
G36*
G01X355095Y887431D02*
X354910Y886831D01*
X353880D01*
X353695Y887431D01*
Y887605D01*
X355095D01*
Y887431D01*
G37*
G36*
G01X351297Y886017D02*
X351724Y885557D01*
X351209Y884665D01*
X350597Y884805D01*
X350446Y884892D01*
X351146Y886104D01*
X351297Y886017D01*
G37*
G36*
G01X355095Y887431D02*
X354910Y886831D01*
X353880D01*
X353695Y887431D01*
Y887605D01*
X355095D01*
Y887431D01*
G37*
G36*
G01X347597Y892426D02*
X348024Y891966D01*
X347509Y891074D01*
X346897Y891214D01*
X346746Y891301D01*
X347446Y892513D01*
X347597Y892426D01*
G37*
G36*
G01X340329Y887431D02*
X340144Y886831D01*
X339114D01*
X338929Y887431D01*
Y887606D01*
X340329D01*
Y887431D01*
G37*
G36*
G01X345743Y889214D02*
X346170Y888754D01*
X345655Y887862D01*
X345043Y888002D01*
X344892Y888089D01*
X345592Y889301D01*
X345743Y889214D01*
G37*
G36*
G01X344062Y887431D02*
X343877Y886831D01*
X342847D01*
X342662Y887431D01*
Y887605D01*
X344062D01*
Y887431D01*
G37*
G36*
G01X351395Y893839D02*
X351210Y893239D01*
X350180D01*
X349995Y893839D01*
Y894014D01*
X351395D01*
Y893839D01*
G37*
G36*
G01X355095D02*
X354910Y893239D01*
X353880D01*
X353695Y893839D01*
Y894014D01*
X355095D01*
Y893839D01*
G37*
G36*
G01X347597Y892426D02*
X348024Y891966D01*
X347509Y891074D01*
X346897Y891214D01*
X346746Y891301D01*
X347446Y892513D01*
X347597Y892426D01*
G37*
G36*
G01X340329Y887431D02*
X340144Y886831D01*
X339114D01*
X338929Y887431D01*
Y887606D01*
X340329D01*
Y887431D01*
G37*
G36*
G01X345743Y889214D02*
X346170Y888754D01*
X345655Y887862D01*
X345043Y888002D01*
X344892Y888089D01*
X345592Y889301D01*
X345743Y889214D01*
G37*
G36*
G01X344062Y887431D02*
X343877Y886831D01*
X342847D01*
X342662Y887431D01*
Y887605D01*
X344062D01*
Y887431D01*
G37*
G36*
G01X351395Y893839D02*
X351210Y893239D01*
X350180D01*
X349995Y893839D01*
Y894014D01*
X351395D01*
Y893839D01*
G37*
G36*
G01X355095D02*
X354910Y893239D01*
X353880D01*
X353695Y893839D01*
Y894014D01*
X355095D01*
Y893839D01*
G37*
G36*
G01X346469Y887253D02*
X346042Y887713D01*
X346557Y888605D01*
X347169Y888465D01*
X347320Y888378D01*
X346620Y887166D01*
X346469Y887253D01*
G37*
G36*
G01X348315Y890452D02*
X347888Y890912D01*
X348403Y891804D01*
X349015Y891664D01*
X349166Y891577D01*
X348466Y890365D01*
X348315Y890452D01*
G37*
G36*
G01X349995Y892233D02*
X350180Y892833D01*
X351210D01*
X351395Y892233D01*
Y892058D01*
X349995D01*
Y892233D01*
G37*
G36*
G01X338929Y885823D02*
X339114Y886423D01*
X340144D01*
X340329Y885823D01*
Y885648D01*
X338929D01*
Y885823D01*
G37*
G36*
G01X342629D02*
X342814Y886423D01*
X343844D01*
X344029Y885823D01*
Y885648D01*
X342629D01*
Y885823D01*
G37*
G36*
G01X353695Y892233D02*
X353880Y892833D01*
X354910D01*
X355095Y892233D01*
Y892058D01*
X353695D01*
Y892233D01*
G37*
G36*
G01X346469Y887253D02*
X346042Y887713D01*
X346557Y888605D01*
X347169Y888465D01*
X347320Y888378D01*
X346620Y887166D01*
X346469Y887253D01*
G37*
G36*
G01X348315Y890452D02*
X347888Y890912D01*
X348403Y891804D01*
X349015Y891664D01*
X349166Y891577D01*
X348466Y890365D01*
X348315Y890452D01*
G37*
G36*
G01X349995Y892233D02*
X350180Y892833D01*
X351210D01*
X351395Y892233D01*
Y892058D01*
X349995D01*
Y892233D01*
G37*
G36*
G01X338929Y885823D02*
X339114Y886423D01*
X340144D01*
X340329Y885823D01*
Y885648D01*
X338929D01*
Y885823D01*
G37*
G36*
G01X342629D02*
X342814Y886423D01*
X343844D01*
X344029Y885823D01*
Y885648D01*
X342629D01*
Y885823D01*
G37*
G36*
G01X353695Y892233D02*
X353880Y892833D01*
X354910D01*
X355095Y892233D01*
Y892058D01*
X353695D01*
Y892233D01*
G37*
G36*
G01X348212Y895437D02*
X348397Y896037D01*
X349427D01*
X349612Y895437D01*
Y895262D01*
X348212D01*
Y895437D01*
G37*
G36*
G01X346443Y893618D02*
X346016Y894078D01*
X346531Y894970D01*
X347143Y894830D01*
X347294Y894743D01*
X346594Y893531D01*
X346443Y893618D01*
G37*
G36*
G01X340755Y889027D02*
X340940Y889627D01*
X341970D01*
X342155Y889027D01*
Y888853D01*
X340755D01*
Y889027D01*
G37*
G36*
G01X344586Y890402D02*
X344159Y890862D01*
X344674Y891754D01*
X345286Y891614D01*
X345437Y891527D01*
X344737Y890315D01*
X344586Y890402D01*
G37*
G36*
G01X351912Y895437D02*
X352097Y896037D01*
X353127D01*
X353312Y895437D01*
Y895262D01*
X351912D01*
Y895437D01*
G37*
G36*
G01X348212D02*
X348397Y896037D01*
X349427D01*
X349612Y895437D01*
Y895262D01*
X348212D01*
Y895437D01*
G37*
G36*
G01X346443Y893618D02*
X346016Y894078D01*
X346531Y894970D01*
X347143Y894830D01*
X347294Y894743D01*
X346594Y893531D01*
X346443Y893618D01*
G37*
G36*
G01X340755Y889027D02*
X340940Y889627D01*
X341970D01*
X342155Y889027D01*
Y888853D01*
X340755D01*
Y889027D01*
G37*
G36*
G01X344586Y890402D02*
X344159Y890862D01*
X344674Y891754D01*
X345286Y891614D01*
X345437Y891527D01*
X344737Y890315D01*
X344586Y890402D01*
G37*
G36*
G01X351912Y895437D02*
X352097Y896037D01*
X353127D01*
X353312Y895437D01*
Y895262D01*
X351912D01*
Y895437D01*
G37*
G36*
G01X347597Y886017D02*
X348024Y885557D01*
X347509Y884665D01*
X346897Y884805D01*
X346746Y884892D01*
X347446Y886104D01*
X347597Y886017D01*
G37*
G36*
G01X349439Y889206D02*
X349866Y888746D01*
X349351Y887854D01*
X348739Y887994D01*
X348588Y888081D01*
X349288Y889293D01*
X349439Y889206D01*
G37*
G36*
G01X353312Y890635D02*
X353127Y890035D01*
X352097D01*
X351912Y890635D01*
Y890810D01*
X353312D01*
Y890635D01*
G37*
G36*
G01X347597Y886017D02*
X348024Y885557D01*
X347509Y884665D01*
X346897Y884805D01*
X346746Y884892D01*
X347446Y886104D01*
X347597Y886017D01*
G37*
G36*
G01X349439Y889206D02*
X349866Y888746D01*
X349351Y887854D01*
X348739Y887994D01*
X348588Y888081D01*
X349288Y889293D01*
X349439Y889206D01*
G37*
G36*
G01X353312Y890635D02*
X353127Y890035D01*
X352097D01*
X351912Y890635D01*
Y890810D01*
X353312D01*
Y890635D01*
G37*
G36*
G01X340329Y900251D02*
X340144Y899651D01*
X339114D01*
X338929Y900251D01*
Y900425D01*
X340329D01*
Y900251D01*
G37*
G36*
G01D02*
X340144Y899651D01*
X339114D01*
X338929Y900251D01*
Y900425D01*
X340329D01*
Y900251D01*
G37*
G36*
G01X344455Y901845D02*
X344640Y902445D01*
X345670D01*
X345855Y901845D01*
Y901671D01*
X344455D01*
Y901845D01*
G37*
G36*
G01X348212D02*
X348397Y902445D01*
X349427D01*
X349612Y901845D01*
Y901671D01*
X348212D01*
Y901845D01*
G37*
G36*
G01X351912D02*
X352097Y902445D01*
X353127D01*
X353312Y901845D01*
Y901671D01*
X351912D01*
Y901845D01*
G37*
G36*
G01X344455D02*
X344640Y902445D01*
X345670D01*
X345855Y901845D01*
Y901671D01*
X344455D01*
Y901845D01*
G37*
G36*
G01X348212D02*
X348397Y902445D01*
X349427D01*
X349612Y901845D01*
Y901671D01*
X348212D01*
Y901845D01*
G37*
G36*
G01X351912D02*
X352097Y902445D01*
X353127D01*
X353312Y901845D01*
Y901671D01*
X351912D01*
Y901845D01*
G37*
G36*
G01X342179Y916271D02*
X341994Y915671D01*
X340964D01*
X340779Y916271D01*
Y916446D01*
X342179D01*
Y916271D01*
G37*
G36*
G01X345879D02*
X345694Y915671D01*
X344664D01*
X344479Y916271D01*
Y916445D01*
X345879D01*
Y916271D01*
G37*
G36*
G01X342179D02*
X341994Y915671D01*
X340964D01*
X340779Y916271D01*
Y916446D01*
X342179D01*
Y916271D01*
G37*
G36*
G01X345879D02*
X345694Y915671D01*
X344664D01*
X344479Y916271D01*
Y916445D01*
X345879D01*
Y916271D01*
G37*
G36*
G01X347597Y918060D02*
X348024Y917600D01*
X347509Y916708D01*
X346897Y916848D01*
X346746Y916935D01*
X347446Y918147D01*
X347597Y918060D01*
G37*
G36*
G01D02*
X348024Y917600D01*
X347509Y916708D01*
X346897Y916848D01*
X346746Y916935D01*
X347446Y918147D01*
X347597Y918060D01*
G37*
G36*
G01X344479Y908253D02*
X344664Y908853D01*
X345694D01*
X345879Y908253D01*
Y908079D01*
X344479D01*
Y908253D01*
G37*
G36*
G01X348212D02*
X348397Y908853D01*
X349427D01*
X349612Y908253D01*
Y908079D01*
X348212D01*
Y908253D01*
G37*
G36*
G01X339065Y906472D02*
X338638Y906932D01*
X339153Y907824D01*
X339765Y907684D01*
X339916Y907597D01*
X339216Y906385D01*
X339065Y906472D01*
G37*
G36*
G01X340812Y908255D02*
X340997Y908855D01*
X342027D01*
X342212Y908255D01*
Y908080D01*
X340812D01*
Y908255D01*
G37*
G36*
G01X351912Y908253D02*
X352097Y908853D01*
X353127D01*
X353312Y908253D01*
Y908079D01*
X351912D01*
Y908253D01*
G37*
G36*
G01X344479D02*
X344664Y908853D01*
X345694D01*
X345879Y908253D01*
Y908079D01*
X344479D01*
Y908253D01*
G37*
G36*
G01X348212D02*
X348397Y908853D01*
X349427D01*
X349612Y908253D01*
Y908079D01*
X348212D01*
Y908253D01*
G37*
G36*
G01X339065Y906472D02*
X338638Y906932D01*
X339153Y907824D01*
X339765Y907684D01*
X339916Y907597D01*
X339216Y906385D01*
X339065Y906472D01*
G37*
G36*
G01X340812Y908255D02*
X340997Y908855D01*
X342027D01*
X342212Y908255D01*
Y908080D01*
X340812D01*
Y908255D01*
G37*
G36*
G01X351912Y908253D02*
X352097Y908853D01*
X353127D01*
X353312Y908253D01*
Y908079D01*
X351912D01*
Y908253D01*
G37*
G36*
G01X342668Y905051D02*
X342853Y905651D01*
X343883D01*
X344068Y905051D01*
Y904876D01*
X342668D01*
Y905051D01*
G37*
G36*
G01X340910Y903260D02*
X340483Y903720D01*
X340998Y904612D01*
X341610Y904472D01*
X341761Y904385D01*
X341061Y903173D01*
X340910Y903260D01*
G37*
G36*
G01X346290Y905049D02*
X346475Y905649D01*
X347505D01*
X347690Y905049D01*
Y904875D01*
X346290D01*
Y905049D01*
G37*
G36*
G01X349995D02*
X350180Y905649D01*
X351210D01*
X351395Y905049D01*
Y904875D01*
X349995D01*
Y905049D01*
G37*
G36*
G01X353705D02*
X353890Y905649D01*
X354920D01*
X355105Y905049D01*
Y904875D01*
X353705D01*
Y905049D01*
G37*
G36*
G01X342668Y905051D02*
X342853Y905651D01*
X343883D01*
X344068Y905051D01*
Y904876D01*
X342668D01*
Y905051D01*
G37*
G36*
G01X340910Y903260D02*
X340483Y903720D01*
X340998Y904612D01*
X341610Y904472D01*
X341761Y904385D01*
X341061Y903173D01*
X340910Y903260D01*
G37*
G36*
G01X346290Y905049D02*
X346475Y905649D01*
X347505D01*
X347690Y905049D01*
Y904875D01*
X346290D01*
Y905049D01*
G37*
G36*
G01X349995D02*
X350180Y905649D01*
X351210D01*
X351395Y905049D01*
Y904875D01*
X349995D01*
Y905049D01*
G37*
G36*
G01X353705D02*
X353890Y905649D01*
X354920D01*
X355105Y905049D01*
Y904875D01*
X353705D01*
Y905049D01*
G37*
G36*
G01X340197Y905243D02*
X340624Y904783D01*
X340109Y903891D01*
X339497Y904031D01*
X339346Y904118D01*
X340046Y905330D01*
X340197Y905243D01*
G37*
G36*
G01X343989Y906657D02*
X343804Y906057D01*
X342774D01*
X342589Y906657D01*
Y906831D01*
X343989D01*
Y906657D01*
G37*
G36*
G01X347705D02*
X347520Y906057D01*
X346490D01*
X346305Y906657D01*
Y906832D01*
X347705D01*
Y906657D01*
G37*
G36*
G01X351395D02*
X351210Y906057D01*
X350180D01*
X349995Y906657D01*
Y906831D01*
X351395D01*
Y906657D01*
G37*
G36*
G01X355105D02*
X354920Y906057D01*
X353890D01*
X353705Y906657D01*
Y906831D01*
X355105D01*
Y906657D01*
G37*
G36*
G01X340197Y905243D02*
X340624Y904783D01*
X340109Y903891D01*
X339497Y904031D01*
X339346Y904118D01*
X340046Y905330D01*
X340197Y905243D01*
G37*
G36*
G01X343989Y906657D02*
X343804Y906057D01*
X342774D01*
X342589Y906657D01*
Y906831D01*
X343989D01*
Y906657D01*
G37*
G36*
G01X347705D02*
X347520Y906057D01*
X346490D01*
X346305Y906657D01*
Y906832D01*
X347705D01*
Y906657D01*
G37*
G36*
G01X351395D02*
X351210Y906057D01*
X350180D01*
X349995Y906657D01*
Y906831D01*
X351395D01*
Y906657D01*
G37*
G36*
G01X355105D02*
X354920Y906057D01*
X353890D01*
X353705Y906657D01*
Y906831D01*
X355105D01*
Y906657D01*
G37*
G36*
G01X342047Y902039D02*
X342474Y901579D01*
X341959Y900687D01*
X341347Y900827D01*
X341196Y900914D01*
X341896Y902126D01*
X342047Y902039D01*
G37*
G36*
G01X345855Y903453D02*
X345670Y902853D01*
X344640D01*
X344455Y903453D01*
Y903627D01*
X345855D01*
Y903453D01*
G37*
G36*
G01X349612D02*
X349427Y902853D01*
X348397D01*
X348212Y903453D01*
Y903627D01*
X349612D01*
Y903453D01*
G37*
G36*
G01X353312D02*
X353127Y902853D01*
X352097D01*
X351912Y903453D01*
Y903627D01*
X353312D01*
Y903453D01*
G37*
G36*
G01X342047Y902039D02*
X342474Y901579D01*
X341959Y900687D01*
X341347Y900827D01*
X341196Y900914D01*
X341896Y902126D01*
X342047Y902039D01*
G37*
G36*
G01X345855Y903453D02*
X345670Y902853D01*
X344640D01*
X344455Y903453D01*
Y903627D01*
X345855D01*
Y903453D01*
G37*
G36*
G01X349612D02*
X349427Y902853D01*
X348397D01*
X348212Y903453D01*
Y903627D01*
X349612D01*
Y903453D01*
G37*
G36*
G01X353312D02*
X353127Y902853D01*
X352097D01*
X351912Y903453D01*
Y903627D01*
X353312D01*
Y903453D01*
G37*
G36*
G01X340329Y913067D02*
X340144Y912467D01*
X339114D01*
X338929Y913067D01*
Y913241D01*
X340329D01*
Y913067D01*
G37*
G36*
G01X344029D02*
X343844Y912467D01*
X342814D01*
X342629Y913067D01*
Y913241D01*
X344029D01*
Y913067D01*
G37*
G36*
G01X347705D02*
X347520Y912467D01*
X346490D01*
X346305Y913067D01*
Y913241D01*
X347705D01*
Y913067D01*
G37*
G36*
G01X351395Y913065D02*
X351210Y912465D01*
X350180D01*
X349995Y913065D01*
Y913240D01*
X351395D01*
Y913065D01*
G37*
G36*
G01X353164Y914884D02*
X353591Y914424D01*
X353076Y913532D01*
X352464Y913672D01*
X352313Y913759D01*
X353013Y914971D01*
X353164Y914884D01*
G37*
G36*
G01X340329Y913067D02*
X340144Y912467D01*
X339114D01*
X338929Y913067D01*
Y913241D01*
X340329D01*
Y913067D01*
G37*
G36*
G01X344029D02*
X343844Y912467D01*
X342814D01*
X342629Y913067D01*
Y913241D01*
X344029D01*
Y913067D01*
G37*
G36*
G01X347705D02*
X347520Y912467D01*
X346490D01*
X346305Y913067D01*
Y913241D01*
X347705D01*
Y913067D01*
G37*
G36*
G01X351395Y913065D02*
X351210Y912465D01*
X350180D01*
X349995Y913065D01*
Y913240D01*
X351395D01*
Y913065D01*
G37*
G36*
G01X353164Y914884D02*
X353591Y914424D01*
X353076Y913532D01*
X352464Y913672D01*
X352313Y913759D01*
X353013Y914971D01*
X353164Y914884D01*
G37*
G36*
G01X338929Y911457D02*
X339114Y912057D01*
X340144D01*
X340329Y911457D01*
Y911283D01*
X338929D01*
Y911457D01*
G37*
G36*
G01X342629D02*
X342814Y912057D01*
X343844D01*
X344029Y911457D01*
Y911283D01*
X342629D01*
Y911457D01*
G37*
G36*
G01X346305D02*
X346490Y912057D01*
X347520D01*
X347705Y911457D01*
Y911283D01*
X346305D01*
Y911457D01*
G37*
G36*
G01X349995Y911459D02*
X350180Y912059D01*
X351210D01*
X351395Y911459D01*
Y911284D01*
X349995D01*
Y911459D01*
G37*
G36*
G01X353843Y912844D02*
X353416Y913304D01*
X353931Y914196D01*
X354543Y914056D01*
X354694Y913969D01*
X353994Y912757D01*
X353843Y912844D01*
G37*
G36*
G01X338929Y911457D02*
X339114Y912057D01*
X340144D01*
X340329Y911457D01*
Y911283D01*
X338929D01*
Y911457D01*
G37*
G36*
G01X342629D02*
X342814Y912057D01*
X343844D01*
X344029Y911457D01*
Y911283D01*
X342629D01*
Y911457D01*
G37*
G36*
G01X346305D02*
X346490Y912057D01*
X347520D01*
X347705Y911457D01*
Y911283D01*
X346305D01*
Y911457D01*
G37*
G36*
G01X349995Y911459D02*
X350180Y912059D01*
X351210D01*
X351395Y911459D01*
Y911284D01*
X349995D01*
Y911459D01*
G37*
G36*
G01X353843Y912844D02*
X353416Y913304D01*
X353931Y914196D01*
X354543Y914056D01*
X354694Y913969D01*
X353994Y912757D01*
X353843Y912844D01*
G37*
G36*
G01X340779Y914661D02*
X340964Y915261D01*
X341994D01*
X342179Y914661D01*
Y914487D01*
X340779D01*
Y914661D01*
G37*
G36*
G01X344479D02*
X344664Y915261D01*
X345694D01*
X345879Y914661D01*
Y914487D01*
X344479D01*
Y914661D01*
G37*
G36*
G01X348212Y914663D02*
X348397Y915263D01*
X349427D01*
X349612Y914663D01*
Y914488D01*
X348212D01*
Y914663D01*
G37*
G36*
G01X352015Y916086D02*
X351588Y916546D01*
X352103Y917438D01*
X352715Y917298D01*
X352866Y917211D01*
X352166Y915999D01*
X352015Y916086D01*
G37*
G36*
G01X340779Y914661D02*
X340964Y915261D01*
X341994D01*
X342179Y914661D01*
Y914487D01*
X340779D01*
Y914661D01*
G37*
G36*
G01X344479D02*
X344664Y915261D01*
X345694D01*
X345879Y914661D01*
Y914487D01*
X344479D01*
Y914661D01*
G37*
G36*
G01X348212Y914663D02*
X348397Y915263D01*
X349427D01*
X349612Y914663D01*
Y914488D01*
X348212D01*
Y914663D01*
G37*
G36*
G01X352015Y916086D02*
X351588Y916546D01*
X352103Y917438D01*
X352715Y917298D01*
X352866Y917211D01*
X352166Y915999D01*
X352015Y916086D01*
G37*
G36*
G01X342179Y909863D02*
X341994Y909263D01*
X340964D01*
X340779Y909863D01*
Y910037D01*
X342179D01*
Y909863D01*
G37*
G36*
G01X345910Y909861D02*
X345725Y909261D01*
X344695D01*
X344510Y909861D01*
Y910036D01*
X345910D01*
Y909861D01*
G37*
G36*
G01X349612D02*
X349427Y909261D01*
X348397D01*
X348212Y909861D01*
Y910035D01*
X349612D01*
Y909861D01*
G37*
G36*
G01X353312D02*
X353127Y909261D01*
X352097D01*
X351912Y909861D01*
Y910035D01*
X353312D01*
Y909861D01*
G37*
G36*
G01X354985Y911636D02*
X355412Y911176D01*
X354897Y910284D01*
X354285Y910424D01*
X354134Y910511D01*
X354834Y911723D01*
X354985Y911636D01*
G37*
G36*
G01X342179Y909863D02*
X341994Y909263D01*
X340964D01*
X340779Y909863D01*
Y910037D01*
X342179D01*
Y909863D01*
G37*
G36*
G01X345910Y909861D02*
X345725Y909261D01*
X344695D01*
X344510Y909861D01*
Y910036D01*
X345910D01*
Y909861D01*
G37*
G36*
G01X349612D02*
X349427Y909261D01*
X348397D01*
X348212Y909861D01*
Y910035D01*
X349612D01*
Y909861D01*
G37*
G36*
G01X353312D02*
X353127Y909261D01*
X352097D01*
X351912Y909861D01*
Y910035D01*
X353312D01*
Y909861D01*
G37*
G36*
G01X354985Y911636D02*
X355412Y911176D01*
X354897Y910284D01*
X354285Y910424D01*
X354134Y910511D01*
X354834Y911723D01*
X354985Y911636D01*
G37*
G36*
G01X340911Y928894D02*
X340484Y929354D01*
X340999Y930246D01*
X341611Y930106D01*
X341762Y930019D01*
X341062Y928807D01*
X340911Y928894D01*
G37*
G36*
G01X342629Y930683D02*
X342814Y931283D01*
X343844D01*
X344029Y930683D01*
Y930509D01*
X342629D01*
Y930683D01*
G37*
G36*
G01X346329D02*
X346514Y931283D01*
X347544D01*
X347729Y930683D01*
Y930509D01*
X346329D01*
Y930683D01*
G37*
G36*
G01X350005D02*
X350190Y931283D01*
X351220D01*
X351405Y930683D01*
Y930509D01*
X350005D01*
Y930683D01*
G37*
G36*
G01X353695Y930685D02*
X353880Y931285D01*
X354910D01*
X355095Y930685D01*
Y930510D01*
X353695D01*
Y930685D01*
G37*
G36*
G01X340911Y928894D02*
X340484Y929354D01*
X340999Y930246D01*
X341611Y930106D01*
X341762Y930019D01*
X341062Y928807D01*
X340911Y928894D01*
G37*
G36*
G01X342629Y930683D02*
X342814Y931283D01*
X343844D01*
X344029Y930683D01*
Y930509D01*
X342629D01*
Y930683D01*
G37*
G36*
G01X346329D02*
X346514Y931283D01*
X347544D01*
X347729Y930683D01*
Y930509D01*
X346329D01*
Y930683D01*
G37*
G36*
G01X350005D02*
X350190Y931283D01*
X351220D01*
X351405Y930683D01*
Y930509D01*
X350005D01*
Y930683D01*
G37*
G36*
G01X353695Y930685D02*
X353880Y931285D01*
X354910D01*
X355095Y930685D01*
Y930510D01*
X353695D01*
Y930685D01*
G37*
G36*
G01X342736Y925649D02*
X342309Y926109D01*
X342824Y927001D01*
X343436Y926861D01*
X343587Y926774D01*
X342887Y925562D01*
X342736Y925649D01*
G37*
G36*
G01X348212Y927479D02*
X348397Y928079D01*
X349427D01*
X349612Y927479D01*
Y927305D01*
X348212D01*
Y927479D01*
G37*
G36*
G01X344479D02*
X344664Y928079D01*
X345694D01*
X345879Y927479D01*
Y927305D01*
X344479D01*
Y927479D01*
G37*
G36*
G01X338908Y924275D02*
X339093Y924875D01*
X340123D01*
X340308Y924275D01*
Y924101D01*
X338908D01*
Y924275D01*
G37*
G36*
G01X351912Y927479D02*
X352097Y928079D01*
X353127D01*
X353312Y927479D01*
Y927305D01*
X351912D01*
Y927479D01*
G37*
G36*
G01X342736Y925649D02*
X342309Y926109D01*
X342824Y927001D01*
X343436Y926861D01*
X343587Y926774D01*
X342887Y925562D01*
X342736Y925649D01*
G37*
G36*
G01X348212Y927479D02*
X348397Y928079D01*
X349427D01*
X349612Y927479D01*
Y927305D01*
X348212D01*
Y927479D01*
G37*
G36*
G01X344479D02*
X344664Y928079D01*
X345694D01*
X345879Y927479D01*
Y927305D01*
X344479D01*
Y927479D01*
G37*
G36*
G01X338908Y924275D02*
X339093Y924875D01*
X340123D01*
X340308Y924275D01*
Y924101D01*
X338908D01*
Y924275D01*
G37*
G36*
G01X351912Y927479D02*
X352097Y928079D01*
X353127D01*
X353312Y927479D01*
Y927305D01*
X351912D01*
Y927479D01*
G37*
G36*
G01X345910Y929087D02*
X345725Y928487D01*
X344695D01*
X344510Y929087D01*
Y929262D01*
X345910D01*
Y929087D01*
G37*
G36*
G01X349579D02*
X349394Y928487D01*
X348364D01*
X348179Y929087D01*
Y929262D01*
X349579D01*
Y929087D01*
G37*
G36*
G01X340350Y925883D02*
X340165Y925283D01*
X339135D01*
X338950Y925883D01*
Y926058D01*
X340350D01*
Y925883D01*
G37*
G36*
G01X342044Y927666D02*
X342471Y927206D01*
X341956Y926314D01*
X341344Y926454D01*
X341193Y926541D01*
X341893Y927753D01*
X342044Y927666D01*
G37*
G36*
G01X353312Y929087D02*
X353127Y928487D01*
X352097D01*
X351912Y929087D01*
Y929261D01*
X353312D01*
Y929087D01*
G37*
G36*
G01X345910D02*
X345725Y928487D01*
X344695D01*
X344510Y929087D01*
Y929262D01*
X345910D01*
Y929087D01*
G37*
G36*
G01X349579D02*
X349394Y928487D01*
X348364D01*
X348179Y929087D01*
Y929262D01*
X349579D01*
Y929087D01*
G37*
G36*
G01X340350Y925883D02*
X340165Y925283D01*
X339135D01*
X338950Y925883D01*
Y926058D01*
X340350D01*
Y925883D01*
G37*
G36*
G01X342044Y927666D02*
X342471Y927206D01*
X341956Y926314D01*
X341344Y926454D01*
X341193Y926541D01*
X341893Y927753D01*
X342044Y927666D01*
G37*
G36*
G01X353312Y929087D02*
X353127Y928487D01*
X352097D01*
X351912Y929087D01*
Y929261D01*
X353312D01*
Y929087D01*
G37*
G36*
G01X351395Y925883D02*
X351210Y925283D01*
X350180D01*
X349995Y925883D01*
Y926057D01*
X351395D01*
Y925883D01*
G37*
G36*
G01X343914Y924498D02*
X344341Y924038D01*
X343826Y923146D01*
X343214Y923286D01*
X343063Y923373D01*
X343763Y924585D01*
X343914Y924498D01*
G37*
G36*
G01X342202Y922679D02*
X342017Y922079D01*
X340987D01*
X340802Y922679D01*
Y922853D01*
X342202D01*
Y922679D01*
G37*
G36*
G01X347705Y925883D02*
X347520Y925283D01*
X346490D01*
X346305Y925883D01*
Y926058D01*
X347705D01*
Y925883D01*
G37*
G36*
G01X355105D02*
X354920Y925283D01*
X353890D01*
X353705Y925883D01*
Y926057D01*
X355105D01*
Y925883D01*
G37*
G36*
G01X351395D02*
X351210Y925283D01*
X350180D01*
X349995Y925883D01*
Y926057D01*
X351395D01*
Y925883D01*
G37*
G36*
G01X343914Y924498D02*
X344341Y924038D01*
X343826Y923146D01*
X343214Y923286D01*
X343063Y923373D01*
X343763Y924585D01*
X343914Y924498D01*
G37*
G36*
G01X342202Y922679D02*
X342017Y922079D01*
X340987D01*
X340802Y922679D01*
Y922853D01*
X342202D01*
Y922679D01*
G37*
G36*
G01X347705Y925883D02*
X347520Y925283D01*
X346490D01*
X346305Y925883D01*
Y926058D01*
X347705D01*
Y925883D01*
G37*
G36*
G01X355105D02*
X354920Y925283D01*
X353890D01*
X353705Y925883D01*
Y926057D01*
X355105D01*
Y925883D01*
G37*
G36*
G01X339061Y932098D02*
X338634Y932558D01*
X339149Y933450D01*
X339761Y933310D01*
X339912Y933223D01*
X339212Y932011D01*
X339061Y932098D01*
G37*
G36*
G01D02*
X338634Y932558D01*
X339149Y933450D01*
X339761Y933310D01*
X339912Y933223D01*
X339212Y932011D01*
X339061Y932098D01*
G37*
G36*
G01X344062Y932291D02*
X343877Y931691D01*
X342847D01*
X342662Y932291D01*
Y932466D01*
X344062D01*
Y932291D01*
G37*
G36*
G01X340197Y930878D02*
X340624Y930418D01*
X340109Y929526D01*
X339497Y929666D01*
X339346Y929753D01*
X340046Y930965D01*
X340197Y930878D01*
G37*
G36*
G01X347729Y932291D02*
X347544Y931691D01*
X346514D01*
X346329Y932291D01*
Y932466D01*
X347729D01*
Y932291D01*
G37*
G36*
G01X351405D02*
X351220Y931691D01*
X350190D01*
X350005Y932291D01*
Y932466D01*
X351405D01*
Y932291D01*
G37*
G36*
G01X355095D02*
X354910Y931691D01*
X353880D01*
X353695Y932291D01*
Y932465D01*
X355095D01*
Y932291D01*
G37*
G36*
G01X344062D02*
X343877Y931691D01*
X342847D01*
X342662Y932291D01*
Y932466D01*
X344062D01*
Y932291D01*
G37*
G36*
G01X340197Y930878D02*
X340624Y930418D01*
X340109Y929526D01*
X339497Y929666D01*
X339346Y929753D01*
X340046Y930965D01*
X340197Y930878D01*
G37*
G36*
G01X347729Y932291D02*
X347544Y931691D01*
X346514D01*
X346329Y932291D01*
Y932466D01*
X347729D01*
Y932291D01*
G37*
G36*
G01X351405D02*
X351220Y931691D01*
X350190D01*
X350005Y932291D01*
Y932466D01*
X351405D01*
Y932291D01*
G37*
G36*
G01X355095D02*
X354910Y931691D01*
X353880D01*
X353695Y932291D01*
Y932465D01*
X355095D01*
Y932291D01*
G37*
G36*
G01X340755Y921073D02*
X340940Y921673D01*
X341970D01*
X342155Y921073D01*
Y920898D01*
X340755D01*
Y921073D01*
G37*
G36*
G01X344619Y922501D02*
X344192Y922961D01*
X344707Y923853D01*
X345319Y923713D01*
X345470Y923626D01*
X344770Y922414D01*
X344619Y922501D01*
G37*
G36*
G01X346290Y924275D02*
X346475Y924875D01*
X347505D01*
X347690Y924275D01*
Y924101D01*
X346290D01*
Y924275D01*
G37*
G36*
G01X349995D02*
X350180Y924875D01*
X351210D01*
X351395Y924275D01*
Y924101D01*
X349995D01*
Y924275D01*
G37*
G36*
G01X353705D02*
X353890Y924875D01*
X354920D01*
X355105Y924275D01*
Y924101D01*
X353705D01*
Y924275D01*
G37*
G36*
G01X340755Y921073D02*
X340940Y921673D01*
X341970D01*
X342155Y921073D01*
Y920898D01*
X340755D01*
Y921073D01*
G37*
G36*
G01X344619Y922501D02*
X344192Y922961D01*
X344707Y923853D01*
X345319Y923713D01*
X345470Y923626D01*
X344770Y922414D01*
X344619Y922501D01*
G37*
G36*
G01X346290Y924275D02*
X346475Y924875D01*
X347505D01*
X347690Y924275D01*
Y924101D01*
X346290D01*
Y924275D01*
G37*
G36*
G01X349995D02*
X350180Y924875D01*
X351210D01*
X351395Y924275D01*
Y924101D01*
X349995D01*
Y924275D01*
G37*
G36*
G01X353705D02*
X353890Y924875D01*
X354920D01*
X355105Y924275D01*
Y924101D01*
X353705D01*
Y924275D01*
G37*
G36*
G01X338905Y917867D02*
X339090Y918467D01*
X340120D01*
X340305Y917867D01*
Y917693D01*
X338905D01*
Y917867D01*
G37*
G36*
G01X342598D02*
X342783Y918467D01*
X343813D01*
X343998Y917867D01*
Y917692D01*
X342598D01*
Y917867D01*
G37*
G36*
G01X348212Y921071D02*
X348397Y921671D01*
X349427D01*
X349612Y921071D01*
Y920897D01*
X348212D01*
Y921071D01*
G37*
G36*
G01X346464Y919288D02*
X346037Y919748D01*
X346552Y920640D01*
X347164Y920500D01*
X347315Y920413D01*
X346615Y919201D01*
X346464Y919288D01*
G37*
G36*
G01X351912Y921071D02*
X352097Y921671D01*
X353127D01*
X353312Y921071D01*
Y920897D01*
X351912D01*
Y921071D01*
G37*
G36*
G01X338905Y917867D02*
X339090Y918467D01*
X340120D01*
X340305Y917867D01*
Y917693D01*
X338905D01*
Y917867D01*
G37*
G36*
G01X342598D02*
X342783Y918467D01*
X343813D01*
X343998Y917867D01*
Y917692D01*
X342598D01*
Y917867D01*
G37*
G36*
G01X348212Y921071D02*
X348397Y921671D01*
X349427D01*
X349612Y921071D01*
Y920897D01*
X348212D01*
Y921071D01*
G37*
G36*
G01X346464Y919288D02*
X346037Y919748D01*
X346552Y920640D01*
X347164Y920500D01*
X347315Y920413D01*
X346615Y919201D01*
X346464Y919288D01*
G37*
G36*
G01X351912Y921071D02*
X352097Y921671D01*
X353127D01*
X353312Y921071D01*
Y920897D01*
X351912D01*
Y921071D01*
G37*
G36*
G01X340352Y919475D02*
X340167Y918875D01*
X339137D01*
X338952Y919475D01*
Y919649D01*
X340352D01*
Y919475D01*
G37*
G36*
G01X344060D02*
X343875Y918875D01*
X342845D01*
X342660Y919475D01*
Y919650D01*
X344060D01*
Y919475D01*
G37*
G36*
G01X345739Y921250D02*
X346166Y920790D01*
X345651Y919898D01*
X345039Y920038D01*
X344888Y920125D01*
X345588Y921337D01*
X345739Y921250D01*
G37*
G36*
G01X349612Y922679D02*
X349427Y922079D01*
X348397D01*
X348212Y922679D01*
Y922853D01*
X349612D01*
Y922679D01*
G37*
G36*
G01X353312D02*
X353127Y922079D01*
X352097D01*
X351912Y922679D01*
Y922853D01*
X353312D01*
Y922679D01*
G37*
G36*
G01X340352Y919475D02*
X340167Y918875D01*
X339137D01*
X338952Y919475D01*
Y919649D01*
X340352D01*
Y919475D01*
G37*
G36*
G01X344060D02*
X343875Y918875D01*
X342845D01*
X342660Y919475D01*
Y919650D01*
X344060D01*
Y919475D01*
G37*
G36*
G01X345739Y921250D02*
X346166Y920790D01*
X345651Y919898D01*
X345039Y920038D01*
X344888Y920125D01*
X345588Y921337D01*
X345739Y921250D01*
G37*
G36*
G01X349612Y922679D02*
X349427Y922079D01*
X348397D01*
X348212Y922679D01*
Y922853D01*
X349612D01*
Y922679D01*
G37*
G36*
G01X353312D02*
X353127Y922079D01*
X352097D01*
X351912Y922679D01*
Y922853D01*
X353312D01*
Y922679D01*
G37*
G36*
G01X351395Y919473D02*
X351210Y918873D01*
X350180D01*
X349995Y919473D01*
Y919648D01*
X351395D01*
Y919473D01*
G37*
G36*
G01X355095D02*
X354910Y918873D01*
X353880D01*
X353695Y919473D01*
Y919648D01*
X355095D01*
Y919473D01*
G37*
G36*
G01X351395D02*
X351210Y918873D01*
X350180D01*
X349995Y919473D01*
Y919648D01*
X351395D01*
Y919473D01*
G37*
G36*
G01X355095D02*
X354910Y918873D01*
X353880D01*
X353695Y919473D01*
Y919648D01*
X355095D01*
Y919473D01*
G37*
G36*
G01X353695Y917867D02*
X353880Y918467D01*
X354910D01*
X355095Y917867D01*
Y917692D01*
X353695D01*
Y917867D01*
G37*
G36*
G01D02*
X353880Y918467D01*
X354910D01*
X355095Y917867D01*
Y917692D01*
X353695D01*
Y917867D01*
G37*
G36*
G01X342212Y941903D02*
X342027Y941303D01*
X340997D01*
X340812Y941903D01*
Y942078D01*
X342212D01*
Y941903D01*
G37*
G36*
G01X349612D02*
X349427Y941303D01*
X348397D01*
X348212Y941903D01*
Y942078D01*
X349612D01*
Y941903D01*
G37*
G36*
G01X345912D02*
X345727Y941303D01*
X344697D01*
X344512Y941903D01*
Y942078D01*
X345912D01*
Y941903D01*
G37*
G36*
G01X353312D02*
X353127Y941303D01*
X352097D01*
X351912Y941903D01*
Y942078D01*
X353312D01*
Y941903D01*
G37*
G36*
G01X342212D02*
X342027Y941303D01*
X340997D01*
X340812Y941903D01*
Y942078D01*
X342212D01*
Y941903D01*
G37*
G36*
G01X349612D02*
X349427Y941303D01*
X348397D01*
X348212Y941903D01*
Y942078D01*
X349612D01*
Y941903D01*
G37*
G36*
G01X345912D02*
X345727Y941303D01*
X344697D01*
X344512Y941903D01*
Y942078D01*
X345912D01*
Y941903D01*
G37*
G36*
G01X353312D02*
X353127Y941303D01*
X352097D01*
X351912Y941903D01*
Y942078D01*
X353312D01*
Y941903D01*
G37*
G36*
G01X344053Y938701D02*
X343868Y938101D01*
X342838D01*
X342653Y938701D01*
Y938875D01*
X344053D01*
Y938701D01*
G37*
G36*
G01X340363Y938699D02*
X340178Y938099D01*
X339148D01*
X338963Y938699D01*
Y938874D01*
X340363D01*
Y938699D01*
G37*
G36*
G01X347705Y938701D02*
X347520Y938101D01*
X346490D01*
X346305Y938701D01*
Y938875D01*
X347705D01*
Y938701D01*
G37*
G36*
G01X351395Y938699D02*
X351210Y938099D01*
X350180D01*
X349995Y938699D01*
Y938874D01*
X351395D01*
Y938699D01*
G37*
G36*
G01X355095D02*
X354910Y938099D01*
X353880D01*
X353695Y938699D01*
Y938874D01*
X355095D01*
Y938699D01*
G37*
G36*
G01X344053Y938701D02*
X343868Y938101D01*
X342838D01*
X342653Y938701D01*
Y938875D01*
X344053D01*
Y938701D01*
G37*
G36*
G01X340363Y938699D02*
X340178Y938099D01*
X339148D01*
X338963Y938699D01*
Y938874D01*
X340363D01*
Y938699D01*
G37*
G36*
G01X347705Y938701D02*
X347520Y938101D01*
X346490D01*
X346305Y938701D01*
Y938875D01*
X347705D01*
Y938701D01*
G37*
G36*
G01X351395Y938699D02*
X351210Y938099D01*
X350180D01*
X349995Y938699D01*
Y938874D01*
X351395D01*
Y938699D01*
G37*
G36*
G01X355095D02*
X354910Y938099D01*
X353880D01*
X353695Y938699D01*
Y938874D01*
X355095D01*
Y938699D01*
G37*
G36*
G01X344500Y946705D02*
X344685Y947305D01*
X345715D01*
X345900Y946705D01*
Y946531D01*
X344500D01*
Y946705D01*
G37*
G36*
G01X348212D02*
X348397Y947305D01*
X349427D01*
X349612Y946705D01*
Y946531D01*
X348212D01*
Y946705D01*
G37*
G36*
G01X340729D02*
X340914Y947305D01*
X341944D01*
X342129Y946705D01*
Y946531D01*
X340729D01*
Y946705D01*
G37*
G36*
G01X351912D02*
X352097Y947305D01*
X353127D01*
X353312Y946705D01*
Y946531D01*
X351912D01*
Y946705D01*
G37*
G36*
G01X344500D02*
X344685Y947305D01*
X345715D01*
X345900Y946705D01*
Y946531D01*
X344500D01*
Y946705D01*
G37*
G36*
G01X348212D02*
X348397Y947305D01*
X349427D01*
X349612Y946705D01*
Y946531D01*
X348212D01*
Y946705D01*
G37*
G36*
G01X340729D02*
X340914Y947305D01*
X341944D01*
X342129Y946705D01*
Y946531D01*
X340729D01*
Y946705D01*
G37*
G36*
G01X351912D02*
X352097Y947305D01*
X353127D01*
X353312Y946705D01*
Y946531D01*
X351912D01*
Y946705D01*
G37*
G36*
G01X342179Y948313D02*
X341994Y947713D01*
X340964D01*
X340779Y948313D01*
Y948488D01*
X342179D01*
Y948313D01*
G37*
G36*
G01X349612D02*
X349427Y947713D01*
X348397D01*
X348212Y948313D01*
Y948487D01*
X349612D01*
Y948313D01*
G37*
G36*
G01X345879D02*
X345694Y947713D01*
X344664D01*
X344479Y948313D01*
Y948488D01*
X345879D01*
Y948313D01*
G37*
G36*
G01X353312D02*
X353127Y947713D01*
X352097D01*
X351912Y948313D01*
Y948487D01*
X353312D01*
Y948313D01*
G37*
G36*
G01X342179D02*
X341994Y947713D01*
X340964D01*
X340779Y948313D01*
Y948488D01*
X342179D01*
Y948313D01*
G37*
G36*
G01X349612D02*
X349427Y947713D01*
X348397D01*
X348212Y948313D01*
Y948487D01*
X349612D01*
Y948313D01*
G37*
G36*
G01X345879D02*
X345694Y947713D01*
X344664D01*
X344479Y948313D01*
Y948488D01*
X345879D01*
Y948313D01*
G37*
G36*
G01X353312D02*
X353127Y947713D01*
X352097D01*
X351912Y948313D01*
Y948487D01*
X353312D01*
Y948313D01*
G37*
G36*
G01X340358Y945107D02*
X340173Y944507D01*
X339143D01*
X338958Y945107D01*
Y945282D01*
X340358D01*
Y945107D01*
G37*
G36*
G01X344067Y945109D02*
X343882Y944509D01*
X342852D01*
X342667Y945109D01*
Y945283D01*
X344067D01*
Y945109D01*
G37*
G36*
G01X347687Y945107D02*
X347502Y944507D01*
X346472D01*
X346287Y945107D01*
Y945282D01*
X347687D01*
Y945107D01*
G37*
G36*
G01X351395D02*
X351210Y944507D01*
X350180D01*
X349995Y945107D01*
Y945282D01*
X351395D01*
Y945107D01*
G37*
G36*
G01X355105D02*
X354920Y944507D01*
X353890D01*
X353705Y945107D01*
Y945282D01*
X355105D01*
Y945107D01*
G37*
G36*
G01X340358D02*
X340173Y944507D01*
X339143D01*
X338958Y945107D01*
Y945282D01*
X340358D01*
Y945107D01*
G37*
G36*
G01X344067Y945109D02*
X343882Y944509D01*
X342852D01*
X342667Y945109D01*
Y945283D01*
X344067D01*
Y945109D01*
G37*
G36*
G01X347687Y945107D02*
X347502Y944507D01*
X346472D01*
X346287Y945107D01*
Y945282D01*
X347687D01*
Y945107D01*
G37*
G36*
G01X351395D02*
X351210Y944507D01*
X350180D01*
X349995Y945107D01*
Y945282D01*
X351395D01*
Y945107D01*
G37*
G36*
G01X355105D02*
X354920Y944507D01*
X353890D01*
X353705Y945107D01*
Y945282D01*
X355105D01*
Y945107D01*
G37*
G36*
G01X342595Y943501D02*
X342780Y944101D01*
X343810D01*
X343995Y943501D01*
Y943326D01*
X342595D01*
Y943501D01*
G37*
G36*
G01X338895D02*
X339080Y944101D01*
X340110D01*
X340295Y943501D01*
Y943326D01*
X338895D01*
Y943501D01*
G37*
G36*
G01X346295D02*
X346480Y944101D01*
X347510D01*
X347695Y943501D01*
Y943326D01*
X346295D01*
Y943501D01*
G37*
G36*
G01X349995D02*
X350180Y944101D01*
X351210D01*
X351395Y943501D01*
Y943326D01*
X349995D01*
Y943501D01*
G37*
G36*
G01X353705D02*
X353890Y944101D01*
X354920D01*
X355105Y943501D01*
Y943326D01*
X353705D01*
Y943501D01*
G37*
G36*
G01X342595D02*
X342780Y944101D01*
X343810D01*
X343995Y943501D01*
Y943326D01*
X342595D01*
Y943501D01*
G37*
G36*
G01X338895D02*
X339080Y944101D01*
X340110D01*
X340295Y943501D01*
Y943326D01*
X338895D01*
Y943501D01*
G37*
G36*
G01X346295D02*
X346480Y944101D01*
X347510D01*
X347695Y943501D01*
Y943326D01*
X346295D01*
Y943501D01*
G37*
G36*
G01X349995D02*
X350180Y944101D01*
X351210D01*
X351395Y943501D01*
Y943326D01*
X349995D01*
Y943501D01*
G37*
G36*
G01X353705D02*
X353890Y944101D01*
X354920D01*
X355105Y943501D01*
Y943326D01*
X353705D01*
Y943501D01*
G37*
G36*
G01X340746Y940297D02*
X340931Y940897D01*
X341961D01*
X342146Y940297D01*
Y940122D01*
X340746D01*
Y940297D01*
G37*
G36*
G01X348212D02*
X348397Y940897D01*
X349427D01*
X349612Y940297D01*
Y940122D01*
X348212D01*
Y940297D01*
G37*
G36*
G01X344479Y940295D02*
X344664Y940895D01*
X345694D01*
X345879Y940295D01*
Y940121D01*
X344479D01*
Y940295D01*
G37*
G36*
G01X351912Y940297D02*
X352097Y940897D01*
X353127D01*
X353312Y940297D01*
Y940122D01*
X351912D01*
Y940297D01*
G37*
G36*
G01X340746D02*
X340931Y940897D01*
X341961D01*
X342146Y940297D01*
Y940122D01*
X340746D01*
Y940297D01*
G37*
G36*
G01X348212D02*
X348397Y940897D01*
X349427D01*
X349612Y940297D01*
Y940122D01*
X348212D01*
Y940297D01*
G37*
G36*
G01X344479Y940295D02*
X344664Y940895D01*
X345694D01*
X345879Y940295D01*
Y940121D01*
X344479D01*
Y940295D01*
G37*
G36*
G01X351912Y940297D02*
X352097Y940897D01*
X353127D01*
X353312Y940297D01*
Y940122D01*
X351912D01*
Y940297D01*
G37*
G36*
G01X342202Y935497D02*
X342017Y934897D01*
X340987D01*
X340802Y935497D01*
Y935671D01*
X342202D01*
Y935497D01*
G37*
G36*
G01X349612Y935495D02*
X349427Y934895D01*
X348397D01*
X348212Y935495D01*
Y935669D01*
X349612D01*
Y935495D01*
G37*
G36*
G01X345899D02*
X345714Y934895D01*
X344684D01*
X344499Y935495D01*
Y935670D01*
X345899D01*
Y935495D01*
G37*
G36*
G01X353312D02*
X353127Y934895D01*
X352097D01*
X351912Y935495D01*
Y935669D01*
X353312D01*
Y935495D01*
G37*
G36*
G01X342202Y935497D02*
X342017Y934897D01*
X340987D01*
X340802Y935497D01*
Y935671D01*
X342202D01*
Y935497D01*
G37*
G36*
G01X349612Y935495D02*
X349427Y934895D01*
X348397D01*
X348212Y935495D01*
Y935669D01*
X349612D01*
Y935495D01*
G37*
G36*
G01X345899D02*
X345714Y934895D01*
X344684D01*
X344499Y935495D01*
Y935670D01*
X345899D01*
Y935495D01*
G37*
G36*
G01X353312D02*
X353127Y934895D01*
X352097D01*
X351912Y935495D01*
Y935669D01*
X353312D01*
Y935495D01*
G37*
G36*
G01X340755Y933887D02*
X340940Y934487D01*
X341970D01*
X342155Y933887D01*
Y933713D01*
X340755D01*
Y933887D01*
G37*
G36*
G01X348179D02*
X348364Y934487D01*
X349394D01*
X349579Y933887D01*
Y933713D01*
X348179D01*
Y933887D01*
G37*
G36*
G01X344455Y933889D02*
X344640Y934489D01*
X345670D01*
X345855Y933889D01*
Y933714D01*
X344455D01*
Y933889D01*
G37*
G36*
G01X351912D02*
X352097Y934489D01*
X353127D01*
X353312Y933889D01*
Y933714D01*
X351912D01*
Y933889D01*
G37*
G36*
G01X340755Y933887D02*
X340940Y934487D01*
X341970D01*
X342155Y933887D01*
Y933713D01*
X340755D01*
Y933887D01*
G37*
G36*
G01X348179D02*
X348364Y934487D01*
X349394D01*
X349579Y933887D01*
Y933713D01*
X348179D01*
Y933887D01*
G37*
G36*
G01X344455Y933889D02*
X344640Y934489D01*
X345670D01*
X345855Y933889D01*
Y933714D01*
X344455D01*
Y933889D01*
G37*
G36*
G01X351912D02*
X352097Y934489D01*
X353127D01*
X353312Y933889D01*
Y933714D01*
X351912D01*
Y933889D01*
G37*
G36*
G01X346305Y937091D02*
X346490Y937691D01*
X347520D01*
X347705Y937091D01*
Y936917D01*
X346305D01*
Y937091D01*
G37*
G36*
G01X349995Y937093D02*
X350180Y937693D01*
X351210D01*
X351395Y937093D01*
Y936918D01*
X349995D01*
Y937093D01*
G37*
G36*
G01X342652D02*
X342837Y937693D01*
X343867D01*
X344052Y937093D01*
Y936918D01*
X342652D01*
Y937093D01*
G37*
G36*
G01X338929Y937091D02*
X339114Y937691D01*
X340144D01*
X340329Y937091D01*
Y936917D01*
X338929D01*
Y937091D01*
G37*
G36*
G01X353695Y937093D02*
X353880Y937693D01*
X354910D01*
X355095Y937093D01*
Y936918D01*
X353695D01*
Y937093D01*
G37*
G36*
G01X346305Y937091D02*
X346490Y937691D01*
X347520D01*
X347705Y937091D01*
Y936917D01*
X346305D01*
Y937091D01*
G37*
G36*
G01X349995Y937093D02*
X350180Y937693D01*
X351210D01*
X351395Y937093D01*
Y936918D01*
X349995D01*
Y937093D01*
G37*
G36*
G01X342652D02*
X342837Y937693D01*
X343867D01*
X344052Y937093D01*
Y936918D01*
X342652D01*
Y937093D01*
G37*
G36*
G01X338929Y937091D02*
X339114Y937691D01*
X340144D01*
X340329Y937091D01*
Y936917D01*
X338929D01*
Y937091D01*
G37*
G36*
G01X353695Y937093D02*
X353880Y937693D01*
X354910D01*
X355095Y937093D01*
Y936918D01*
X353695D01*
Y937093D01*
G37*
G36*
G01X342628Y962725D02*
X342813Y963325D01*
X343843D01*
X344028Y962725D01*
Y962551D01*
X342628D01*
Y962725D01*
G37*
G36*
G01X338928D02*
X339113Y963325D01*
X340143D01*
X340328Y962725D01*
Y962551D01*
X338928D01*
Y962725D01*
G37*
G36*
G01X346295Y962727D02*
X346480Y963327D01*
X347510D01*
X347695Y962727D01*
Y962552D01*
X346295D01*
Y962727D01*
G37*
G36*
G01X349995D02*
X350180Y963327D01*
X351210D01*
X351395Y962727D01*
Y962552D01*
X349995D01*
Y962727D01*
G37*
G36*
G01X353705D02*
X353890Y963327D01*
X354920D01*
X355105Y962727D01*
Y962552D01*
X353705D01*
Y962727D01*
G37*
G36*
G01X342628Y962725D02*
X342813Y963325D01*
X343843D01*
X344028Y962725D01*
Y962551D01*
X342628D01*
Y962725D01*
G37*
G36*
G01X338928D02*
X339113Y963325D01*
X340143D01*
X340328Y962725D01*
Y962551D01*
X338928D01*
Y962725D01*
G37*
G36*
G01X346295Y962727D02*
X346480Y963327D01*
X347510D01*
X347695Y962727D01*
Y962552D01*
X346295D01*
Y962727D01*
G37*
G36*
G01X349995D02*
X350180Y963327D01*
X351210D01*
X351395Y962727D01*
Y962552D01*
X349995D01*
Y962727D01*
G37*
G36*
G01X353705D02*
X353890Y963327D01*
X354920D01*
X355105Y962727D01*
Y962552D01*
X353705D01*
Y962727D01*
G37*
G36*
G01X340745Y959523D02*
X340930Y960123D01*
X341960D01*
X342145Y959523D01*
Y959348D01*
X340745D01*
Y959523D01*
G37*
G36*
G01X348168Y959521D02*
X348353Y960121D01*
X349383D01*
X349568Y959521D01*
Y959347D01*
X348168D01*
Y959521D01*
G37*
G36*
G01X344455Y959523D02*
X344640Y960123D01*
X345670D01*
X345855Y959523D01*
Y959348D01*
X344455D01*
Y959523D01*
G37*
G36*
G01X351865Y959521D02*
X352050Y960121D01*
X353080D01*
X353265Y959521D01*
Y959347D01*
X351865D01*
Y959521D01*
G37*
G36*
G01X340745Y959523D02*
X340930Y960123D01*
X341960D01*
X342145Y959523D01*
Y959348D01*
X340745D01*
Y959523D01*
G37*
G36*
G01X348168Y959521D02*
X348353Y960121D01*
X349383D01*
X349568Y959521D01*
Y959347D01*
X348168D01*
Y959521D01*
G37*
G36*
G01X344455Y959523D02*
X344640Y960123D01*
X345670D01*
X345855Y959523D01*
Y959348D01*
X344455D01*
Y959523D01*
G37*
G36*
G01X351865Y959521D02*
X352050Y960121D01*
X353080D01*
X353265Y959521D01*
Y959347D01*
X351865D01*
Y959521D01*
G37*
G36*
G01X342178Y961131D02*
X341993Y960531D01*
X340963D01*
X340778Y961131D01*
Y961305D01*
X342178D01*
Y961131D01*
G37*
G36*
G01X345902Y961129D02*
X345717Y960529D01*
X344687D01*
X344502Y961129D01*
Y961304D01*
X345902D01*
Y961129D01*
G37*
G36*
G01X349612D02*
X349427Y960529D01*
X348397D01*
X348212Y961129D01*
Y961304D01*
X349612D01*
Y961129D01*
G37*
G36*
G01X353312D02*
X353127Y960529D01*
X352097D01*
X351912Y961129D01*
Y961304D01*
X353312D01*
Y961129D01*
G37*
G36*
G01X342178Y961131D02*
X341993Y960531D01*
X340963D01*
X340778Y961131D01*
Y961305D01*
X342178D01*
Y961131D01*
G37*
G36*
G01X345902Y961129D02*
X345717Y960529D01*
X344687D01*
X344502Y961129D01*
Y961304D01*
X345902D01*
Y961129D01*
G37*
G36*
G01X349612D02*
X349427Y960529D01*
X348397D01*
X348212Y961129D01*
Y961304D01*
X349612D01*
Y961129D01*
G37*
G36*
G01X353312D02*
X353127Y960529D01*
X352097D01*
X351912Y961129D01*
Y961304D01*
X353312D01*
Y961129D01*
G37*
G36*
G01X344062Y957925D02*
X343877Y957325D01*
X342847D01*
X342662Y957925D01*
Y958100D01*
X344062D01*
Y957925D01*
G37*
G36*
G01X340362D02*
X340177Y957325D01*
X339147D01*
X338962Y957925D01*
Y958100D01*
X340362D01*
Y957925D01*
G37*
G36*
G01X347705Y957927D02*
X347520Y957327D01*
X346490D01*
X346305Y957927D01*
Y958101D01*
X347705D01*
Y957927D01*
G37*
G36*
G01X351442D02*
X351257Y957327D01*
X350227D01*
X350042Y957927D01*
Y958101D01*
X351442D01*
Y957927D01*
G37*
G36*
G01X355142D02*
X354957Y957327D01*
X353927D01*
X353742Y957927D01*
Y958101D01*
X355142D01*
Y957927D01*
G37*
G36*
G01X344062Y957925D02*
X343877Y957325D01*
X342847D01*
X342662Y957925D01*
Y958100D01*
X344062D01*
Y957925D01*
G37*
G36*
G01X340362D02*
X340177Y957325D01*
X339147D01*
X338962Y957925D01*
Y958100D01*
X340362D01*
Y957925D01*
G37*
G36*
G01X347705Y957927D02*
X347520Y957327D01*
X346490D01*
X346305Y957927D01*
Y958101D01*
X347705D01*
Y957927D01*
G37*
G36*
G01X351442D02*
X351257Y957327D01*
X350227D01*
X350042Y957927D01*
Y958101D01*
X351442D01*
Y957927D01*
G37*
G36*
G01X355142D02*
X354957Y957327D01*
X353927D01*
X353742Y957927D01*
Y958101D01*
X355142D01*
Y957927D01*
G37*
G36*
G01X342629Y949909D02*
X342814Y950509D01*
X343844D01*
X344029Y949909D01*
Y949734D01*
X342629D01*
Y949909D01*
G37*
G36*
G01X338905D02*
X339090Y950509D01*
X340120D01*
X340305Y949909D01*
Y949735D01*
X338905D01*
Y949909D01*
G37*
G36*
G01X346305D02*
X346490Y950509D01*
X347520D01*
X347705Y949909D01*
Y949734D01*
X346305D01*
Y949909D01*
G37*
G36*
G01X349995D02*
X350180Y950509D01*
X351210D01*
X351395Y949909D01*
Y949735D01*
X349995D01*
Y949909D01*
G37*
G36*
G01X353695D02*
X353880Y950509D01*
X354910D01*
X355095Y949909D01*
Y949735D01*
X353695D01*
Y949909D01*
G37*
G36*
G01X342629D02*
X342814Y950509D01*
X343844D01*
X344029Y949909D01*
Y949734D01*
X342629D01*
Y949909D01*
G37*
G36*
G01X338905D02*
X339090Y950509D01*
X340120D01*
X340305Y949909D01*
Y949735D01*
X338905D01*
Y949909D01*
G37*
G36*
G01X346305D02*
X346490Y950509D01*
X347520D01*
X347705Y949909D01*
Y949734D01*
X346305D01*
Y949909D01*
G37*
G36*
G01X349995D02*
X350180Y950509D01*
X351210D01*
X351395Y949909D01*
Y949735D01*
X349995D01*
Y949909D01*
G37*
G36*
G01X353695D02*
X353880Y950509D01*
X354910D01*
X355095Y949909D01*
Y949735D01*
X353695D01*
Y949909D01*
G37*
G36*
G01X349577Y954723D02*
X349392Y954123D01*
X348362D01*
X348177Y954723D01*
Y954897D01*
X349577D01*
Y954723D01*
G37*
G36*
G01X345879Y954721D02*
X345694Y954121D01*
X344664D01*
X344479Y954721D01*
Y954895D01*
X345879D01*
Y954721D01*
G37*
G36*
G01X342155D02*
X341970Y954121D01*
X340940D01*
X340755Y954721D01*
Y954896D01*
X342155D01*
Y954721D01*
G37*
G36*
G01X353277Y954723D02*
X353092Y954123D01*
X352062D01*
X351877Y954723D01*
Y954897D01*
X353277D01*
Y954723D01*
G37*
G36*
G01X349577D02*
X349392Y954123D01*
X348362D01*
X348177Y954723D01*
Y954897D01*
X349577D01*
Y954723D01*
G37*
G36*
G01X345879Y954721D02*
X345694Y954121D01*
X344664D01*
X344479Y954721D01*
Y954895D01*
X345879D01*
Y954721D01*
G37*
G36*
G01X342155D02*
X341970Y954121D01*
X340940D01*
X340755Y954721D01*
Y954896D01*
X342155D01*
Y954721D01*
G37*
G36*
G01X353277Y954723D02*
X353092Y954123D01*
X352062D01*
X351877Y954723D01*
Y954897D01*
X353277D01*
Y954723D01*
G37*
G36*
G01X348212Y953113D02*
X348397Y953713D01*
X349427D01*
X349612Y953113D01*
Y952939D01*
X348212D01*
Y953113D01*
G37*
G36*
G01X344479D02*
X344664Y953713D01*
X345694D01*
X345879Y953113D01*
Y952939D01*
X344479D01*
Y953113D01*
G37*
G36*
G01X340755D02*
X340940Y953713D01*
X341970D01*
X342155Y953113D01*
Y952938D01*
X340755D01*
Y953113D01*
G37*
G36*
G01X351912D02*
X352097Y953713D01*
X353127D01*
X353312Y953113D01*
Y952939D01*
X351912D01*
Y953113D01*
G37*
G36*
G01X348212D02*
X348397Y953713D01*
X349427D01*
X349612Y953113D01*
Y952939D01*
X348212D01*
Y953113D01*
G37*
G36*
G01X344479D02*
X344664Y953713D01*
X345694D01*
X345879Y953113D01*
Y952939D01*
X344479D01*
Y953113D01*
G37*
G36*
G01X340755D02*
X340940Y953713D01*
X341970D01*
X342155Y953113D01*
Y952938D01*
X340755D01*
Y953113D01*
G37*
G36*
G01X351912D02*
X352097Y953713D01*
X353127D01*
X353312Y953113D01*
Y952939D01*
X351912D01*
Y953113D01*
G37*
G36*
G01X346305Y956317D02*
X346490Y956917D01*
X347520D01*
X347705Y956317D01*
Y956143D01*
X346305D01*
Y956317D01*
G37*
G36*
G01X349995Y956319D02*
X350180Y956919D01*
X351210D01*
X351395Y956319D01*
Y956144D01*
X349995D01*
Y956319D01*
G37*
G36*
G01X342662D02*
X342847Y956919D01*
X343877D01*
X344062Y956319D01*
Y956144D01*
X342662D01*
Y956319D01*
G37*
G36*
G01X338929Y956317D02*
X339114Y956917D01*
X340144D01*
X340329Y956317D01*
Y956143D01*
X338929D01*
Y956317D01*
G37*
G36*
G01X353695Y956319D02*
X353880Y956919D01*
X354910D01*
X355095Y956319D01*
Y956144D01*
X353695D01*
Y956319D01*
G37*
G36*
G01X346305Y956317D02*
X346490Y956917D01*
X347520D01*
X347705Y956317D01*
Y956143D01*
X346305D01*
Y956317D01*
G37*
G36*
G01X349995Y956319D02*
X350180Y956919D01*
X351210D01*
X351395Y956319D01*
Y956144D01*
X349995D01*
Y956319D01*
G37*
G36*
G01X342662D02*
X342847Y956919D01*
X343877D01*
X344062Y956319D01*
Y956144D01*
X342662D01*
Y956319D01*
G37*
G36*
G01X338929Y956317D02*
X339114Y956917D01*
X340144D01*
X340329Y956317D01*
Y956143D01*
X338929D01*
Y956317D01*
G37*
G36*
G01X353695Y956319D02*
X353880Y956919D01*
X354910D01*
X355095Y956319D01*
Y956144D01*
X353695D01*
Y956319D01*
G37*
G36*
G01X344062Y951517D02*
X343877Y950917D01*
X342847D01*
X342662Y951517D01*
Y951691D01*
X344062D01*
Y951517D01*
G37*
G36*
G01X340295D02*
X340110Y950917D01*
X339080D01*
X338895Y951517D01*
Y951691D01*
X340295D01*
Y951517D01*
G37*
G36*
G01X347696D02*
X347511Y950917D01*
X346481D01*
X346296Y951517D01*
Y951691D01*
X347696D01*
Y951517D01*
G37*
G36*
G01X351395D02*
X351210Y950917D01*
X350180D01*
X349995Y951517D01*
Y951691D01*
X351395D01*
Y951517D01*
G37*
G36*
G01X355095D02*
X354910Y950917D01*
X353880D01*
X353695Y951517D01*
Y951691D01*
X355095D01*
Y951517D01*
G37*
G36*
G01X344062D02*
X343877Y950917D01*
X342847D01*
X342662Y951517D01*
Y951691D01*
X344062D01*
Y951517D01*
G37*
G36*
G01X340295D02*
X340110Y950917D01*
X339080D01*
X338895Y951517D01*
Y951691D01*
X340295D01*
Y951517D01*
G37*
G36*
G01X347696D02*
X347511Y950917D01*
X346481D01*
X346296Y951517D01*
Y951691D01*
X347696D01*
Y951517D01*
G37*
G36*
G01X351395D02*
X351210Y950917D01*
X350180D01*
X349995Y951517D01*
Y951691D01*
X351395D01*
Y951517D01*
G37*
G36*
G01X355095D02*
X354910Y950917D01*
X353880D01*
X353695Y951517D01*
Y951691D01*
X355095D01*
Y951517D01*
G37*
G36*
G01X343995Y964333D02*
X343810Y963733D01*
X342780D01*
X342595Y964333D01*
Y964508D01*
X343995D01*
Y964333D01*
G37*
G36*
G01X340295D02*
X340110Y963733D01*
X339080D01*
X338895Y964333D01*
Y964508D01*
X340295D01*
Y964333D01*
G37*
G36*
G01X347695D02*
X347510Y963733D01*
X346480D01*
X346295Y964333D01*
Y964508D01*
X347695D01*
Y964333D01*
G37*
G36*
G01X351395D02*
X351210Y963733D01*
X350180D01*
X349995Y964333D01*
Y964508D01*
X351395D01*
Y964333D01*
G37*
G36*
G01X355105D02*
X354920Y963733D01*
X353890D01*
X353705Y964333D01*
Y964508D01*
X355105D01*
Y964333D01*
G37*
G36*
G01X343995D02*
X343810Y963733D01*
X342780D01*
X342595Y964333D01*
Y964508D01*
X343995D01*
Y964333D01*
G37*
G36*
G01X340295D02*
X340110Y963733D01*
X339080D01*
X338895Y964333D01*
Y964508D01*
X340295D01*
Y964333D01*
G37*
G36*
G01X347695D02*
X347510Y963733D01*
X346480D01*
X346295Y964333D01*
Y964508D01*
X347695D01*
Y964333D01*
G37*
G36*
G01X351395D02*
X351210Y963733D01*
X350180D01*
X349995Y964333D01*
Y964508D01*
X351395D01*
Y964333D01*
G37*
G36*
G01X355105D02*
X354920Y963733D01*
X353890D01*
X353705Y964333D01*
Y964508D01*
X355105D01*
Y964333D01*
G37*
G36*
G01X341619Y977714D02*
X341007Y977574D01*
X340492Y978466D01*
X340919Y978926D01*
X341070Y979013D01*
X341770Y977801D01*
X341619Y977714D01*
G37*
G36*
G01X344029Y977151D02*
X343844Y976551D01*
X342814D01*
X342629Y977151D01*
Y977326D01*
X344029D01*
Y977151D01*
G37*
G36*
G01X347705D02*
X347520Y976551D01*
X346490D01*
X346305Y977151D01*
Y977326D01*
X347705D01*
Y977151D01*
G37*
G36*
G01X351405D02*
X351220Y976551D01*
X350190D01*
X350005Y977151D01*
Y977325D01*
X351405D01*
Y977151D01*
G37*
G36*
G01X355105D02*
X354920Y976551D01*
X353890D01*
X353705Y977151D01*
Y977326D01*
X355105D01*
Y977151D01*
G37*
G36*
G01X341619Y977714D02*
X341007Y977574D01*
X340492Y978466D01*
X340919Y978926D01*
X341070Y979013D01*
X341770Y977801D01*
X341619Y977714D01*
G37*
G36*
G01X344029Y977151D02*
X343844Y976551D01*
X342814D01*
X342629Y977151D01*
Y977326D01*
X344029D01*
Y977151D01*
G37*
G36*
G01X347705D02*
X347520Y976551D01*
X346490D01*
X346305Y977151D01*
Y977326D01*
X347705D01*
Y977151D01*
G37*
G36*
G01X351405D02*
X351220Y976551D01*
X350190D01*
X350005Y977151D01*
Y977325D01*
X351405D01*
Y977151D01*
G37*
G36*
G01X355105D02*
X354920Y976551D01*
X353890D01*
X353705Y977151D01*
Y977326D01*
X355105D01*
Y977151D01*
G37*
G36*
G01X338929Y975543D02*
X339114Y976143D01*
X340144D01*
X340329Y975543D01*
Y975368D01*
X338929D01*
Y975543D01*
G37*
G36*
G01X342629D02*
X342814Y976143D01*
X343844D01*
X344029Y975543D01*
Y975368D01*
X342629D01*
Y975543D01*
G37*
G36*
G01X346305D02*
X346490Y976143D01*
X347520D01*
X347705Y975543D01*
Y975368D01*
X346305D01*
Y975543D01*
G37*
G36*
G01X350005D02*
X350190Y976143D01*
X351220D01*
X351405Y975543D01*
Y975369D01*
X350005D01*
Y975543D01*
G37*
G36*
G01X353752D02*
X353937Y976143D01*
X354967D01*
X355152Y975543D01*
Y975368D01*
X353752D01*
Y975543D01*
G37*
G36*
G01X338929D02*
X339114Y976143D01*
X340144D01*
X340329Y975543D01*
Y975368D01*
X338929D01*
Y975543D01*
G37*
G36*
G01X342629D02*
X342814Y976143D01*
X343844D01*
X344029Y975543D01*
Y975368D01*
X342629D01*
Y975543D01*
G37*
G36*
G01X346305D02*
X346490Y976143D01*
X347520D01*
X347705Y975543D01*
Y975368D01*
X346305D01*
Y975543D01*
G37*
G36*
G01X350005D02*
X350190Y976143D01*
X351220D01*
X351405Y975543D01*
Y975369D01*
X350005D01*
Y975543D01*
G37*
G36*
G01X353752D02*
X353937Y976143D01*
X354967D01*
X355152Y975543D01*
Y975368D01*
X353752D01*
Y975543D01*
G37*
G36*
G01X338895Y981953D02*
X339080Y982553D01*
X340110D01*
X340295Y981953D01*
Y981778D01*
X338895D01*
Y981953D01*
G37*
G36*
G01X341364Y981346D02*
X341976Y981486D01*
X342491Y980594D01*
X342064Y980134D01*
X341913Y980047D01*
X341213Y981259D01*
X341364Y981346D01*
G37*
G36*
G01X348212Y978749D02*
X348397Y979349D01*
X349427D01*
X349612Y978749D01*
Y978574D01*
X348212D01*
Y978749D01*
G37*
G36*
G01X344479Y978747D02*
X344664Y979347D01*
X345694D01*
X345879Y978747D01*
Y978573D01*
X344479D01*
Y978747D01*
G37*
G36*
G01X351879D02*
X352064Y979347D01*
X353094D01*
X353279Y978747D01*
Y978573D01*
X351879D01*
Y978747D01*
G37*
G36*
G01X338895Y981953D02*
X339080Y982553D01*
X340110D01*
X340295Y981953D01*
Y981778D01*
X338895D01*
Y981953D01*
G37*
G36*
G01X341364Y981346D02*
X341976Y981486D01*
X342491Y980594D01*
X342064Y980134D01*
X341913Y980047D01*
X341213Y981259D01*
X341364Y981346D01*
G37*
G36*
G01X348212Y978749D02*
X348397Y979349D01*
X349427D01*
X349612Y978749D01*
Y978574D01*
X348212D01*
Y978749D01*
G37*
G36*
G01X344479Y978747D02*
X344664Y979347D01*
X345694D01*
X345879Y978747D01*
Y978573D01*
X344479D01*
Y978747D01*
G37*
G36*
G01X351879D02*
X352064Y979347D01*
X353094D01*
X353279Y978747D01*
Y978573D01*
X351879D01*
Y978747D01*
G37*
G36*
G01X342179Y973947D02*
X341994Y973347D01*
X340964D01*
X340779Y973947D01*
Y974122D01*
X342179D01*
Y973947D01*
G37*
G36*
G01X349612D02*
X349427Y973347D01*
X348397D01*
X348212Y973947D01*
Y974121D01*
X349612D01*
Y973947D01*
G37*
G36*
G01X345879D02*
X345694Y973347D01*
X344664D01*
X344479Y973947D01*
Y974122D01*
X345879D01*
Y973947D01*
G37*
G36*
G01X353255D02*
X353070Y973347D01*
X352040D01*
X351855Y973947D01*
Y974122D01*
X353255D01*
Y973947D01*
G37*
G36*
G01X342179D02*
X341994Y973347D01*
X340964D01*
X340779Y973947D01*
Y974122D01*
X342179D01*
Y973947D01*
G37*
G36*
G01X349612D02*
X349427Y973347D01*
X348397D01*
X348212Y973947D01*
Y974121D01*
X349612D01*
Y973947D01*
G37*
G36*
G01X345879D02*
X345694Y973347D01*
X344664D01*
X344479Y973947D01*
Y974122D01*
X345879D01*
Y973947D01*
G37*
G36*
G01X353255D02*
X353070Y973347D01*
X352040D01*
X351855Y973947D01*
Y974122D01*
X353255D01*
Y973947D01*
G37*
G36*
G01X340812Y965931D02*
X340997Y966531D01*
X342027D01*
X342212Y965931D01*
Y965757D01*
X340812D01*
Y965931D01*
G37*
G36*
G01X348212D02*
X348397Y966531D01*
X349427D01*
X349612Y965931D01*
Y965757D01*
X348212D01*
Y965931D01*
G37*
G36*
G01X344512D02*
X344697Y966531D01*
X345727D01*
X345912Y965931D01*
Y965757D01*
X344512D01*
Y965931D01*
G37*
G36*
G01X351912D02*
X352097Y966531D01*
X353127D01*
X353312Y965931D01*
Y965757D01*
X351912D01*
Y965931D01*
G37*
G36*
G01X340812D02*
X340997Y966531D01*
X342027D01*
X342212Y965931D01*
Y965757D01*
X340812D01*
Y965931D01*
G37*
G36*
G01X348212D02*
X348397Y966531D01*
X349427D01*
X349612Y965931D01*
Y965757D01*
X348212D01*
Y965931D01*
G37*
G36*
G01X344512D02*
X344697Y966531D01*
X345727D01*
X345912Y965931D01*
Y965757D01*
X344512D01*
Y965931D01*
G37*
G36*
G01X351912D02*
X352097Y966531D01*
X353127D01*
X353312Y965931D01*
Y965757D01*
X351912D01*
Y965931D01*
G37*
G36*
G01X338929Y969135D02*
X339114Y969735D01*
X340144D01*
X340329Y969135D01*
Y968960D01*
X338929D01*
Y969135D01*
G37*
G36*
G01X342629D02*
X342814Y969735D01*
X343844D01*
X344029Y969135D01*
Y968960D01*
X342629D01*
Y969135D01*
G37*
G36*
G01X346305D02*
X346490Y969735D01*
X347520D01*
X347705Y969135D01*
Y968960D01*
X346305D01*
Y969135D01*
G37*
G36*
G01X349995D02*
X350180Y969735D01*
X351210D01*
X351395Y969135D01*
Y968961D01*
X349995D01*
Y969135D01*
G37*
G36*
G01X353695D02*
X353880Y969735D01*
X354910D01*
X355095Y969135D01*
Y968961D01*
X353695D01*
Y969135D01*
G37*
G36*
G01X338929D02*
X339114Y969735D01*
X340144D01*
X340329Y969135D01*
Y968960D01*
X338929D01*
Y969135D01*
G37*
G36*
G01X342629D02*
X342814Y969735D01*
X343844D01*
X344029Y969135D01*
Y968960D01*
X342629D01*
Y969135D01*
G37*
G36*
G01X346305D02*
X346490Y969735D01*
X347520D01*
X347705Y969135D01*
Y968960D01*
X346305D01*
Y969135D01*
G37*
G36*
G01X349995D02*
X350180Y969735D01*
X351210D01*
X351395Y969135D01*
Y968961D01*
X349995D01*
Y969135D01*
G37*
G36*
G01X353695D02*
X353880Y969735D01*
X354910D01*
X355095Y969135D01*
Y968961D01*
X353695D01*
Y969135D01*
G37*
G36*
G01X342179Y967539D02*
X341994Y966939D01*
X340964D01*
X340779Y967539D01*
Y967714D01*
X342179D01*
Y967539D01*
G37*
G36*
G01X345879D02*
X345694Y966939D01*
X344664D01*
X344479Y967539D01*
Y967714D01*
X345879D01*
Y967539D01*
G37*
G36*
G01X349612D02*
X349427Y966939D01*
X348397D01*
X348212Y967539D01*
Y967713D01*
X349612D01*
Y967539D01*
G37*
G36*
G01X353312D02*
X353127Y966939D01*
X352097D01*
X351912Y967539D01*
Y967713D01*
X353312D01*
Y967539D01*
G37*
G36*
G01X342179D02*
X341994Y966939D01*
X340964D01*
X340779Y967539D01*
Y967714D01*
X342179D01*
Y967539D01*
G37*
G36*
G01X345879D02*
X345694Y966939D01*
X344664D01*
X344479Y967539D01*
Y967714D01*
X345879D01*
Y967539D01*
G37*
G36*
G01X349612D02*
X349427Y966939D01*
X348397D01*
X348212Y967539D01*
Y967713D01*
X349612D01*
Y967539D01*
G37*
G36*
G01X353312D02*
X353127Y966939D01*
X352097D01*
X351912Y967539D01*
Y967713D01*
X353312D01*
Y967539D01*
G37*
G36*
G01X341211Y1005289D02*
X341396Y1005889D01*
X342426D01*
X342611Y1005289D01*
Y1005114D01*
X341211D01*
Y1005289D01*
G37*
G36*
G01X348635D02*
X348820Y1005889D01*
X349850D01*
X350035Y1005289D01*
Y1005115D01*
X348635D01*
Y1005289D01*
G37*
G36*
G01X344911D02*
X345096Y1005889D01*
X346126D01*
X346311Y1005289D01*
Y1005114D01*
X344911D01*
Y1005289D01*
G37*
G36*
G01X352335D02*
X352520Y1005889D01*
X353550D01*
X353735Y1005289D01*
Y1005114D01*
X352335D01*
Y1005289D01*
G37*
G36*
G01X341211D02*
X341396Y1005889D01*
X342426D01*
X342611Y1005289D01*
Y1005114D01*
X341211D01*
Y1005289D01*
G37*
G36*
G01X348635D02*
X348820Y1005889D01*
X349850D01*
X350035Y1005289D01*
Y1005115D01*
X348635D01*
Y1005289D01*
G37*
G36*
G01X344911D02*
X345096Y1005889D01*
X346126D01*
X346311Y1005289D01*
Y1005114D01*
X344911D01*
Y1005289D01*
G37*
G36*
G01X352335D02*
X352520Y1005889D01*
X353550D01*
X353735Y1005289D01*
Y1005114D01*
X352335D01*
Y1005289D01*
G37*
G36*
G01X343061Y1002083D02*
X343246Y1002683D01*
X344276D01*
X344461Y1002083D01*
Y1001909D01*
X343061D01*
Y1002083D01*
G37*
G36*
G01X339361D02*
X339546Y1002683D01*
X340576D01*
X340761Y1002083D01*
Y1001909D01*
X339361D01*
Y1002083D01*
G37*
G36*
G01X346761D02*
X346946Y1002683D01*
X347976D01*
X348161Y1002083D01*
Y1001909D01*
X346761D01*
Y1002083D01*
G37*
G36*
G01X350461D02*
X350646Y1002683D01*
X351676D01*
X351861Y1002083D01*
Y1001909D01*
X350461D01*
Y1002083D01*
G37*
G36*
G01X354161D02*
X354346Y1002683D01*
X355376D01*
X355561Y1002083D01*
Y1001909D01*
X354161D01*
Y1002083D01*
G37*
G36*
G01X343061D02*
X343246Y1002683D01*
X344276D01*
X344461Y1002083D01*
Y1001909D01*
X343061D01*
Y1002083D01*
G37*
G36*
G01X339361D02*
X339546Y1002683D01*
X340576D01*
X340761Y1002083D01*
Y1001909D01*
X339361D01*
Y1002083D01*
G37*
G36*
G01X346761D02*
X346946Y1002683D01*
X347976D01*
X348161Y1002083D01*
Y1001909D01*
X346761D01*
Y1002083D01*
G37*
G36*
G01X350461D02*
X350646Y1002683D01*
X351676D01*
X351861Y1002083D01*
Y1001909D01*
X350461D01*
Y1002083D01*
G37*
G36*
G01X354161D02*
X354346Y1002683D01*
X355376D01*
X355561Y1002083D01*
Y1001909D01*
X354161D01*
Y1002083D01*
G37*
G36*
G01X340761Y1003693D02*
X340576Y1003093D01*
X339546D01*
X339361Y1003693D01*
Y1003867D01*
X340761D01*
Y1003693D01*
G37*
G36*
G01X348161D02*
X347976Y1003093D01*
X346946D01*
X346761Y1003693D01*
Y1003867D01*
X348161D01*
Y1003693D01*
G37*
G36*
G01X351828Y1003691D02*
X351643Y1003091D01*
X350613D01*
X350428Y1003691D01*
Y1003866D01*
X351828D01*
Y1003691D01*
G37*
G36*
G01X344461Y1003693D02*
X344276Y1003093D01*
X343246D01*
X343061Y1003693D01*
Y1003867D01*
X344461D01*
Y1003693D01*
G37*
G36*
G01X355561D02*
X355376Y1003093D01*
X354346D01*
X354161Y1003693D01*
Y1003867D01*
X355561D01*
Y1003693D01*
G37*
G36*
G01X340761D02*
X340576Y1003093D01*
X339546D01*
X339361Y1003693D01*
Y1003867D01*
X340761D01*
Y1003693D01*
G37*
G36*
G01X348161D02*
X347976Y1003093D01*
X346946D01*
X346761Y1003693D01*
Y1003867D01*
X348161D01*
Y1003693D01*
G37*
G36*
G01X351828Y1003691D02*
X351643Y1003091D01*
X350613D01*
X350428Y1003691D01*
Y1003866D01*
X351828D01*
Y1003691D01*
G37*
G36*
G01X344461Y1003693D02*
X344276Y1003093D01*
X343246D01*
X343061Y1003693D01*
Y1003867D01*
X344461D01*
Y1003693D01*
G37*
G36*
G01X355561D02*
X355376Y1003093D01*
X354346D01*
X354161Y1003693D01*
Y1003867D01*
X355561D01*
Y1003693D01*
G37*
G36*
G01X342611Y1000489D02*
X342426Y999889D01*
X341396D01*
X341211Y1000489D01*
Y1000663D01*
X342611D01*
Y1000489D01*
G37*
G36*
G01X350011D02*
X349826Y999889D01*
X348796D01*
X348611Y1000489D01*
Y1000663D01*
X350011D01*
Y1000489D01*
G37*
G36*
G01X346311D02*
X346126Y999889D01*
X345096D01*
X344911Y1000489D01*
Y1000663D01*
X346311D01*
Y1000489D01*
G37*
G36*
G01X353711D02*
X353526Y999889D01*
X352496D01*
X352311Y1000489D01*
Y1000663D01*
X353711D01*
Y1000489D01*
G37*
G36*
G01X342611D02*
X342426Y999889D01*
X341396D01*
X341211Y1000489D01*
Y1000663D01*
X342611D01*
Y1000489D01*
G37*
G36*
G01X350011D02*
X349826Y999889D01*
X348796D01*
X348611Y1000489D01*
Y1000663D01*
X350011D01*
Y1000489D01*
G37*
G36*
G01X346311D02*
X346126Y999889D01*
X345096D01*
X344911Y1000489D01*
Y1000663D01*
X346311D01*
Y1000489D01*
G37*
G36*
G01X353711D02*
X353526Y999889D01*
X352496D01*
X352311Y1000489D01*
Y1000663D01*
X353711D01*
Y1000489D01*
G37*
G36*
G01X341211Y1011697D02*
X341396Y1012297D01*
X342426D01*
X342611Y1011697D01*
Y1011522D01*
X341211D01*
Y1011697D01*
G37*
G36*
G01X344911D02*
X345096Y1012297D01*
X346126D01*
X346311Y1011697D01*
Y1011522D01*
X344911D01*
Y1011697D01*
G37*
G36*
G01X348611D02*
X348796Y1012297D01*
X349826D01*
X350011Y1011697D01*
Y1011522D01*
X348611D01*
Y1011697D01*
G37*
G36*
G01X352311D02*
X352496Y1012297D01*
X353526D01*
X353711Y1011697D01*
Y1011522D01*
X352311D01*
Y1011697D01*
G37*
G36*
G01X341211D02*
X341396Y1012297D01*
X342426D01*
X342611Y1011697D01*
Y1011522D01*
X341211D01*
Y1011697D01*
G37*
G36*
G01X344911D02*
X345096Y1012297D01*
X346126D01*
X346311Y1011697D01*
Y1011522D01*
X344911D01*
Y1011697D01*
G37*
G36*
G01X348611D02*
X348796Y1012297D01*
X349826D01*
X350011Y1011697D01*
Y1011522D01*
X348611D01*
Y1011697D01*
G37*
G36*
G01X352311D02*
X352496Y1012297D01*
X353526D01*
X353711Y1011697D01*
Y1011522D01*
X352311D01*
Y1011697D01*
G37*
G36*
G01X339361Y1008493D02*
X339546Y1009093D01*
X340576D01*
X340761Y1008493D01*
Y1008318D01*
X339361D01*
Y1008493D01*
G37*
G36*
G01X343061D02*
X343246Y1009093D01*
X344276D01*
X344461Y1008493D01*
Y1008318D01*
X343061D01*
Y1008493D01*
G37*
G36*
G01X346761D02*
X346946Y1009093D01*
X347976D01*
X348161Y1008493D01*
Y1008318D01*
X346761D01*
Y1008493D01*
G37*
G36*
G01X350428D02*
X350613Y1009093D01*
X351643D01*
X351828Y1008493D01*
Y1008319D01*
X350428D01*
Y1008493D01*
G37*
G36*
G01X354161D02*
X354346Y1009093D01*
X355376D01*
X355561Y1008493D01*
Y1008318D01*
X354161D01*
Y1008493D01*
G37*
G36*
G01X339361D02*
X339546Y1009093D01*
X340576D01*
X340761Y1008493D01*
Y1008318D01*
X339361D01*
Y1008493D01*
G37*
G36*
G01X343061D02*
X343246Y1009093D01*
X344276D01*
X344461Y1008493D01*
Y1008318D01*
X343061D01*
Y1008493D01*
G37*
G36*
G01X346761D02*
X346946Y1009093D01*
X347976D01*
X348161Y1008493D01*
Y1008318D01*
X346761D01*
Y1008493D01*
G37*
G36*
G01X350428D02*
X350613Y1009093D01*
X351643D01*
X351828Y1008493D01*
Y1008319D01*
X350428D01*
Y1008493D01*
G37*
G36*
G01X354161D02*
X354346Y1009093D01*
X355376D01*
X355561Y1008493D01*
Y1008318D01*
X354161D01*
Y1008493D01*
G37*
G36*
G01X340761Y1010101D02*
X340576Y1009501D01*
X339546D01*
X339361Y1010101D01*
Y1010276D01*
X340761D01*
Y1010101D01*
G37*
G36*
G01X344461D02*
X344276Y1009501D01*
X343246D01*
X343061Y1010101D01*
Y1010276D01*
X344461D01*
Y1010101D01*
G37*
G36*
G01X348161D02*
X347976Y1009501D01*
X346946D01*
X346761Y1010101D01*
Y1010276D01*
X348161D01*
Y1010101D01*
G37*
G36*
G01X351861D02*
X351676Y1009501D01*
X350646D01*
X350461Y1010101D01*
Y1010276D01*
X351861D01*
Y1010101D01*
G37*
G36*
G01X355561D02*
X355376Y1009501D01*
X354346D01*
X354161Y1010101D01*
Y1010276D01*
X355561D01*
Y1010101D01*
G37*
G36*
G01X340761D02*
X340576Y1009501D01*
X339546D01*
X339361Y1010101D01*
Y1010276D01*
X340761D01*
Y1010101D01*
G37*
G36*
G01X344461D02*
X344276Y1009501D01*
X343246D01*
X343061Y1010101D01*
Y1010276D01*
X344461D01*
Y1010101D01*
G37*
G36*
G01X348161D02*
X347976Y1009501D01*
X346946D01*
X346761Y1010101D01*
Y1010276D01*
X348161D01*
Y1010101D01*
G37*
G36*
G01X351861D02*
X351676Y1009501D01*
X350646D01*
X350461Y1010101D01*
Y1010276D01*
X351861D01*
Y1010101D01*
G37*
G36*
G01X355561D02*
X355376Y1009501D01*
X354346D01*
X354161Y1010101D01*
Y1010276D01*
X355561D01*
Y1010101D01*
G37*
G36*
G01X342611Y1006897D02*
X342426Y1006297D01*
X341396D01*
X341211Y1006897D01*
Y1007072D01*
X342611D01*
Y1006897D01*
G37*
G36*
G01X346311D02*
X346126Y1006297D01*
X345096D01*
X344911Y1006897D01*
Y1007072D01*
X346311D01*
Y1006897D01*
G37*
G36*
G01X350035D02*
X349850Y1006297D01*
X348820D01*
X348635Y1006897D01*
Y1007071D01*
X350035D01*
Y1006897D01*
G37*
G36*
G01X353735D02*
X353550Y1006297D01*
X352520D01*
X352335Y1006897D01*
Y1007072D01*
X353735D01*
Y1006897D01*
G37*
G36*
G01X342611D02*
X342426Y1006297D01*
X341396D01*
X341211Y1006897D01*
Y1007072D01*
X342611D01*
Y1006897D01*
G37*
G36*
G01X346311D02*
X346126Y1006297D01*
X345096D01*
X344911Y1006897D01*
Y1007072D01*
X346311D01*
Y1006897D01*
G37*
G36*
G01X350035D02*
X349850Y1006297D01*
X348820D01*
X348635Y1006897D01*
Y1007071D01*
X350035D01*
Y1006897D01*
G37*
G36*
G01X353735D02*
X353550Y1006297D01*
X352520D01*
X352335Y1006897D01*
Y1007072D01*
X353735D01*
Y1006897D01*
G37*
G36*
G01X344461Y1029327D02*
X344276Y1028727D01*
X343246D01*
X343061Y1029327D01*
Y1029502D01*
X344461D01*
Y1029327D01*
G37*
G36*
G01X340761D02*
X340576Y1028727D01*
X339546D01*
X339361Y1029327D01*
Y1029502D01*
X340761D01*
Y1029327D01*
G37*
G36*
G01X348161D02*
X347976Y1028727D01*
X346946D01*
X346761Y1029327D01*
Y1029502D01*
X348161D01*
Y1029327D01*
G37*
G36*
G01X351828Y1029325D02*
X351643Y1028725D01*
X350613D01*
X350428Y1029325D01*
Y1029500D01*
X351828D01*
Y1029325D01*
G37*
G36*
G01X355561Y1029327D02*
X355376Y1028727D01*
X354346D01*
X354161Y1029327D01*
Y1029502D01*
X355561D01*
Y1029327D01*
G37*
G36*
G01X344461D02*
X344276Y1028727D01*
X343246D01*
X343061Y1029327D01*
Y1029502D01*
X344461D01*
Y1029327D01*
G37*
G36*
G01X340761D02*
X340576Y1028727D01*
X339546D01*
X339361Y1029327D01*
Y1029502D01*
X340761D01*
Y1029327D01*
G37*
G36*
G01X348161D02*
X347976Y1028727D01*
X346946D01*
X346761Y1029327D01*
Y1029502D01*
X348161D01*
Y1029327D01*
G37*
G36*
G01X351828Y1029325D02*
X351643Y1028725D01*
X350613D01*
X350428Y1029325D01*
Y1029500D01*
X351828D01*
Y1029325D01*
G37*
G36*
G01X355561Y1029327D02*
X355376Y1028727D01*
X354346D01*
X354161Y1029327D01*
Y1029502D01*
X355561D01*
Y1029327D01*
G37*
G36*
G01X342611Y1019715D02*
X342426Y1019115D01*
X341396D01*
X341211Y1019715D01*
Y1019889D01*
X342611D01*
Y1019715D01*
G37*
G36*
G01X346311D02*
X346126Y1019115D01*
X345096D01*
X344911Y1019715D01*
Y1019889D01*
X346311D01*
Y1019715D01*
G37*
G36*
G01X350011D02*
X349826Y1019115D01*
X348796D01*
X348611Y1019715D01*
Y1019889D01*
X350011D01*
Y1019715D01*
G37*
G36*
G01X353711D02*
X353526Y1019115D01*
X352496D01*
X352311Y1019715D01*
Y1019889D01*
X353711D01*
Y1019715D01*
G37*
G36*
G01X342611D02*
X342426Y1019115D01*
X341396D01*
X341211Y1019715D01*
Y1019889D01*
X342611D01*
Y1019715D01*
G37*
G36*
G01X346311D02*
X346126Y1019115D01*
X345096D01*
X344911Y1019715D01*
Y1019889D01*
X346311D01*
Y1019715D01*
G37*
G36*
G01X350011D02*
X349826Y1019115D01*
X348796D01*
X348611Y1019715D01*
Y1019889D01*
X350011D01*
Y1019715D01*
G37*
G36*
G01X353711D02*
X353526Y1019115D01*
X352496D01*
X352311Y1019715D01*
Y1019889D01*
X353711D01*
Y1019715D01*
G37*
G36*
G01X344461Y1016509D02*
X344276Y1015909D01*
X343246D01*
X343061Y1016509D01*
Y1016684D01*
X344461D01*
Y1016509D01*
G37*
G36*
G01X348161D02*
X347976Y1015909D01*
X346946D01*
X346761Y1016509D01*
Y1016684D01*
X348161D01*
Y1016509D01*
G37*
G36*
G01X351861D02*
X351676Y1015909D01*
X350646D01*
X350461Y1016509D01*
Y1016684D01*
X351861D01*
Y1016509D01*
G37*
G36*
G01X340761D02*
X340576Y1015909D01*
X339546D01*
X339361Y1016509D01*
Y1016684D01*
X340761D01*
Y1016509D01*
G37*
G36*
G01X344461D02*
X344276Y1015909D01*
X343246D01*
X343061Y1016509D01*
Y1016684D01*
X344461D01*
Y1016509D01*
G37*
G36*
G01X348161D02*
X347976Y1015909D01*
X346946D01*
X346761Y1016509D01*
Y1016684D01*
X348161D01*
Y1016509D01*
G37*
G36*
G01X351861D02*
X351676Y1015909D01*
X350646D01*
X350461Y1016509D01*
Y1016684D01*
X351861D01*
Y1016509D01*
G37*
G36*
G01X340761D02*
X340576Y1015909D01*
X339546D01*
X339361Y1016509D01*
Y1016684D01*
X340761D01*
Y1016509D01*
G37*
G36*
G01X339361Y1021309D02*
X339546Y1021909D01*
X340576D01*
X340761Y1021309D01*
Y1021135D01*
X339361D01*
Y1021309D01*
G37*
G36*
G01X343061D02*
X343246Y1021909D01*
X344276D01*
X344461Y1021309D01*
Y1021135D01*
X343061D01*
Y1021309D01*
G37*
G36*
G01X346761D02*
X346946Y1021909D01*
X347976D01*
X348161Y1021309D01*
Y1021135D01*
X346761D01*
Y1021309D01*
G37*
G36*
G01X350461D02*
X350646Y1021909D01*
X351676D01*
X351861Y1021309D01*
Y1021135D01*
X350461D01*
Y1021309D01*
G37*
G36*
G01X354161D02*
X354346Y1021909D01*
X355376D01*
X355561Y1021309D01*
Y1021135D01*
X354161D01*
Y1021309D01*
G37*
G36*
G01X339361D02*
X339546Y1021909D01*
X340576D01*
X340761Y1021309D01*
Y1021135D01*
X339361D01*
Y1021309D01*
G37*
G36*
G01X343061D02*
X343246Y1021909D01*
X344276D01*
X344461Y1021309D01*
Y1021135D01*
X343061D01*
Y1021309D01*
G37*
G36*
G01X346761D02*
X346946Y1021909D01*
X347976D01*
X348161Y1021309D01*
Y1021135D01*
X346761D01*
Y1021309D01*
G37*
G36*
G01X350461D02*
X350646Y1021909D01*
X351676D01*
X351861Y1021309D01*
Y1021135D01*
X350461D01*
Y1021309D01*
G37*
G36*
G01X354161D02*
X354346Y1021909D01*
X355376D01*
X355561Y1021309D01*
Y1021135D01*
X354161D01*
Y1021309D01*
G37*
G36*
G01X341211Y1018105D02*
X341396Y1018705D01*
X342426D01*
X342611Y1018105D01*
Y1017931D01*
X341211D01*
Y1018105D01*
G37*
G36*
G01X344911D02*
X345096Y1018705D01*
X346126D01*
X346311Y1018105D01*
Y1017931D01*
X344911D01*
Y1018105D01*
G37*
G36*
G01X348611D02*
X348796Y1018705D01*
X349826D01*
X350011Y1018105D01*
Y1017931D01*
X348611D01*
Y1018105D01*
G37*
G36*
G01X352311D02*
X352496Y1018705D01*
X353526D01*
X353711Y1018105D01*
Y1017931D01*
X352311D01*
Y1018105D01*
G37*
G36*
G01X341211D02*
X341396Y1018705D01*
X342426D01*
X342611Y1018105D01*
Y1017931D01*
X341211D01*
Y1018105D01*
G37*
G36*
G01X344911D02*
X345096Y1018705D01*
X346126D01*
X346311Y1018105D01*
Y1017931D01*
X344911D01*
Y1018105D01*
G37*
G36*
G01X348611D02*
X348796Y1018705D01*
X349826D01*
X350011Y1018105D01*
Y1017931D01*
X348611D01*
Y1018105D01*
G37*
G36*
G01X352311D02*
X352496Y1018705D01*
X353526D01*
X353711Y1018105D01*
Y1017931D01*
X352311D01*
Y1018105D01*
G37*
G36*
G01X344461Y1022919D02*
X344276Y1022319D01*
X343246D01*
X343061Y1022919D01*
Y1023093D01*
X344461D01*
Y1022919D01*
G37*
G36*
G01X340761D02*
X340576Y1022319D01*
X339546D01*
X339361Y1022919D01*
Y1023093D01*
X340761D01*
Y1022919D01*
G37*
G36*
G01X348161D02*
X347976Y1022319D01*
X346946D01*
X346761Y1022919D01*
Y1023093D01*
X348161D01*
Y1022919D01*
G37*
G36*
G01X351828Y1022917D02*
X351643Y1022317D01*
X350613D01*
X350428Y1022917D01*
Y1023092D01*
X351828D01*
Y1022917D01*
G37*
G36*
G01X355528D02*
X355343Y1022317D01*
X354313D01*
X354128Y1022917D01*
Y1023092D01*
X355528D01*
Y1022917D01*
G37*
G36*
G01X344461Y1022919D02*
X344276Y1022319D01*
X343246D01*
X343061Y1022919D01*
Y1023093D01*
X344461D01*
Y1022919D01*
G37*
G36*
G01X340761D02*
X340576Y1022319D01*
X339546D01*
X339361Y1022919D01*
Y1023093D01*
X340761D01*
Y1022919D01*
G37*
G36*
G01X348161D02*
X347976Y1022319D01*
X346946D01*
X346761Y1022919D01*
Y1023093D01*
X348161D01*
Y1022919D01*
G37*
G36*
G01X351828Y1022917D02*
X351643Y1022317D01*
X350613D01*
X350428Y1022917D01*
Y1023092D01*
X351828D01*
Y1022917D01*
G37*
G36*
G01X355528D02*
X355343Y1022317D01*
X354313D01*
X354128Y1022917D01*
Y1023092D01*
X355528D01*
Y1022917D01*
G37*
G36*
G01X343061Y1027719D02*
X343246Y1028319D01*
X344276D01*
X344461Y1027719D01*
Y1027544D01*
X343061D01*
Y1027719D01*
G37*
G36*
G01X339361D02*
X339546Y1028319D01*
X340576D01*
X340761Y1027719D01*
Y1027544D01*
X339361D01*
Y1027719D01*
G37*
G36*
G01X346761D02*
X346946Y1028319D01*
X347976D01*
X348161Y1027719D01*
Y1027544D01*
X346761D01*
Y1027719D01*
G37*
G36*
G01X350428D02*
X350613Y1028319D01*
X351643D01*
X351828Y1027719D01*
Y1027545D01*
X350428D01*
Y1027719D01*
G37*
G36*
G01X354128D02*
X354313Y1028319D01*
X355343D01*
X355528Y1027719D01*
Y1027545D01*
X354128D01*
Y1027719D01*
G37*
G36*
G01X343061D02*
X343246Y1028319D01*
X344276D01*
X344461Y1027719D01*
Y1027544D01*
X343061D01*
Y1027719D01*
G37*
G36*
G01X339361D02*
X339546Y1028319D01*
X340576D01*
X340761Y1027719D01*
Y1027544D01*
X339361D01*
Y1027719D01*
G37*
G36*
G01X346761D02*
X346946Y1028319D01*
X347976D01*
X348161Y1027719D01*
Y1027544D01*
X346761D01*
Y1027719D01*
G37*
G36*
G01X350428D02*
X350613Y1028319D01*
X351643D01*
X351828Y1027719D01*
Y1027545D01*
X350428D01*
Y1027719D01*
G37*
G36*
G01X354128D02*
X354313Y1028319D01*
X355343D01*
X355528Y1027719D01*
Y1027545D01*
X354128D01*
Y1027719D01*
G37*
G36*
G01X341211Y1024513D02*
X341396Y1025113D01*
X342426D01*
X342611Y1024513D01*
Y1024339D01*
X341211D01*
Y1024513D01*
G37*
G36*
G01X348635Y1024515D02*
X348820Y1025115D01*
X349850D01*
X350035Y1024515D01*
Y1024340D01*
X348635D01*
Y1024515D01*
G37*
G36*
G01X344911Y1024513D02*
X345096Y1025113D01*
X346126D01*
X346311Y1024513D01*
Y1024339D01*
X344911D01*
Y1024513D01*
G37*
G36*
G01X352345Y1024515D02*
X352530Y1025115D01*
X353560D01*
X353745Y1024515D01*
Y1024340D01*
X352345D01*
Y1024515D01*
G37*
G36*
G01X341211Y1024513D02*
X341396Y1025113D01*
X342426D01*
X342611Y1024513D01*
Y1024339D01*
X341211D01*
Y1024513D01*
G37*
G36*
G01X348635Y1024515D02*
X348820Y1025115D01*
X349850D01*
X350035Y1024515D01*
Y1024340D01*
X348635D01*
Y1024515D01*
G37*
G36*
G01X344911Y1024513D02*
X345096Y1025113D01*
X346126D01*
X346311Y1024513D01*
Y1024339D01*
X344911D01*
Y1024513D01*
G37*
G36*
G01X352345Y1024515D02*
X352530Y1025115D01*
X353560D01*
X353745Y1024515D01*
Y1024340D01*
X352345D01*
Y1024515D01*
G37*
G36*
G01X346311Y1026123D02*
X346126Y1025523D01*
X345096D01*
X344911Y1026123D01*
Y1026297D01*
X346311D01*
Y1026123D01*
G37*
G36*
G01X342611D02*
X342426Y1025523D01*
X341396D01*
X341211Y1026123D01*
Y1026297D01*
X342611D01*
Y1026123D01*
G37*
G36*
G01X350035Y1026121D02*
X349850Y1025521D01*
X348820D01*
X348635Y1026121D01*
Y1026296D01*
X350035D01*
Y1026121D01*
G37*
G36*
G01X353745D02*
X353560Y1025521D01*
X352530D01*
X352345Y1026121D01*
Y1026296D01*
X353745D01*
Y1026121D01*
G37*
G36*
G01X346311Y1026123D02*
X346126Y1025523D01*
X345096D01*
X344911Y1026123D01*
Y1026297D01*
X346311D01*
Y1026123D01*
G37*
G36*
G01X342611D02*
X342426Y1025523D01*
X341396D01*
X341211Y1026123D01*
Y1026297D01*
X342611D01*
Y1026123D01*
G37*
G36*
G01X350035Y1026121D02*
X349850Y1025521D01*
X348820D01*
X348635Y1026121D01*
Y1026296D01*
X350035D01*
Y1026121D01*
G37*
G36*
G01X353745D02*
X353560Y1025521D01*
X352530D01*
X352345Y1026121D01*
Y1026296D01*
X353745D01*
Y1026121D01*
G37*
G36*
G01X342611Y1032531D02*
X342426Y1031931D01*
X341396D01*
X341211Y1032531D01*
Y1032706D01*
X342611D01*
Y1032531D01*
G37*
G36*
G01X350035D02*
X349850Y1031931D01*
X348820D01*
X348635Y1032531D01*
Y1032705D01*
X350035D01*
Y1032531D01*
G37*
G36*
G01X346311D02*
X346126Y1031931D01*
X345096D01*
X344911Y1032531D01*
Y1032706D01*
X346311D01*
Y1032531D01*
G37*
G36*
G01X353711D02*
X353526Y1031931D01*
X352496D01*
X352311Y1032531D01*
Y1032706D01*
X353711D01*
Y1032531D01*
G37*
G36*
G01X342611D02*
X342426Y1031931D01*
X341396D01*
X341211Y1032531D01*
Y1032706D01*
X342611D01*
Y1032531D01*
G37*
G36*
G01X350035D02*
X349850Y1031931D01*
X348820D01*
X348635Y1032531D01*
Y1032705D01*
X350035D01*
Y1032531D01*
G37*
G36*
G01X346311D02*
X346126Y1031931D01*
X345096D01*
X344911Y1032531D01*
Y1032706D01*
X346311D01*
Y1032531D01*
G37*
G36*
G01X353711D02*
X353526Y1031931D01*
X352496D01*
X352311Y1032531D01*
Y1032706D01*
X353711D01*
Y1032531D01*
G37*
G36*
G01X339361Y1034127D02*
X339546Y1034727D01*
X340576D01*
X340761Y1034127D01*
Y1033952D01*
X339361D01*
Y1034127D01*
G37*
G36*
G01X343061D02*
X343246Y1034727D01*
X344276D01*
X344461Y1034127D01*
Y1033952D01*
X343061D01*
Y1034127D01*
G37*
G36*
G01X346761D02*
X346946Y1034727D01*
X347976D01*
X348161Y1034127D01*
Y1033952D01*
X346761D01*
Y1034127D01*
G37*
G36*
G01X350461D02*
X350646Y1034727D01*
X351676D01*
X351861Y1034127D01*
Y1033952D01*
X350461D01*
Y1034127D01*
G37*
G36*
G01X339361D02*
X339546Y1034727D01*
X340576D01*
X340761Y1034127D01*
Y1033952D01*
X339361D01*
Y1034127D01*
G37*
G36*
G01X343061D02*
X343246Y1034727D01*
X344276D01*
X344461Y1034127D01*
Y1033952D01*
X343061D01*
Y1034127D01*
G37*
G36*
G01X346761D02*
X346946Y1034727D01*
X347976D01*
X348161Y1034127D01*
Y1033952D01*
X346761D01*
Y1034127D01*
G37*
G36*
G01X350461D02*
X350646Y1034727D01*
X351676D01*
X351861Y1034127D01*
Y1033952D01*
X350461D01*
Y1034127D01*
G37*
G36*
G01X341211Y1030923D02*
X341396Y1031523D01*
X342426D01*
X342611Y1030923D01*
Y1030748D01*
X341211D01*
Y1030923D01*
G37*
G36*
G01X348635D02*
X348820Y1031523D01*
X349850D01*
X350035Y1030923D01*
Y1030749D01*
X348635D01*
Y1030923D01*
G37*
G36*
G01X344911D02*
X345096Y1031523D01*
X346126D01*
X346311Y1030923D01*
Y1030748D01*
X344911D01*
Y1030923D01*
G37*
G36*
G01X352335D02*
X352520Y1031523D01*
X353550D01*
X353735Y1030923D01*
Y1030748D01*
X352335D01*
Y1030923D01*
G37*
G36*
G01X341211D02*
X341396Y1031523D01*
X342426D01*
X342611Y1030923D01*
Y1030748D01*
X341211D01*
Y1030923D01*
G37*
G36*
G01X348635D02*
X348820Y1031523D01*
X349850D01*
X350035Y1030923D01*
Y1030749D01*
X348635D01*
Y1030923D01*
G37*
G36*
G01X344911D02*
X345096Y1031523D01*
X346126D01*
X346311Y1030923D01*
Y1030748D01*
X344911D01*
Y1030923D01*
G37*
G36*
G01X352335D02*
X352520Y1031523D01*
X353550D01*
X353735Y1030923D01*
Y1030748D01*
X352335D01*
Y1030923D01*
G37*
G36*
G01X339361Y1040535D02*
X339546Y1041135D01*
X340576D01*
X340761Y1040535D01*
Y1040361D01*
X339361D01*
Y1040535D01*
G37*
G36*
G01X343061D02*
X343246Y1041135D01*
X344276D01*
X344461Y1040535D01*
Y1040361D01*
X343061D01*
Y1040535D01*
G37*
G36*
G01X346761D02*
X346946Y1041135D01*
X347976D01*
X348161Y1040535D01*
Y1040361D01*
X346761D01*
Y1040535D01*
G37*
G36*
G01X350461D02*
X350646Y1041135D01*
X351676D01*
X351861Y1040535D01*
Y1040361D01*
X350461D01*
Y1040535D01*
G37*
G36*
G01X354161D02*
X354346Y1041135D01*
X355376D01*
X355561Y1040535D01*
Y1040361D01*
X354161D01*
Y1040535D01*
G37*
G36*
G01X339361D02*
X339546Y1041135D01*
X340576D01*
X340761Y1040535D01*
Y1040361D01*
X339361D01*
Y1040535D01*
G37*
G36*
G01X343061D02*
X343246Y1041135D01*
X344276D01*
X344461Y1040535D01*
Y1040361D01*
X343061D01*
Y1040535D01*
G37*
G36*
G01X346761D02*
X346946Y1041135D01*
X347976D01*
X348161Y1040535D01*
Y1040361D01*
X346761D01*
Y1040535D01*
G37*
G36*
G01X350461D02*
X350646Y1041135D01*
X351676D01*
X351861Y1040535D01*
Y1040361D01*
X350461D01*
Y1040535D01*
G37*
G36*
G01X354161D02*
X354346Y1041135D01*
X355376D01*
X355561Y1040535D01*
Y1040361D01*
X354161D01*
Y1040535D01*
G37*
G36*
G01X341211Y1037331D02*
X341396Y1037931D01*
X342426D01*
X342611Y1037331D01*
Y1037157D01*
X341211D01*
Y1037331D01*
G37*
G36*
G01X348598D02*
X348783Y1037931D01*
X349813D01*
X349998Y1037331D01*
Y1037156D01*
X348598D01*
Y1037331D01*
G37*
G36*
G01X344911D02*
X345096Y1037931D01*
X346126D01*
X346311Y1037331D01*
Y1037157D01*
X344911D01*
Y1037331D01*
G37*
G36*
G01X352312D02*
X352497Y1037931D01*
X353527D01*
X353712Y1037331D01*
Y1037156D01*
X352312D01*
Y1037331D01*
G37*
G36*
G01X341211D02*
X341396Y1037931D01*
X342426D01*
X342611Y1037331D01*
Y1037157D01*
X341211D01*
Y1037331D01*
G37*
G36*
G01X348598D02*
X348783Y1037931D01*
X349813D01*
X349998Y1037331D01*
Y1037156D01*
X348598D01*
Y1037331D01*
G37*
G36*
G01X344911D02*
X345096Y1037931D01*
X346126D01*
X346311Y1037331D01*
Y1037157D01*
X344911D01*
Y1037331D01*
G37*
G36*
G01X352312D02*
X352497Y1037931D01*
X353527D01*
X353712Y1037331D01*
Y1037156D01*
X352312D01*
Y1037331D01*
G37*
G36*
G01X342611Y1038941D02*
X342426Y1038341D01*
X341396D01*
X341211Y1038941D01*
Y1039115D01*
X342611D01*
Y1038941D01*
G37*
G36*
G01X350011D02*
X349826Y1038341D01*
X348796D01*
X348611Y1038941D01*
Y1039115D01*
X350011D01*
Y1038941D01*
G37*
G36*
G01X346311D02*
X346126Y1038341D01*
X345096D01*
X344911Y1038941D01*
Y1039115D01*
X346311D01*
Y1038941D01*
G37*
G36*
G01X353711D02*
X353526Y1038341D01*
X352496D01*
X352311Y1038941D01*
Y1039115D01*
X353711D01*
Y1038941D01*
G37*
G36*
G01X342611D02*
X342426Y1038341D01*
X341396D01*
X341211Y1038941D01*
Y1039115D01*
X342611D01*
Y1038941D01*
G37*
G36*
G01X350011D02*
X349826Y1038341D01*
X348796D01*
X348611Y1038941D01*
Y1039115D01*
X350011D01*
Y1038941D01*
G37*
G36*
G01X346311D02*
X346126Y1038341D01*
X345096D01*
X344911Y1038941D01*
Y1039115D01*
X346311D01*
Y1038941D01*
G37*
G36*
G01X353711D02*
X353526Y1038341D01*
X352496D01*
X352311Y1038941D01*
Y1039115D01*
X353711D01*
Y1038941D01*
G37*
G36*
G01X344461Y1035735D02*
X344276Y1035135D01*
X343246D01*
X343061Y1035735D01*
Y1035910D01*
X344461D01*
Y1035735D01*
G37*
G36*
G01X340761D02*
X340576Y1035135D01*
X339546D01*
X339361Y1035735D01*
Y1035910D01*
X340761D01*
Y1035735D01*
G37*
G36*
G01X348161D02*
X347976Y1035135D01*
X346946D01*
X346761Y1035735D01*
Y1035910D01*
X348161D01*
Y1035735D01*
G37*
G36*
G01X351872D02*
X351687Y1035135D01*
X350657D01*
X350472Y1035735D01*
Y1035910D01*
X351872D01*
Y1035735D01*
G37*
G36*
G01X344461D02*
X344276Y1035135D01*
X343246D01*
X343061Y1035735D01*
Y1035910D01*
X344461D01*
Y1035735D01*
G37*
G36*
G01X340761D02*
X340576Y1035135D01*
X339546D01*
X339361Y1035735D01*
Y1035910D01*
X340761D01*
Y1035735D01*
G37*
G36*
G01X348161D02*
X347976Y1035135D01*
X346946D01*
X346761Y1035735D01*
Y1035910D01*
X348161D01*
Y1035735D01*
G37*
G36*
G01X351872D02*
X351687Y1035135D01*
X350657D01*
X350472Y1035735D01*
Y1035910D01*
X351872D01*
Y1035735D01*
G37*
G36*
G01X342611Y1045349D02*
X342426Y1044749D01*
X341396D01*
X341211Y1045349D01*
Y1045523D01*
X342611D01*
Y1045349D01*
G37*
G36*
G01X350011D02*
X349826Y1044749D01*
X348796D01*
X348611Y1045349D01*
Y1045523D01*
X350011D01*
Y1045349D01*
G37*
G36*
G01X346311D02*
X346126Y1044749D01*
X345096D01*
X344911Y1045349D01*
Y1045523D01*
X346311D01*
Y1045349D01*
G37*
G36*
G01X353711D02*
X353526Y1044749D01*
X352496D01*
X352311Y1045349D01*
Y1045523D01*
X353711D01*
Y1045349D01*
G37*
G36*
G01X342611D02*
X342426Y1044749D01*
X341396D01*
X341211Y1045349D01*
Y1045523D01*
X342611D01*
Y1045349D01*
G37*
G36*
G01X350011D02*
X349826Y1044749D01*
X348796D01*
X348611Y1045349D01*
Y1045523D01*
X350011D01*
Y1045349D01*
G37*
G36*
G01X346311D02*
X346126Y1044749D01*
X345096D01*
X344911Y1045349D01*
Y1045523D01*
X346311D01*
Y1045349D01*
G37*
G36*
G01X353711D02*
X353526Y1044749D01*
X352496D01*
X352311Y1045349D01*
Y1045523D01*
X353711D01*
Y1045349D01*
G37*
G36*
G01X348611Y1043739D02*
X348796Y1044339D01*
X349826D01*
X350011Y1043739D01*
Y1043565D01*
X348611D01*
Y1043739D01*
G37*
G36*
G01X344911D02*
X345096Y1044339D01*
X346126D01*
X346311Y1043739D01*
Y1043565D01*
X344911D01*
Y1043739D01*
G37*
G36*
G01X341211D02*
X341396Y1044339D01*
X342426D01*
X342611Y1043739D01*
Y1043565D01*
X341211D01*
Y1043739D01*
G37*
G36*
G01X352311D02*
X352496Y1044339D01*
X353526D01*
X353711Y1043739D01*
Y1043565D01*
X352311D01*
Y1043739D01*
G37*
G36*
G01X348611D02*
X348796Y1044339D01*
X349826D01*
X350011Y1043739D01*
Y1043565D01*
X348611D01*
Y1043739D01*
G37*
G36*
G01X344911D02*
X345096Y1044339D01*
X346126D01*
X346311Y1043739D01*
Y1043565D01*
X344911D01*
Y1043739D01*
G37*
G36*
G01X341211D02*
X341396Y1044339D01*
X342426D01*
X342611Y1043739D01*
Y1043565D01*
X341211D01*
Y1043739D01*
G37*
G36*
G01X352311D02*
X352496Y1044339D01*
X353526D01*
X353711Y1043739D01*
Y1043565D01*
X352311D01*
Y1043739D01*
G37*
G36*
G01X343061Y1046945D02*
X343246Y1047545D01*
X344276D01*
X344461Y1046945D01*
Y1046770D01*
X343061D01*
Y1046945D01*
G37*
G36*
G01X339361D02*
X339546Y1047545D01*
X340576D01*
X340761Y1046945D01*
Y1046770D01*
X339361D01*
Y1046945D01*
G37*
G36*
G01X346761D02*
X346946Y1047545D01*
X347976D01*
X348161Y1046945D01*
Y1046770D01*
X346761D01*
Y1046945D01*
G37*
G36*
G01X350461Y1046943D02*
X350646Y1047543D01*
X351676D01*
X351861Y1046943D01*
Y1046769D01*
X350461D01*
Y1046943D01*
G37*
G36*
G01X354161D02*
X354346Y1047543D01*
X355376D01*
X355561Y1046943D01*
Y1046769D01*
X354161D01*
Y1046943D01*
G37*
G36*
G01X343061Y1046945D02*
X343246Y1047545D01*
X344276D01*
X344461Y1046945D01*
Y1046770D01*
X343061D01*
Y1046945D01*
G37*
G36*
G01X339361D02*
X339546Y1047545D01*
X340576D01*
X340761Y1046945D01*
Y1046770D01*
X339361D01*
Y1046945D01*
G37*
G36*
G01X346761D02*
X346946Y1047545D01*
X347976D01*
X348161Y1046945D01*
Y1046770D01*
X346761D01*
Y1046945D01*
G37*
G36*
G01X350461Y1046943D02*
X350646Y1047543D01*
X351676D01*
X351861Y1046943D01*
Y1046769D01*
X350461D01*
Y1046943D01*
G37*
G36*
G01X354161D02*
X354346Y1047543D01*
X355376D01*
X355561Y1046943D01*
Y1046769D01*
X354161D01*
Y1046943D01*
G37*
G36*
G01X344461Y1042145D02*
X344276Y1041545D01*
X343246D01*
X343061Y1042145D01*
Y1042319D01*
X344461D01*
Y1042145D01*
G37*
G36*
G01X340761D02*
X340576Y1041545D01*
X339546D01*
X339361Y1042145D01*
Y1042319D01*
X340761D01*
Y1042145D01*
G37*
G36*
G01X348161D02*
X347976Y1041545D01*
X346946D01*
X346761Y1042145D01*
Y1042319D01*
X348161D01*
Y1042145D01*
G37*
G36*
G01X351861D02*
X351676Y1041545D01*
X350646D01*
X350461Y1042145D01*
Y1042319D01*
X351861D01*
Y1042145D01*
G37*
G36*
G01X355561D02*
X355376Y1041545D01*
X354346D01*
X354161Y1042145D01*
Y1042319D01*
X355561D01*
Y1042145D01*
G37*
G36*
G01X344461D02*
X344276Y1041545D01*
X343246D01*
X343061Y1042145D01*
Y1042319D01*
X344461D01*
Y1042145D01*
G37*
G36*
G01X340761D02*
X340576Y1041545D01*
X339546D01*
X339361Y1042145D01*
Y1042319D01*
X340761D01*
Y1042145D01*
G37*
G36*
G01X348161D02*
X347976Y1041545D01*
X346946D01*
X346761Y1042145D01*
Y1042319D01*
X348161D01*
Y1042145D01*
G37*
G36*
G01X351861D02*
X351676Y1041545D01*
X350646D01*
X350461Y1042145D01*
Y1042319D01*
X351861D01*
Y1042145D01*
G37*
G36*
G01X355561D02*
X355376Y1041545D01*
X354346D01*
X354161Y1042145D01*
Y1042319D01*
X355561D01*
Y1042145D01*
G37*
G36*
G01X343061Y1059761D02*
X343246Y1060361D01*
X344276D01*
X344461Y1059761D01*
Y1059586D01*
X343061D01*
Y1059761D01*
G37*
G36*
G01X346761D02*
X346946Y1060361D01*
X347976D01*
X348161Y1059761D01*
Y1059586D01*
X346761D01*
Y1059761D01*
G37*
G36*
G01X350461D02*
X350646Y1060361D01*
X351676D01*
X351861Y1059761D01*
Y1059586D01*
X350461D01*
Y1059761D01*
G37*
G36*
G01X339921Y1062403D02*
X340533Y1062543D01*
X341048Y1061651D01*
X340621Y1061191D01*
X340470Y1061104D01*
X339770Y1062316D01*
X339921Y1062403D01*
G37*
G36*
G01X354161Y1059761D02*
X354346Y1060361D01*
X355376D01*
X355561Y1059761D01*
Y1059586D01*
X354161D01*
Y1059761D01*
G37*
G36*
G01X343061D02*
X343246Y1060361D01*
X344276D01*
X344461Y1059761D01*
Y1059586D01*
X343061D01*
Y1059761D01*
G37*
G36*
G01X346761D02*
X346946Y1060361D01*
X347976D01*
X348161Y1059761D01*
Y1059586D01*
X346761D01*
Y1059761D01*
G37*
G36*
G01X350461D02*
X350646Y1060361D01*
X351676D01*
X351861Y1059761D01*
Y1059586D01*
X350461D01*
Y1059761D01*
G37*
G36*
G01X339921Y1062403D02*
X340533Y1062543D01*
X341048Y1061651D01*
X340621Y1061191D01*
X340470Y1061104D01*
X339770Y1062316D01*
X339921Y1062403D01*
G37*
G36*
G01X354161Y1059761D02*
X354346Y1060361D01*
X355376D01*
X355561Y1059761D01*
Y1059586D01*
X354161D01*
Y1059761D01*
G37*
G36*
G01X338079Y1059183D02*
X338691Y1059323D01*
X339206Y1058431D01*
X338779Y1057971D01*
X338628Y1057884D01*
X337928Y1059096D01*
X338079Y1059183D01*
G37*
G36*
G01X341211Y1056557D02*
X341396Y1057157D01*
X342426D01*
X342611Y1056557D01*
Y1056382D01*
X341211D01*
Y1056557D01*
G37*
G36*
G01X348611D02*
X348796Y1057157D01*
X349826D01*
X350011Y1056557D01*
Y1056382D01*
X348611D01*
Y1056557D01*
G37*
G36*
G01X344911D02*
X345096Y1057157D01*
X346126D01*
X346311Y1056557D01*
Y1056382D01*
X344911D01*
Y1056557D01*
G37*
G36*
G01X352311D02*
X352496Y1057157D01*
X353526D01*
X353711Y1056557D01*
Y1056382D01*
X352311D01*
Y1056557D01*
G37*
G36*
G01X338079Y1059183D02*
X338691Y1059323D01*
X339206Y1058431D01*
X338779Y1057971D01*
X338628Y1057884D01*
X337928Y1059096D01*
X338079Y1059183D01*
G37*
G36*
G01X341211Y1056557D02*
X341396Y1057157D01*
X342426D01*
X342611Y1056557D01*
Y1056382D01*
X341211D01*
Y1056557D01*
G37*
G36*
G01X348611D02*
X348796Y1057157D01*
X349826D01*
X350011Y1056557D01*
Y1056382D01*
X348611D01*
Y1056557D01*
G37*
G36*
G01X344911D02*
X345096Y1057157D01*
X346126D01*
X346311Y1056557D01*
Y1056382D01*
X344911D01*
Y1056557D01*
G37*
G36*
G01X352311D02*
X352496Y1057157D01*
X353526D01*
X353711Y1056557D01*
Y1056382D01*
X352311D01*
Y1056557D01*
G37*
G36*
G01X342611Y1058165D02*
X342426Y1057565D01*
X341396D01*
X341211Y1058165D01*
Y1058340D01*
X342611D01*
Y1058165D01*
G37*
G36*
G01X340193Y1058743D02*
X339581Y1058603D01*
X339066Y1059495D01*
X339493Y1059955D01*
X339644Y1060042D01*
X340344Y1058830D01*
X340193Y1058743D01*
G37*
G36*
G01X350011Y1058165D02*
X349826Y1057565D01*
X348796D01*
X348611Y1058165D01*
Y1058340D01*
X350011D01*
Y1058165D01*
G37*
G36*
G01X346311D02*
X346126Y1057565D01*
X345096D01*
X344911Y1058165D01*
Y1058340D01*
X346311D01*
Y1058165D01*
G37*
G36*
G01X353711D02*
X353526Y1057565D01*
X352496D01*
X352311Y1058165D01*
Y1058340D01*
X353711D01*
Y1058165D01*
G37*
G36*
G01X342611D02*
X342426Y1057565D01*
X341396D01*
X341211Y1058165D01*
Y1058340D01*
X342611D01*
Y1058165D01*
G37*
G36*
G01X340193Y1058743D02*
X339581Y1058603D01*
X339066Y1059495D01*
X339493Y1059955D01*
X339644Y1060042D01*
X340344Y1058830D01*
X340193Y1058743D01*
G37*
G36*
G01X350011Y1058165D02*
X349826Y1057565D01*
X348796D01*
X348611Y1058165D01*
Y1058340D01*
X350011D01*
Y1058165D01*
G37*
G36*
G01X346311D02*
X346126Y1057565D01*
X345096D01*
X344911Y1058165D01*
Y1058340D01*
X346311D01*
Y1058165D01*
G37*
G36*
G01X353711D02*
X353526Y1057565D01*
X352496D01*
X352311Y1058165D01*
Y1058340D01*
X353711D01*
Y1058165D01*
G37*
G36*
G01X340761Y1054961D02*
X340576Y1054361D01*
X339546D01*
X339361Y1054961D01*
Y1055136D01*
X340761D01*
Y1054961D01*
G37*
G36*
G01X344461D02*
X344276Y1054361D01*
X343246D01*
X343061Y1054961D01*
Y1055136D01*
X344461D01*
Y1054961D01*
G37*
G36*
G01X348161D02*
X347976Y1054361D01*
X346946D01*
X346761Y1054961D01*
Y1055136D01*
X348161D01*
Y1054961D01*
G37*
G36*
G01X351861D02*
X351676Y1054361D01*
X350646D01*
X350461Y1054961D01*
Y1055136D01*
X351861D01*
Y1054961D01*
G37*
G36*
G01X340761D02*
X340576Y1054361D01*
X339546D01*
X339361Y1054961D01*
Y1055136D01*
X340761D01*
Y1054961D01*
G37*
G36*
G01X344461D02*
X344276Y1054361D01*
X343246D01*
X343061Y1054961D01*
Y1055136D01*
X344461D01*
Y1054961D01*
G37*
G36*
G01X348161D02*
X347976Y1054361D01*
X346946D01*
X346761Y1054961D01*
Y1055136D01*
X348161D01*
Y1054961D01*
G37*
G36*
G01X351861D02*
X351676Y1054361D01*
X350646D01*
X350461Y1054961D01*
Y1055136D01*
X351861D01*
Y1054961D01*
G37*
G36*
G01X350461Y1053353D02*
X350646Y1053953D01*
X351676D01*
X351861Y1053353D01*
Y1053178D01*
X350461D01*
Y1053353D01*
G37*
G36*
G01X339361D02*
X339546Y1053953D01*
X340576D01*
X340761Y1053353D01*
Y1053178D01*
X339361D01*
Y1053353D01*
G37*
G36*
G01X343061D02*
X343246Y1053953D01*
X344276D01*
X344461Y1053353D01*
Y1053178D01*
X343061D01*
Y1053353D01*
G37*
G36*
G01X346761D02*
X346946Y1053953D01*
X347976D01*
X348161Y1053353D01*
Y1053178D01*
X346761D01*
Y1053353D01*
G37*
G36*
G01X350461D02*
X350646Y1053953D01*
X351676D01*
X351861Y1053353D01*
Y1053178D01*
X350461D01*
Y1053353D01*
G37*
G36*
G01X339361D02*
X339546Y1053953D01*
X340576D01*
X340761Y1053353D01*
Y1053178D01*
X339361D01*
Y1053353D01*
G37*
G36*
G01X343061D02*
X343246Y1053953D01*
X344276D01*
X344461Y1053353D01*
Y1053178D01*
X343061D01*
Y1053353D01*
G37*
G36*
G01X346761D02*
X346946Y1053953D01*
X347976D01*
X348161Y1053353D01*
Y1053178D01*
X346761D01*
Y1053353D01*
G37*
G36*
G01X341211Y1050149D02*
X341396Y1050749D01*
X342426D01*
X342611Y1050149D01*
Y1049974D01*
X341211D01*
Y1050149D01*
G37*
G36*
G01X344911D02*
X345096Y1050749D01*
X346126D01*
X346311Y1050149D01*
Y1049974D01*
X344911D01*
Y1050149D01*
G37*
G36*
G01X348611D02*
X348796Y1050749D01*
X349826D01*
X350011Y1050149D01*
Y1049974D01*
X348611D01*
Y1050149D01*
G37*
G36*
G01X352311D02*
X352496Y1050749D01*
X353526D01*
X353711Y1050149D01*
Y1049974D01*
X352311D01*
Y1050149D01*
G37*
G36*
G01X341211D02*
X341396Y1050749D01*
X342426D01*
X342611Y1050149D01*
Y1049974D01*
X341211D01*
Y1050149D01*
G37*
G36*
G01X344911D02*
X345096Y1050749D01*
X346126D01*
X346311Y1050149D01*
Y1049974D01*
X344911D01*
Y1050149D01*
G37*
G36*
G01X348611D02*
X348796Y1050749D01*
X349826D01*
X350011Y1050149D01*
Y1049974D01*
X348611D01*
Y1050149D01*
G37*
G36*
G01X352311D02*
X352496Y1050749D01*
X353526D01*
X353711Y1050149D01*
Y1049974D01*
X352311D01*
Y1050149D01*
G37*
G36*
G01X342611Y1051757D02*
X342426Y1051157D01*
X341396D01*
X341211Y1051757D01*
Y1051931D01*
X342611D01*
Y1051757D01*
G37*
G36*
G01X346311D02*
X346126Y1051157D01*
X345096D01*
X344911Y1051757D01*
Y1051931D01*
X346311D01*
Y1051757D01*
G37*
G36*
G01X350011D02*
X349826Y1051157D01*
X348796D01*
X348611Y1051757D01*
Y1051931D01*
X350011D01*
Y1051757D01*
G37*
G36*
G01X353735D02*
X353550Y1051157D01*
X352520D01*
X352335Y1051757D01*
Y1051931D01*
X353735D01*
Y1051757D01*
G37*
G36*
G01X342611D02*
X342426Y1051157D01*
X341396D01*
X341211Y1051757D01*
Y1051931D01*
X342611D01*
Y1051757D01*
G37*
G36*
G01X346311D02*
X346126Y1051157D01*
X345096D01*
X344911Y1051757D01*
Y1051931D01*
X346311D01*
Y1051757D01*
G37*
G36*
G01X350011D02*
X349826Y1051157D01*
X348796D01*
X348611Y1051757D01*
Y1051931D01*
X350011D01*
Y1051757D01*
G37*
G36*
G01X353735D02*
X353550Y1051157D01*
X352520D01*
X352335Y1051757D01*
Y1051931D01*
X353735D01*
Y1051757D01*
G37*
G36*
G01X344461Y1048553D02*
X344276Y1047953D01*
X343246D01*
X343061Y1048553D01*
Y1048727D01*
X344461D01*
Y1048553D01*
G37*
G36*
G01X340761D02*
X340576Y1047953D01*
X339546D01*
X339361Y1048553D01*
Y1048727D01*
X340761D01*
Y1048553D01*
G37*
G36*
G01X348161D02*
X347976Y1047953D01*
X346946D01*
X346761Y1048553D01*
Y1048727D01*
X348161D01*
Y1048553D01*
G37*
G36*
G01X351861D02*
X351676Y1047953D01*
X350646D01*
X350461Y1048553D01*
Y1048727D01*
X351861D01*
Y1048553D01*
G37*
G36*
G01X355561D02*
X355376Y1047953D01*
X354346D01*
X354161Y1048553D01*
Y1048727D01*
X355561D01*
Y1048553D01*
G37*
G36*
G01X344461D02*
X344276Y1047953D01*
X343246D01*
X343061Y1048553D01*
Y1048727D01*
X344461D01*
Y1048553D01*
G37*
G36*
G01X340761D02*
X340576Y1047953D01*
X339546D01*
X339361Y1048553D01*
Y1048727D01*
X340761D01*
Y1048553D01*
G37*
G36*
G01X348161D02*
X347976Y1047953D01*
X346946D01*
X346761Y1048553D01*
Y1048727D01*
X348161D01*
Y1048553D01*
G37*
G36*
G01X351861D02*
X351676Y1047953D01*
X350646D01*
X350461Y1048553D01*
Y1048727D01*
X351861D01*
Y1048553D01*
G37*
G36*
G01X355561D02*
X355376Y1047953D01*
X354346D01*
X354161Y1048553D01*
Y1048727D01*
X355561D01*
Y1048553D01*
G37*
G36*
G01X348611Y1062965D02*
X348796Y1063565D01*
X349826D01*
X350011Y1062965D01*
Y1062791D01*
X348611D01*
Y1062965D01*
G37*
G36*
G01X344911D02*
X345096Y1063565D01*
X346126D01*
X346311Y1062965D01*
Y1062791D01*
X344911D01*
Y1062965D01*
G37*
G36*
G01X352311D02*
X352496Y1063565D01*
X353526D01*
X353711Y1062965D01*
Y1062791D01*
X352311D01*
Y1062965D01*
G37*
G36*
G01X348611D02*
X348796Y1063565D01*
X349826D01*
X350011Y1062965D01*
Y1062791D01*
X348611D01*
Y1062965D01*
G37*
G36*
G01X344911D02*
X345096Y1063565D01*
X346126D01*
X346311Y1062965D01*
Y1062791D01*
X344911D01*
Y1062965D01*
G37*
G36*
G01X352311D02*
X352496Y1063565D01*
X353526D01*
X353711Y1062965D01*
Y1062791D01*
X352311D01*
Y1062965D01*
G37*
G36*
G01X344461Y1061369D02*
X344276Y1060769D01*
X343246D01*
X343061Y1061369D01*
Y1061544D01*
X344461D01*
Y1061369D01*
G37*
G36*
G01X348161D02*
X347976Y1060769D01*
X346946D01*
X346761Y1061369D01*
Y1061544D01*
X348161D01*
Y1061369D01*
G37*
G36*
G01X342051Y1061932D02*
X341439Y1061792D01*
X340924Y1062684D01*
X341351Y1063144D01*
X341502Y1063231D01*
X342202Y1062019D01*
X342051Y1061932D01*
G37*
G36*
G01X351861Y1061369D02*
X351676Y1060769D01*
X350646D01*
X350461Y1061369D01*
Y1061544D01*
X351861D01*
Y1061369D01*
G37*
G36*
G01X355561D02*
X355376Y1060769D01*
X354346D01*
X354161Y1061369D01*
Y1061544D01*
X355561D01*
Y1061369D01*
G37*
G36*
G01X344461D02*
X344276Y1060769D01*
X343246D01*
X343061Y1061369D01*
Y1061544D01*
X344461D01*
Y1061369D01*
G37*
G36*
G01X348161D02*
X347976Y1060769D01*
X346946D01*
X346761Y1061369D01*
Y1061544D01*
X348161D01*
Y1061369D01*
G37*
G36*
G01X342051Y1061932D02*
X341439Y1061792D01*
X340924Y1062684D01*
X341351Y1063144D01*
X341502Y1063231D01*
X342202Y1062019D01*
X342051Y1061932D01*
G37*
G36*
G01X351861Y1061369D02*
X351676Y1060769D01*
X350646D01*
X350461Y1061369D01*
Y1061544D01*
X351861D01*
Y1061369D01*
G37*
G36*
G01X355561D02*
X355376Y1060769D01*
X354346D01*
X354161Y1061369D01*
Y1061544D01*
X355561D01*
Y1061369D01*
G37*
G36*
G01X344485Y1074187D02*
X344300Y1073587D01*
X343270D01*
X343085Y1074187D01*
Y1074362D01*
X344485D01*
Y1074187D01*
G37*
G36*
G01X347597Y1071553D02*
X346985Y1071413D01*
X346470Y1072305D01*
X346897Y1072765D01*
X347048Y1072852D01*
X347748Y1071640D01*
X347597Y1071553D01*
G37*
G36*
G01X349988Y1070981D02*
X349803Y1070381D01*
X348773D01*
X348588Y1070981D01*
Y1071156D01*
X349988D01*
Y1070981D01*
G37*
G36*
G01X342026Y1074793D02*
X341414Y1074653D01*
X340899Y1075545D01*
X341326Y1076005D01*
X341477Y1076092D01*
X342177Y1074880D01*
X342026Y1074793D01*
G37*
G36*
G01X353735Y1070983D02*
X353550Y1070383D01*
X352520D01*
X352335Y1070983D01*
Y1071157D01*
X353735D01*
Y1070983D01*
G37*
G36*
G01X344485Y1074187D02*
X344300Y1073587D01*
X343270D01*
X343085Y1074187D01*
Y1074362D01*
X344485D01*
Y1074187D01*
G37*
G36*
G01X347597Y1071553D02*
X346985Y1071413D01*
X346470Y1072305D01*
X346897Y1072765D01*
X347048Y1072852D01*
X347748Y1071640D01*
X347597Y1071553D01*
G37*
G36*
G01X349988Y1070981D02*
X349803Y1070381D01*
X348773D01*
X348588Y1070981D01*
Y1071156D01*
X349988D01*
Y1070981D01*
G37*
G36*
G01X342026Y1074793D02*
X341414Y1074653D01*
X340899Y1075545D01*
X341326Y1076005D01*
X341477Y1076092D01*
X342177Y1074880D01*
X342026Y1074793D01*
G37*
G36*
G01X353735Y1070983D02*
X353550Y1070383D01*
X352520D01*
X352335Y1070983D01*
Y1071157D01*
X353735D01*
Y1070983D01*
G37*
G36*
G01X348161Y1067779D02*
X347976Y1067179D01*
X346946D01*
X346761Y1067779D01*
Y1067953D01*
X348161D01*
Y1067779D01*
G37*
G36*
G01X351828Y1067777D02*
X351643Y1067177D01*
X350613D01*
X350428Y1067777D01*
Y1067952D01*
X351828D01*
Y1067777D01*
G37*
G36*
G01X342578Y1070981D02*
X342393Y1070381D01*
X341363D01*
X341178Y1070981D01*
Y1071156D01*
X342578D01*
Y1070981D01*
G37*
G36*
G01X340197Y1071553D02*
X339585Y1071413D01*
X339070Y1072305D01*
X339497Y1072765D01*
X339648Y1072852D01*
X340348Y1071640D01*
X340197Y1071553D01*
G37*
G36*
G01X345743Y1068356D02*
X345131Y1068216D01*
X344616Y1069108D01*
X345043Y1069568D01*
X345194Y1069655D01*
X345894Y1068443D01*
X345743Y1068356D01*
G37*
G36*
G01X355561Y1067779D02*
X355376Y1067179D01*
X354346D01*
X354161Y1067779D01*
Y1067953D01*
X355561D01*
Y1067779D01*
G37*
G36*
G01X348161D02*
X347976Y1067179D01*
X346946D01*
X346761Y1067779D01*
Y1067953D01*
X348161D01*
Y1067779D01*
G37*
G36*
G01X351828Y1067777D02*
X351643Y1067177D01*
X350613D01*
X350428Y1067777D01*
Y1067952D01*
X351828D01*
Y1067777D01*
G37*
G36*
G01X342578Y1070981D02*
X342393Y1070381D01*
X341363D01*
X341178Y1070981D01*
Y1071156D01*
X342578D01*
Y1070981D01*
G37*
G36*
G01X340197Y1071553D02*
X339585Y1071413D01*
X339070Y1072305D01*
X339497Y1072765D01*
X339648Y1072852D01*
X340348Y1071640D01*
X340197Y1071553D01*
G37*
G36*
G01X345743Y1068356D02*
X345131Y1068216D01*
X344616Y1069108D01*
X345043Y1069568D01*
X345194Y1069655D01*
X345894Y1068443D01*
X345743Y1068356D01*
G37*
G36*
G01X355561Y1067779D02*
X355376Y1067179D01*
X354346D01*
X354161Y1067779D01*
Y1067953D01*
X355561D01*
Y1067779D01*
G37*
G36*
G01X344911Y1075783D02*
X345096Y1076383D01*
X346126D01*
X346311Y1075783D01*
Y1075608D01*
X344911D01*
Y1075783D01*
G37*
G36*
G01X339328Y1078987D02*
X339513Y1079587D01*
X340543D01*
X340728Y1078987D01*
Y1078813D01*
X339328D01*
Y1078987D01*
G37*
G36*
G01X350438Y1072579D02*
X350623Y1073179D01*
X351653D01*
X351838Y1072579D01*
Y1072404D01*
X350438D01*
Y1072579D01*
G37*
G36*
G01X347354Y1075165D02*
X347966Y1075305D01*
X348481Y1074413D01*
X348054Y1073953D01*
X347903Y1073866D01*
X347203Y1075078D01*
X347354Y1075165D01*
G37*
G36*
G01X341797Y1078381D02*
X342409Y1078521D01*
X342924Y1077629D01*
X342497Y1077169D01*
X342346Y1077082D01*
X341646Y1078294D01*
X341797Y1078381D01*
G37*
G36*
G01X344911Y1075783D02*
X345096Y1076383D01*
X346126D01*
X346311Y1075783D01*
Y1075608D01*
X344911D01*
Y1075783D01*
G37*
G36*
G01X339328Y1078987D02*
X339513Y1079587D01*
X340543D01*
X340728Y1078987D01*
Y1078813D01*
X339328D01*
Y1078987D01*
G37*
G36*
G01X350438Y1072579D02*
X350623Y1073179D01*
X351653D01*
X351838Y1072579D01*
Y1072404D01*
X350438D01*
Y1072579D01*
G37*
G36*
G01X347354Y1075165D02*
X347966Y1075305D01*
X348481Y1074413D01*
X348054Y1073953D01*
X347903Y1073866D01*
X347203Y1075078D01*
X347354Y1075165D01*
G37*
G36*
G01X341797Y1078381D02*
X342409Y1078521D01*
X342924Y1077629D01*
X342497Y1077169D01*
X342346Y1077082D01*
X341646Y1078294D01*
X341797Y1078381D01*
G37*
G36*
G01X348635Y1069375D02*
X348820Y1069975D01*
X349850D01*
X350035Y1069375D01*
Y1069200D01*
X348635D01*
Y1069375D01*
G37*
G36*
G01X343085Y1072579D02*
X343270Y1073179D01*
X344300D01*
X344485Y1072579D01*
Y1072404D01*
X343085D01*
Y1072579D01*
G37*
G36*
G01X339947Y1075176D02*
X340559Y1075316D01*
X341074Y1074424D01*
X340647Y1073964D01*
X340496Y1073877D01*
X339796Y1075089D01*
X339947Y1075176D01*
G37*
G36*
G01X345471Y1072016D02*
X346083Y1072156D01*
X346598Y1071264D01*
X346171Y1070804D01*
X346020Y1070717D01*
X345320Y1071929D01*
X345471Y1072016D01*
G37*
G36*
G01X352335Y1069373D02*
X352520Y1069973D01*
X353550D01*
X353735Y1069373D01*
Y1069199D01*
X352335D01*
Y1069373D01*
G37*
G36*
G01X348635Y1069375D02*
X348820Y1069975D01*
X349850D01*
X350035Y1069375D01*
Y1069200D01*
X348635D01*
Y1069375D01*
G37*
G36*
G01X343085Y1072579D02*
X343270Y1073179D01*
X344300D01*
X344485Y1072579D01*
Y1072404D01*
X343085D01*
Y1072579D01*
G37*
G36*
G01X339947Y1075176D02*
X340559Y1075316D01*
X341074Y1074424D01*
X340647Y1073964D01*
X340496Y1073877D01*
X339796Y1075089D01*
X339947Y1075176D01*
G37*
G36*
G01X345471Y1072016D02*
X346083Y1072156D01*
X346598Y1071264D01*
X346171Y1070804D01*
X346020Y1070717D01*
X345320Y1071929D01*
X345471Y1072016D01*
G37*
G36*
G01X352335Y1069373D02*
X352520Y1069973D01*
X353550D01*
X353735Y1069373D01*
Y1069199D01*
X352335D01*
Y1069373D01*
G37*
G36*
G01X340738Y1067777D02*
X340553Y1067177D01*
X339523D01*
X339338Y1067777D01*
Y1067952D01*
X340738D01*
Y1067777D01*
G37*
G36*
G01X343893Y1065152D02*
X343281Y1065012D01*
X342766Y1065904D01*
X343193Y1066364D01*
X343344Y1066451D01*
X344044Y1065239D01*
X343893Y1065152D01*
G37*
G36*
G01X350011Y1064575D02*
X349826Y1063975D01*
X348796D01*
X348611Y1064575D01*
Y1064749D01*
X350011D01*
Y1064575D01*
G37*
G36*
G01X346311D02*
X346126Y1063975D01*
X345096D01*
X344911Y1064575D01*
Y1064749D01*
X346311D01*
Y1064575D01*
G37*
G36*
G01X353711D02*
X353526Y1063975D01*
X352496D01*
X352311Y1064575D01*
Y1064749D01*
X353711D01*
Y1064575D01*
G37*
G36*
G01X340738Y1067777D02*
X340553Y1067177D01*
X339523D01*
X339338Y1067777D01*
Y1067952D01*
X340738D01*
Y1067777D01*
G37*
G36*
G01X343893Y1065152D02*
X343281Y1065012D01*
X342766Y1065904D01*
X343193Y1066364D01*
X343344Y1066451D01*
X344044Y1065239D01*
X343893Y1065152D01*
G37*
G36*
G01X350011Y1064575D02*
X349826Y1063975D01*
X348796D01*
X348611Y1064575D01*
Y1064749D01*
X350011D01*
Y1064575D01*
G37*
G36*
G01X346311D02*
X346126Y1063975D01*
X345096D01*
X344911Y1064575D01*
Y1064749D01*
X346311D01*
Y1064575D01*
G37*
G36*
G01X353711D02*
X353526Y1063975D01*
X352496D01*
X352311Y1064575D01*
Y1064749D01*
X353711D01*
Y1064575D01*
G37*
G36*
G01X339361Y1066169D02*
X339546Y1066769D01*
X340576D01*
X340761Y1066169D01*
Y1065995D01*
X339361D01*
Y1066169D01*
G37*
G36*
G01X341779Y1065592D02*
X342391Y1065732D01*
X342906Y1064840D01*
X342479Y1064380D01*
X342328Y1064293D01*
X341628Y1065505D01*
X341779Y1065592D01*
G37*
G36*
G01X339361Y1066169D02*
X339546Y1066769D01*
X340576D01*
X340761Y1066169D01*
Y1065995D01*
X339361D01*
Y1066169D01*
G37*
G36*
G01X341779Y1065592D02*
X342391Y1065732D01*
X342906Y1064840D01*
X342479Y1064380D01*
X342328Y1064293D01*
X341628Y1065505D01*
X341779Y1065592D01*
G37*
G36*
G01X346761Y1066169D02*
X346946Y1066769D01*
X347976D01*
X348161Y1066169D01*
Y1065995D01*
X346761D01*
Y1066169D01*
G37*
G36*
G01X343646Y1068767D02*
X344258Y1068907D01*
X344773Y1068015D01*
X344346Y1067555D01*
X344195Y1067468D01*
X343495Y1068680D01*
X343646Y1068767D01*
G37*
G36*
G01X350461Y1066169D02*
X350646Y1066769D01*
X351676D01*
X351861Y1066169D01*
Y1065995D01*
X350461D01*
Y1066169D01*
G37*
G36*
G01X338097Y1071971D02*
X338709Y1072111D01*
X339224Y1071219D01*
X338797Y1070759D01*
X338646Y1070672D01*
X337946Y1071884D01*
X338097Y1071971D01*
G37*
G36*
G01X341244Y1069374D02*
X341429Y1069974D01*
X342459D01*
X342644Y1069374D01*
Y1069200D01*
X341244D01*
Y1069374D01*
G37*
G36*
G01X354161Y1066169D02*
X354346Y1066769D01*
X355376D01*
X355561Y1066169D01*
Y1065995D01*
X354161D01*
Y1066169D01*
G37*
G36*
G01X346761D02*
X346946Y1066769D01*
X347976D01*
X348161Y1066169D01*
Y1065995D01*
X346761D01*
Y1066169D01*
G37*
G36*
G01X343646Y1068767D02*
X344258Y1068907D01*
X344773Y1068015D01*
X344346Y1067555D01*
X344195Y1067468D01*
X343495Y1068680D01*
X343646Y1068767D01*
G37*
G36*
G01X350461Y1066169D02*
X350646Y1066769D01*
X351676D01*
X351861Y1066169D01*
Y1065995D01*
X350461D01*
Y1066169D01*
G37*
G36*
G01X338097Y1071971D02*
X338709Y1072111D01*
X339224Y1071219D01*
X338797Y1070759D01*
X338646Y1070672D01*
X337946Y1071884D01*
X338097Y1071971D01*
G37*
G36*
G01X341244Y1069374D02*
X341429Y1069974D01*
X342459D01*
X342644Y1069374D01*
Y1069200D01*
X341244D01*
Y1069374D01*
G37*
G36*
G01X354161Y1066169D02*
X354346Y1066769D01*
X355376D01*
X355561Y1066169D01*
Y1065995D01*
X354161D01*
Y1066169D01*
G37*
G36*
G01Y1078987D02*
X354346Y1079587D01*
X355376D01*
X355561Y1078987D01*
Y1078812D01*
X354161D01*
Y1078987D01*
G37*
G36*
G01D02*
X354346Y1079587D01*
X355376D01*
X355561Y1078987D01*
Y1078812D01*
X354161D01*
Y1078987D01*
G37*
G36*
G01X349179Y1078409D02*
X349791Y1078549D01*
X350306Y1077657D01*
X349879Y1077197D01*
X349728Y1077110D01*
X349028Y1078322D01*
X349179Y1078409D01*
G37*
G36*
G01X346761Y1078987D02*
X346946Y1079587D01*
X347976D01*
X348161Y1078987D01*
Y1078812D01*
X346761D01*
Y1078987D01*
G37*
G36*
G01X352311Y1075783D02*
X352496Y1076383D01*
X353526D01*
X353711Y1075783D01*
Y1075608D01*
X352311D01*
Y1075783D01*
G37*
G36*
G01X349179Y1078409D02*
X349791Y1078549D01*
X350306Y1077657D01*
X349879Y1077197D01*
X349728Y1077110D01*
X349028Y1078322D01*
X349179Y1078409D01*
G37*
G36*
G01X346761Y1078987D02*
X346946Y1079587D01*
X347976D01*
X348161Y1078987D01*
Y1078812D01*
X346761D01*
Y1078987D01*
G37*
G36*
G01X352311Y1075783D02*
X352496Y1076383D01*
X353526D01*
X353711Y1075783D01*
Y1075608D01*
X352311D01*
Y1075783D01*
G37*
G36*
G01X351293Y1077969D02*
X350681Y1077829D01*
X350166Y1078721D01*
X350593Y1079181D01*
X350744Y1079268D01*
X351444Y1078056D01*
X351293Y1077969D01*
G37*
G36*
G01X353711Y1077391D02*
X353526Y1076791D01*
X352496D01*
X352311Y1077391D01*
Y1077566D01*
X353711D01*
Y1077391D01*
G37*
G36*
G01X351293Y1077969D02*
X350681Y1077829D01*
X350166Y1078721D01*
X350593Y1079181D01*
X350744Y1079268D01*
X351444Y1078056D01*
X351293Y1077969D01*
G37*
G36*
G01X353711Y1077391D02*
X353526Y1076791D01*
X352496D01*
X352311Y1077391D01*
Y1077566D01*
X353711D01*
Y1077391D01*
G37*
G36*
G01X349426Y1074793D02*
X348814Y1074653D01*
X348299Y1075545D01*
X348726Y1076005D01*
X348877Y1076092D01*
X349577Y1074880D01*
X349426Y1074793D01*
G37*
G36*
G01X346311Y1077391D02*
X346126Y1076791D01*
X345096D01*
X344911Y1077391D01*
Y1077566D01*
X346311D01*
Y1077391D01*
G37*
G36*
G01X343893Y1077969D02*
X343281Y1077829D01*
X342766Y1078721D01*
X343193Y1079181D01*
X343344Y1079268D01*
X344044Y1078056D01*
X343893Y1077969D01*
G37*
G36*
G01X351885Y1074187D02*
X351700Y1073587D01*
X350670D01*
X350485Y1074187D01*
Y1074362D01*
X351885D01*
Y1074187D01*
G37*
G36*
G01X349426Y1074793D02*
X348814Y1074653D01*
X348299Y1075545D01*
X348726Y1076005D01*
X348877Y1076092D01*
X349577Y1074880D01*
X349426Y1074793D01*
G37*
G36*
G01X346311Y1077391D02*
X346126Y1076791D01*
X345096D01*
X344911Y1077391D01*
Y1077566D01*
X346311D01*
Y1077391D01*
G37*
G36*
G01X343893Y1077969D02*
X343281Y1077829D01*
X342766Y1078721D01*
X343193Y1079181D01*
X343344Y1079268D01*
X344044Y1078056D01*
X343893Y1077969D01*
G37*
G36*
G01X351885Y1074187D02*
X351700Y1073587D01*
X350670D01*
X350485Y1074187D01*
Y1074362D01*
X351885D01*
Y1074187D01*
G37*
G36*
G01X353151Y1093975D02*
X352539Y1093835D01*
X352024Y1094727D01*
X352451Y1095187D01*
X352602Y1095274D01*
X353302Y1094062D01*
X353151Y1093975D01*
G37*
G36*
G01X354976Y1090815D02*
X354364Y1090675D01*
X353849Y1091567D01*
X354276Y1092027D01*
X354427Y1092114D01*
X355127Y1090902D01*
X354976Y1090815D01*
G37*
G36*
G01X353151Y1093975D02*
X352539Y1093835D01*
X352024Y1094727D01*
X352451Y1095187D01*
X352602Y1095274D01*
X353302Y1094062D01*
X353151Y1093975D01*
G37*
G36*
G01X354976Y1090815D02*
X354364Y1090675D01*
X353849Y1091567D01*
X354276Y1092027D01*
X354427Y1092114D01*
X355127Y1090902D01*
X354976Y1090815D01*
G37*
G36*
G01X348611Y1082191D02*
X348796Y1082791D01*
X349826D01*
X350011Y1082191D01*
Y1082016D01*
X348611D01*
Y1082191D01*
G37*
G36*
G01X351029Y1081613D02*
X351641Y1081753D01*
X352156Y1080861D01*
X351729Y1080401D01*
X351578Y1080314D01*
X350878Y1081526D01*
X351029Y1081613D01*
G37*
G36*
G01X345481Y1084814D02*
X346093Y1084954D01*
X346608Y1084062D01*
X346181Y1083602D01*
X346030Y1083515D01*
X345330Y1084727D01*
X345481Y1084814D01*
G37*
G36*
G01X339924Y1088032D02*
X340536Y1088172D01*
X341051Y1087280D01*
X340624Y1086820D01*
X340473Y1086733D01*
X339773Y1087945D01*
X339924Y1088032D01*
G37*
G36*
G01X343060Y1085396D02*
X343245Y1085996D01*
X344275D01*
X344460Y1085396D01*
Y1085221D01*
X343060D01*
Y1085396D01*
G37*
G36*
G01X348611Y1082191D02*
X348796Y1082791D01*
X349826D01*
X350011Y1082191D01*
Y1082016D01*
X348611D01*
Y1082191D01*
G37*
G36*
G01X351029Y1081613D02*
X351641Y1081753D01*
X352156Y1080861D01*
X351729Y1080401D01*
X351578Y1080314D01*
X350878Y1081526D01*
X351029Y1081613D01*
G37*
G36*
G01X345481Y1084814D02*
X346093Y1084954D01*
X346608Y1084062D01*
X346181Y1083602D01*
X346030Y1083515D01*
X345330Y1084727D01*
X345481Y1084814D01*
G37*
G36*
G01X339924Y1088032D02*
X340536Y1088172D01*
X341051Y1087280D01*
X340624Y1086820D01*
X340473Y1086733D01*
X339773Y1087945D01*
X339924Y1088032D01*
G37*
G36*
G01X343060Y1085396D02*
X343245Y1085996D01*
X344275D01*
X344460Y1085396D01*
Y1085221D01*
X343060D01*
Y1085396D01*
G37*
G36*
G01X341177Y1082191D02*
X341362Y1082791D01*
X342392D01*
X342577Y1082191D01*
Y1082017D01*
X341177D01*
Y1082191D01*
G37*
G36*
G01X343646Y1081585D02*
X344258Y1081725D01*
X344773Y1080833D01*
X344346Y1080373D01*
X344195Y1080286D01*
X343495Y1081498D01*
X343646Y1081585D01*
G37*
G36*
G01X338070Y1084833D02*
X338682Y1084973D01*
X339197Y1084081D01*
X338770Y1083621D01*
X338619Y1083534D01*
X337919Y1084746D01*
X338070Y1084833D01*
G37*
G36*
G01X341177Y1082191D02*
X341362Y1082791D01*
X342392D01*
X342577Y1082191D01*
Y1082017D01*
X341177D01*
Y1082191D01*
G37*
G36*
G01X343646Y1081585D02*
X344258Y1081725D01*
X344773Y1080833D01*
X344346Y1080373D01*
X344195Y1080286D01*
X343495Y1081498D01*
X343646Y1081585D01*
G37*
G36*
G01X338070Y1084833D02*
X338682Y1084973D01*
X339197Y1084081D01*
X338770Y1083621D01*
X338619Y1083534D01*
X337919Y1084746D01*
X338070Y1084833D01*
G37*
G36*
G01X348161Y1080595D02*
X347976Y1079995D01*
X346946D01*
X346761Y1080595D01*
Y1080770D01*
X348161D01*
Y1080595D01*
G37*
G36*
G01D02*
X347976Y1079995D01*
X346946D01*
X346761Y1080595D01*
Y1080770D01*
X348161D01*
Y1080595D01*
G37*
G36*
G01X345718Y1081213D02*
X345106Y1081073D01*
X344591Y1081965D01*
X345018Y1082425D01*
X345169Y1082512D01*
X345869Y1081300D01*
X345718Y1081213D01*
G37*
G36*
G01X340200Y1084362D02*
X339588Y1084222D01*
X339073Y1085114D01*
X339500Y1085574D01*
X339651Y1085661D01*
X340351Y1084449D01*
X340200Y1084362D01*
G37*
G36*
G01X342610Y1083799D02*
X342425Y1083199D01*
X341395D01*
X341210Y1083799D01*
Y1083974D01*
X342610D01*
Y1083799D01*
G37*
G36*
G01X345718Y1081213D02*
X345106Y1081073D01*
X344591Y1081965D01*
X345018Y1082425D01*
X345169Y1082512D01*
X345869Y1081300D01*
X345718Y1081213D01*
G37*
G36*
G01X340200Y1084362D02*
X339588Y1084222D01*
X339073Y1085114D01*
X339500Y1085574D01*
X339651Y1085661D01*
X340351Y1084449D01*
X340200Y1084362D01*
G37*
G36*
G01X342610Y1083799D02*
X342425Y1083199D01*
X341395D01*
X341210Y1083799D01*
Y1083974D01*
X342610D01*
Y1083799D01*
G37*
G36*
G01X340794Y1080595D02*
X340609Y1079995D01*
X339579D01*
X339394Y1080595D01*
Y1080769D01*
X340794D01*
Y1080595D01*
G37*
G36*
G01D02*
X340609Y1079995D01*
X339579D01*
X339394Y1080595D01*
Y1080769D01*
X340794D01*
Y1080595D01*
G37*
G36*
G01X348127Y1093413D02*
X347942Y1092813D01*
X346912D01*
X346727Y1093413D01*
Y1093587D01*
X348127D01*
Y1093413D01*
G37*
G36*
G01X340727D02*
X340542Y1092813D01*
X339512D01*
X339327Y1093413D01*
Y1093587D01*
X340727D01*
Y1093413D01*
G37*
G36*
G01X344427D02*
X344242Y1092813D01*
X343212D01*
X343027Y1093413D01*
Y1093587D01*
X344427D01*
Y1093413D01*
G37*
G36*
G01X351268Y1090827D02*
X350656Y1090687D01*
X350141Y1091579D01*
X350568Y1092039D01*
X350719Y1092126D01*
X351419Y1090914D01*
X351268Y1090827D01*
G37*
G36*
G01X355001Y1084362D02*
X354389Y1084222D01*
X353874Y1085114D01*
X354301Y1085574D01*
X354452Y1085661D01*
X355152Y1084449D01*
X355001Y1084362D01*
G37*
G36*
G01X353143Y1087582D02*
X352531Y1087442D01*
X352016Y1088334D01*
X352443Y1088794D01*
X352594Y1088881D01*
X353294Y1087669D01*
X353143Y1087582D01*
G37*
G36*
G01X348127Y1093413D02*
X347942Y1092813D01*
X346912D01*
X346727Y1093413D01*
Y1093587D01*
X348127D01*
Y1093413D01*
G37*
G36*
G01X340727D02*
X340542Y1092813D01*
X339512D01*
X339327Y1093413D01*
Y1093587D01*
X340727D01*
Y1093413D01*
G37*
G36*
G01X344427D02*
X344242Y1092813D01*
X343212D01*
X343027Y1093413D01*
Y1093587D01*
X344427D01*
Y1093413D01*
G37*
G36*
G01X351268Y1090827D02*
X350656Y1090687D01*
X350141Y1091579D01*
X350568Y1092039D01*
X350719Y1092126D01*
X351419Y1090914D01*
X351268Y1090827D01*
G37*
G36*
G01X355001Y1084362D02*
X354389Y1084222D01*
X353874Y1085114D01*
X354301Y1085574D01*
X354452Y1085661D01*
X355152Y1084449D01*
X355001Y1084362D01*
G37*
G36*
G01X353143Y1087582D02*
X352531Y1087442D01*
X352016Y1088334D01*
X352443Y1088794D01*
X352594Y1088881D01*
X353294Y1087669D01*
X353143Y1087582D01*
G37*
G36*
G01X348611Y1088599D02*
X348796Y1089199D01*
X349826D01*
X350011Y1088599D01*
Y1088425D01*
X348611D01*
Y1088599D01*
G37*
G36*
G01X344944Y1088600D02*
X345129Y1089200D01*
X346159D01*
X346344Y1088600D01*
Y1088426D01*
X344944D01*
Y1088600D01*
G37*
G36*
G01X339327Y1091805D02*
X339512Y1092405D01*
X340542D01*
X340727Y1091805D01*
Y1091631D01*
X339327D01*
Y1091805D01*
G37*
G36*
G01X351029Y1088022D02*
X351641Y1088162D01*
X352156Y1087270D01*
X351729Y1086810D01*
X351578Y1086723D01*
X350878Y1087935D01*
X351029Y1088022D01*
G37*
G36*
G01X352871Y1084833D02*
X353483Y1084973D01*
X353998Y1084081D01*
X353571Y1083621D01*
X353420Y1083534D01*
X352720Y1084746D01*
X352871Y1084833D01*
G37*
G36*
G01X348611Y1088599D02*
X348796Y1089199D01*
X349826D01*
X350011Y1088599D01*
Y1088425D01*
X348611D01*
Y1088599D01*
G37*
G36*
G01X344944Y1088600D02*
X345129Y1089200D01*
X346159D01*
X346344Y1088600D01*
Y1088426D01*
X344944D01*
Y1088600D01*
G37*
G36*
G01X339327Y1091805D02*
X339512Y1092405D01*
X340542D01*
X340727Y1091805D01*
Y1091631D01*
X339327D01*
Y1091805D01*
G37*
G36*
G01X351029Y1088022D02*
X351641Y1088162D01*
X352156Y1087270D01*
X351729Y1086810D01*
X351578Y1086723D01*
X350878Y1087935D01*
X351029Y1088022D01*
G37*
G36*
G01X352871Y1084833D02*
X353483Y1084973D01*
X353998Y1084081D01*
X353571Y1083621D01*
X353420Y1083534D01*
X352720Y1084746D01*
X352871Y1084833D01*
G37*
G36*
G01X341244Y1095009D02*
X341429Y1095609D01*
X342459D01*
X342644Y1095009D01*
Y1094835D01*
X341244D01*
Y1095009D01*
G37*
G36*
G01X344944D02*
X345129Y1095609D01*
X346159D01*
X346344Y1095009D01*
Y1094835D01*
X344944D01*
Y1095009D01*
G37*
G36*
G01X348644D02*
X348829Y1095609D01*
X349859D01*
X350044Y1095009D01*
Y1094835D01*
X348644D01*
Y1095009D01*
G37*
G36*
G01X351046Y1094402D02*
X351658Y1094542D01*
X352173Y1093650D01*
X351746Y1093190D01*
X351595Y1093103D01*
X350895Y1094315D01*
X351046Y1094402D01*
G37*
G36*
G01X352879Y1091226D02*
X353491Y1091366D01*
X354006Y1090474D01*
X353579Y1090014D01*
X353428Y1089927D01*
X352728Y1091139D01*
X352879Y1091226D01*
G37*
G36*
G01X341244Y1095009D02*
X341429Y1095609D01*
X342459D01*
X342644Y1095009D01*
Y1094835D01*
X341244D01*
Y1095009D01*
G37*
G36*
G01X344944D02*
X345129Y1095609D01*
X346159D01*
X346344Y1095009D01*
Y1094835D01*
X344944D01*
Y1095009D01*
G37*
G36*
G01X348644D02*
X348829Y1095609D01*
X349859D01*
X350044Y1095009D01*
Y1094835D01*
X348644D01*
Y1095009D01*
G37*
G36*
G01X351046Y1094402D02*
X351658Y1094542D01*
X352173Y1093650D01*
X351746Y1093190D01*
X351595Y1093103D01*
X350895Y1094315D01*
X351046Y1094402D01*
G37*
G36*
G01X352879Y1091226D02*
X353491Y1091366D01*
X354006Y1090474D01*
X353579Y1090014D01*
X353428Y1089927D01*
X352728Y1091139D01*
X352879Y1091226D01*
G37*
G36*
G01X355561Y1080595D02*
X355376Y1079995D01*
X354346D01*
X354161Y1080595D01*
Y1080770D01*
X355561D01*
Y1080595D01*
G37*
G36*
G01D02*
X355376Y1079995D01*
X354346D01*
X354161Y1080595D01*
Y1080770D01*
X355561D01*
Y1080595D01*
G37*
G36*
G01X351301Y1084362D02*
X350689Y1084222D01*
X350174Y1085114D01*
X350601Y1085574D01*
X350752Y1085661D01*
X351452Y1084449D01*
X351301Y1084362D01*
G37*
G36*
G01X344427Y1087003D02*
X344242Y1086403D01*
X343212D01*
X343027Y1087003D01*
Y1087178D01*
X344427D01*
Y1087003D01*
G37*
G36*
G01X342047Y1087572D02*
X341435Y1087432D01*
X340920Y1088324D01*
X341347Y1088784D01*
X341498Y1088871D01*
X342198Y1087659D01*
X342047Y1087572D01*
G37*
G36*
G01X348137Y1087003D02*
X347952Y1086403D01*
X346922D01*
X346737Y1087003D01*
Y1087178D01*
X348137D01*
Y1087003D01*
G37*
G36*
G01X353143Y1081173D02*
X352531Y1081033D01*
X352016Y1081925D01*
X352443Y1082385D01*
X352594Y1082472D01*
X353294Y1081260D01*
X353143Y1081173D01*
G37*
G36*
G01X351301Y1084362D02*
X350689Y1084222D01*
X350174Y1085114D01*
X350601Y1085574D01*
X350752Y1085661D01*
X351452Y1084449D01*
X351301Y1084362D01*
G37*
G36*
G01X344427Y1087003D02*
X344242Y1086403D01*
X343212D01*
X343027Y1087003D01*
Y1087178D01*
X344427D01*
Y1087003D01*
G37*
G36*
G01X342047Y1087572D02*
X341435Y1087432D01*
X340920Y1088324D01*
X341347Y1088784D01*
X341498Y1088871D01*
X342198Y1087659D01*
X342047Y1087572D01*
G37*
G36*
G01X348137Y1087003D02*
X347952Y1086403D01*
X346922D01*
X346737Y1087003D01*
Y1087178D01*
X348137D01*
Y1087003D01*
G37*
G36*
G01X353143Y1081173D02*
X352531Y1081033D01*
X352016Y1081925D01*
X352443Y1082385D01*
X352594Y1082472D01*
X353294Y1081260D01*
X353143Y1081173D01*
G37*
G36*
G01X339929Y1107248D02*
X340541Y1107388D01*
X341056Y1106496D01*
X340629Y1106036D01*
X340478Y1105949D01*
X339778Y1107161D01*
X339929Y1107248D01*
G37*
G36*
G01X344911Y1101416D02*
X345096Y1102016D01*
X346126D01*
X346311Y1101416D01*
Y1101242D01*
X344911D01*
Y1101416D01*
G37*
G36*
G01X341771Y1104059D02*
X342383Y1104199D01*
X342898Y1103307D01*
X342471Y1102847D01*
X342320Y1102760D01*
X341620Y1103972D01*
X341771Y1104059D01*
G37*
G36*
G01X344911Y1101416D02*
X345096Y1102016D01*
X346126D01*
X346311Y1101416D01*
Y1101242D01*
X344911D01*
Y1101416D01*
G37*
G36*
G01X341771Y1104059D02*
X342383Y1104199D01*
X342898Y1103307D01*
X342471Y1102847D01*
X342320Y1102760D01*
X341620Y1103972D01*
X341771Y1104059D01*
G37*
G36*
G01X348611Y1101416D02*
X348796Y1102016D01*
X349826D01*
X350011Y1101416D01*
Y1101242D01*
X348611D01*
Y1101416D01*
G37*
G36*
G01X352879Y1097635D02*
X353491Y1097775D01*
X354006Y1096883D01*
X353579Y1096423D01*
X353428Y1096336D01*
X352728Y1097548D01*
X352879Y1097635D01*
G37*
G36*
G01D02*
X353491Y1097775D01*
X354006Y1096883D01*
X353579Y1096423D01*
X353428Y1096336D01*
X352728Y1097548D01*
X352879Y1097635D01*
G37*
G36*
G01X339929Y1100839D02*
X340541Y1100979D01*
X341056Y1100087D01*
X340629Y1099627D01*
X340478Y1099540D01*
X339778Y1100752D01*
X339929Y1100839D01*
G37*
G36*
G01X343061Y1098212D02*
X343246Y1098812D01*
X344276D01*
X344461Y1098212D01*
Y1098038D01*
X343061D01*
Y1098212D01*
G37*
G36*
G01X338071Y1104059D02*
X338683Y1104199D01*
X339198Y1103307D01*
X338771Y1102847D01*
X338620Y1102760D01*
X337920Y1103972D01*
X338071Y1104059D01*
G37*
G36*
G01X339929Y1100839D02*
X340541Y1100979D01*
X341056Y1100087D01*
X340629Y1099627D01*
X340478Y1099540D01*
X339778Y1100752D01*
X339929Y1100839D01*
G37*
G36*
G01X343061Y1098212D02*
X343246Y1098812D01*
X344276D01*
X344461Y1098212D01*
Y1098038D01*
X343061D01*
Y1098212D01*
G37*
G36*
G01X338071Y1104059D02*
X338683Y1104199D01*
X339198Y1103307D01*
X338771Y1102847D01*
X338620Y1102760D01*
X337920Y1103972D01*
X338071Y1104059D01*
G37*
G36*
G01X346761Y1098212D02*
X346946Y1098812D01*
X347976D01*
X348161Y1098212D01*
Y1098038D01*
X346761D01*
Y1098212D01*
G37*
G36*
G01X350461D02*
X350646Y1098812D01*
X351676D01*
X351861Y1098212D01*
Y1098038D01*
X350461D01*
Y1098212D01*
G37*
G36*
G01X346761D02*
X346946Y1098812D01*
X347976D01*
X348161Y1098212D01*
Y1098038D01*
X346761D01*
Y1098212D01*
G37*
G36*
G01X350461D02*
X350646Y1098812D01*
X351676D01*
X351861Y1098212D01*
Y1098038D01*
X350461D01*
Y1098212D01*
G37*
G36*
G01X354993Y1097195D02*
X354381Y1097055D01*
X353866Y1097947D01*
X354293Y1098407D01*
X354444Y1098494D01*
X355144Y1097282D01*
X354993Y1097195D01*
G37*
G36*
G01D02*
X354381Y1097055D01*
X353866Y1097947D01*
X354293Y1098407D01*
X354444Y1098494D01*
X355144Y1097282D01*
X354993Y1097195D01*
G37*
G36*
G01X340201Y1103588D02*
X339589Y1103448D01*
X339074Y1104340D01*
X339501Y1104800D01*
X339652Y1104887D01*
X340352Y1103675D01*
X340201Y1103588D01*
G37*
G36*
G01X344461Y1099822D02*
X344276Y1099222D01*
X343246D01*
X343061Y1099822D01*
Y1099996D01*
X344461D01*
Y1099822D01*
G37*
G36*
G01X342043Y1100399D02*
X341431Y1100259D01*
X340916Y1101151D01*
X341343Y1101611D01*
X341494Y1101698D01*
X342194Y1100486D01*
X342043Y1100399D01*
G37*
G36*
G01X344461Y1099822D02*
X344276Y1099222D01*
X343246D01*
X343061Y1099822D01*
Y1099996D01*
X344461D01*
Y1099822D01*
G37*
G36*
G01X342043Y1100399D02*
X341431Y1100259D01*
X340916Y1101151D01*
X341343Y1101611D01*
X341494Y1101698D01*
X342194Y1100486D01*
X342043Y1100399D01*
G37*
G36*
G01X340201Y1103588D02*
X339589Y1103448D01*
X339074Y1104340D01*
X339501Y1104800D01*
X339652Y1104887D01*
X340352Y1103675D01*
X340201Y1103588D01*
G37*
G36*
G01X348161Y1099822D02*
X347976Y1099222D01*
X346946D01*
X346761Y1099822D01*
Y1099996D01*
X348161D01*
Y1099822D01*
G37*
G36*
G01X351861D02*
X351676Y1099222D01*
X350646D01*
X350461Y1099822D01*
Y1099996D01*
X351861D01*
Y1099822D01*
G37*
G36*
G01X348161D02*
X347976Y1099222D01*
X346946D01*
X346761Y1099822D01*
Y1099996D01*
X348161D01*
Y1099822D01*
G37*
G36*
G01X351861D02*
X351676Y1099222D01*
X350646D01*
X350461Y1099822D01*
Y1099996D01*
X351861D01*
Y1099822D01*
G37*
G36*
G01X340193Y1097195D02*
X339581Y1097055D01*
X339066Y1097947D01*
X339493Y1098407D01*
X339644Y1098494D01*
X340344Y1097282D01*
X340193Y1097195D01*
G37*
G36*
G01X342611Y1096617D02*
X342426Y1096017D01*
X341396D01*
X341211Y1096617D01*
Y1096792D01*
X342611D01*
Y1096617D01*
G37*
G36*
G01X350011D02*
X349826Y1096017D01*
X348796D01*
X348611Y1096617D01*
Y1096792D01*
X350011D01*
Y1096617D01*
G37*
G36*
G01X346311D02*
X346126Y1096017D01*
X345096D01*
X344911Y1096617D01*
Y1096792D01*
X346311D01*
Y1096617D01*
G37*
G36*
G01X340193Y1097195D02*
X339581Y1097055D01*
X339066Y1097947D01*
X339493Y1098407D01*
X339644Y1098494D01*
X340344Y1097282D01*
X340193Y1097195D01*
G37*
G36*
G01X342611Y1096617D02*
X342426Y1096017D01*
X341396D01*
X341211Y1096617D01*
Y1096792D01*
X342611D01*
Y1096617D01*
G37*
G36*
G01X350011D02*
X349826Y1096017D01*
X348796D01*
X348611Y1096617D01*
Y1096792D01*
X350011D01*
Y1096617D01*
G37*
G36*
G01X346311D02*
X346126Y1096017D01*
X345096D01*
X344911Y1096617D01*
Y1096792D01*
X346311D01*
Y1096617D01*
G37*
G36*
G01X360547Y882813D02*
X360974Y882353D01*
X360459Y881461D01*
X359847Y881601D01*
X359696Y881688D01*
X360396Y882900D01*
X360547Y882813D01*
G37*
G36*
G01X367943Y882803D02*
X368370Y882343D01*
X367855Y881451D01*
X367243Y881591D01*
X367092Y881678D01*
X367792Y882890D01*
X367943Y882803D01*
G37*
G36*
G01X355710Y882813D02*
X355283Y882353D01*
X355798Y881461D01*
X356410Y881601D01*
X356561Y881688D01*
X355861Y882900D01*
X355710Y882813D01*
G37*
G36*
G01X363110D02*
X362683Y882353D01*
X363198Y881461D01*
X363810Y881601D01*
X363961Y881688D01*
X363261Y882900D01*
X363110Y882813D01*
G37*
G36*
G01X360547D02*
X360974Y882353D01*
X360459Y881461D01*
X359847Y881601D01*
X359696Y881688D01*
X360396Y882900D01*
X360547Y882813D01*
G37*
G36*
G01X367943Y882803D02*
X368370Y882343D01*
X367855Y881451D01*
X367243Y881591D01*
X367092Y881678D01*
X367792Y882890D01*
X367943Y882803D01*
G37*
G36*
G01X355710Y882813D02*
X355283Y882353D01*
X355798Y881461D01*
X356410Y881601D01*
X356561Y881688D01*
X355861Y882900D01*
X355710Y882813D01*
G37*
G36*
G01X363110D02*
X362683Y882353D01*
X363198Y881461D01*
X363810Y881601D01*
X363961Y881688D01*
X363261Y882900D01*
X363110Y882813D01*
G37*
G36*
G01X366815Y884043D02*
X366388Y884503D01*
X366903Y885395D01*
X367515Y885255D01*
X367666Y885168D01*
X366966Y883956D01*
X366815Y884043D01*
G37*
G36*
G01X359410Y884033D02*
X358983Y884493D01*
X359498Y885385D01*
X360110Y885245D01*
X360261Y885158D01*
X359561Y883946D01*
X359410Y884033D01*
G37*
G36*
G01X366815Y884043D02*
X366388Y884503D01*
X366903Y885395D01*
X367515Y885255D01*
X367666Y885168D01*
X366966Y883956D01*
X366815Y884043D01*
G37*
G36*
G01X359410Y884033D02*
X358983Y884493D01*
X359498Y885385D01*
X360110Y885245D01*
X360261Y885158D01*
X359561Y883946D01*
X359410Y884033D01*
G37*
G36*
G01X356164Y885217D02*
X356776Y885357D01*
X357291Y884465D01*
X356864Y884005D01*
X356713Y883918D01*
X356013Y885130D01*
X356164Y885217D01*
G37*
G36*
G01X363564D02*
X364176Y885357D01*
X364691Y884465D01*
X364264Y884005D01*
X364113Y883918D01*
X363413Y885130D01*
X363564Y885217D01*
G37*
G36*
G01X358805Y900249D02*
X358620Y899649D01*
X357590D01*
X357405Y900249D01*
Y900423D01*
X358805D01*
Y900249D01*
G37*
G36*
G01D02*
X358620Y899649D01*
X357590D01*
X357405Y900249D01*
Y900423D01*
X358805D01*
Y900249D01*
G37*
G36*
G01X357405Y898641D02*
X357590Y899241D01*
X358620D01*
X358805Y898641D01*
Y898467D01*
X357405D01*
Y898641D01*
G37*
G36*
G01X361243Y900027D02*
X360816Y900487D01*
X361331Y901379D01*
X361943Y901239D01*
X362094Y901152D01*
X361394Y899940D01*
X361243Y900027D01*
G37*
G36*
G01X357405Y898641D02*
X357590Y899241D01*
X358620D01*
X358805Y898641D01*
Y898467D01*
X357405D01*
Y898641D01*
G37*
G36*
G01X361243Y900027D02*
X360816Y900487D01*
X361331Y901379D01*
X361943Y901239D01*
X362094Y901152D01*
X361394Y899940D01*
X361243Y900027D01*
G37*
G36*
G01X360655Y897045D02*
X360470Y896445D01*
X359440D01*
X359255Y897045D01*
Y897219D01*
X360655D01*
Y897045D01*
G37*
G36*
G01X362393Y898827D02*
X362820Y898367D01*
X362305Y897475D01*
X361693Y897615D01*
X361542Y897702D01*
X362242Y898914D01*
X362393Y898827D01*
G37*
G36*
G01X366195Y900249D02*
X366010Y899649D01*
X364980D01*
X364795Y900249D01*
Y900423D01*
X366195D01*
Y900249D01*
G37*
G36*
G01X357012Y897043D02*
X356827Y896443D01*
X355797D01*
X355612Y897043D01*
Y897218D01*
X357012D01*
Y897043D01*
G37*
G36*
G01X369895Y900249D02*
X369710Y899649D01*
X368680D01*
X368495Y900249D01*
Y900423D01*
X369895D01*
Y900249D01*
G37*
G36*
G01X360655Y897045D02*
X360470Y896445D01*
X359440D01*
X359255Y897045D01*
Y897219D01*
X360655D01*
Y897045D01*
G37*
G36*
G01X362393Y898827D02*
X362820Y898367D01*
X362305Y897475D01*
X361693Y897615D01*
X361542Y897702D01*
X362242Y898914D01*
X362393Y898827D01*
G37*
G36*
G01X366195Y900249D02*
X366010Y899649D01*
X364980D01*
X364795Y900249D01*
Y900423D01*
X366195D01*
Y900249D01*
G37*
G36*
G01X357012Y897043D02*
X356827Y896443D01*
X355797D01*
X355612Y897043D01*
Y897218D01*
X357012D01*
Y897043D01*
G37*
G36*
G01X369895Y900249D02*
X369710Y899649D01*
X368680D01*
X368495Y900249D01*
Y900423D01*
X369895D01*
Y900249D01*
G37*
G36*
G01X359302Y889029D02*
X359487Y889629D01*
X360517D01*
X360702Y889029D01*
Y888854D01*
X359302D01*
Y889029D01*
G37*
G36*
G01X363012D02*
X363197Y889629D01*
X364227D01*
X364412Y889029D01*
Y888854D01*
X363012D01*
Y889029D01*
G37*
G36*
G01X355602Y889027D02*
X355787Y889627D01*
X356817D01*
X357002Y889027D01*
Y888853D01*
X355602D01*
Y889027D01*
G37*
G36*
G01X366811Y890442D02*
X366384Y890902D01*
X366899Y891794D01*
X367511Y891654D01*
X367662Y891567D01*
X366962Y890355D01*
X366811Y890442D01*
G37*
G36*
G01X368495Y892233D02*
X368680Y892833D01*
X369710D01*
X369895Y892233D01*
Y892058D01*
X368495D01*
Y892233D01*
G37*
G36*
G01X359302Y889029D02*
X359487Y889629D01*
X360517D01*
X360702Y889029D01*
Y888854D01*
X359302D01*
Y889029D01*
G37*
G36*
G01X363012D02*
X363197Y889629D01*
X364227D01*
X364412Y889029D01*
Y888854D01*
X363012D01*
Y889029D01*
G37*
G36*
G01X355602Y889027D02*
X355787Y889627D01*
X356817D01*
X357002Y889027D01*
Y888853D01*
X355602D01*
Y889027D01*
G37*
G36*
G01X366811Y890442D02*
X366384Y890902D01*
X366899Y891794D01*
X367511Y891654D01*
X367662Y891567D01*
X366962Y890355D01*
X366811Y890442D01*
G37*
G36*
G01X368495Y892233D02*
X368680Y892833D01*
X369710D01*
X369895Y892233D01*
Y892058D01*
X368495D01*
Y892233D01*
G37*
G36*
G01X369792Y886007D02*
X370219Y885547D01*
X369704Y884655D01*
X369092Y884795D01*
X368941Y884882D01*
X369641Y886094D01*
X369792Y886007D01*
G37*
G36*
G01D02*
X370219Y885547D01*
X369704Y884655D01*
X369092Y884795D01*
X368941Y884882D01*
X369641Y886094D01*
X369792Y886007D01*
G37*
G36*
G01X358828Y887431D02*
X358643Y886831D01*
X357613D01*
X357428Y887431D01*
Y887606D01*
X358828D01*
Y887431D01*
G37*
G36*
G01X362495D02*
X362310Y886831D01*
X361280D01*
X361095Y887431D01*
Y887605D01*
X362495D01*
Y887431D01*
G37*
G36*
G01X366195D02*
X366010Y886831D01*
X364980D01*
X364795Y887431D01*
Y887605D01*
X366195D01*
Y887431D01*
G37*
G36*
G01X367943Y889214D02*
X368370Y888754D01*
X367855Y887862D01*
X367243Y888002D01*
X367092Y888089D01*
X367792Y889301D01*
X367943Y889214D01*
G37*
G36*
G01X371812Y890635D02*
X371627Y890035D01*
X370597D01*
X370412Y890635D01*
Y890810D01*
X371812D01*
Y890635D01*
G37*
G36*
G01X358828Y887431D02*
X358643Y886831D01*
X357613D01*
X357428Y887431D01*
Y887606D01*
X358828D01*
Y887431D01*
G37*
G36*
G01X362495D02*
X362310Y886831D01*
X361280D01*
X361095Y887431D01*
Y887605D01*
X362495D01*
Y887431D01*
G37*
G36*
G01X366195D02*
X366010Y886831D01*
X364980D01*
X364795Y887431D01*
Y887605D01*
X366195D01*
Y887431D01*
G37*
G36*
G01X367943Y889214D02*
X368370Y888754D01*
X367855Y887862D01*
X367243Y888002D01*
X367092Y888089D01*
X367792Y889301D01*
X367943Y889214D01*
G37*
G36*
G01X371812Y890635D02*
X371627Y890035D01*
X370597D01*
X370412Y890635D01*
Y890810D01*
X371812D01*
Y890635D01*
G37*
G36*
G01X370412Y889029D02*
X370597Y889629D01*
X371627D01*
X371812Y889029D01*
Y888854D01*
X370412D01*
Y889029D01*
G37*
G36*
G01X368664Y887245D02*
X368237Y887705D01*
X368752Y888597D01*
X369364Y888457D01*
X369515Y888370D01*
X368815Y887158D01*
X368664Y887245D01*
G37*
G36*
G01X370412Y889029D02*
X370597Y889629D01*
X371627D01*
X371812Y889029D01*
Y888854D01*
X370412D01*
Y889029D01*
G37*
G36*
G01X368664Y887245D02*
X368237Y887705D01*
X368752Y888597D01*
X369364Y888457D01*
X369515Y888370D01*
X368815Y887158D01*
X368664Y887245D01*
G37*
G36*
G01X364264Y895659D02*
X364691Y895199D01*
X364176Y894307D01*
X363564Y894447D01*
X363413Y894534D01*
X364113Y895746D01*
X364264Y895659D01*
G37*
G36*
G01X368112Y897043D02*
X367927Y896443D01*
X366897D01*
X366712Y897043D01*
Y897218D01*
X368112D01*
Y897043D01*
G37*
G36*
G01X358805Y893839D02*
X358620Y893239D01*
X357590D01*
X357405Y893839D01*
Y894014D01*
X358805D01*
Y893839D01*
G37*
G36*
G01X362562D02*
X362377Y893239D01*
X361347D01*
X361162Y893839D01*
Y894014D01*
X362562D01*
Y893839D01*
G37*
G36*
G01X364264Y895659D02*
X364691Y895199D01*
X364176Y894307D01*
X363564Y894447D01*
X363413Y894534D01*
X364113Y895746D01*
X364264Y895659D01*
G37*
G36*
G01X368112Y897043D02*
X367927Y896443D01*
X366897D01*
X366712Y897043D01*
Y897218D01*
X368112D01*
Y897043D01*
G37*
G36*
G01X358805Y893839D02*
X358620Y893239D01*
X357590D01*
X357405Y893839D01*
Y894014D01*
X358805D01*
Y893839D01*
G37*
G36*
G01X362562D02*
X362377Y893239D01*
X361347D01*
X361162Y893839D01*
Y894014D01*
X362562D01*
Y893839D01*
G37*
G36*
G01X366712Y895437D02*
X366897Y896037D01*
X367927D01*
X368112Y895437D01*
Y895262D01*
X366712D01*
Y895437D01*
G37*
G36*
G01X364961Y893646D02*
X364534Y894106D01*
X365049Y894998D01*
X365661Y894858D01*
X365812Y894771D01*
X365112Y893559D01*
X364961Y893646D01*
G37*
G36*
G01X357452Y892233D02*
X357637Y892833D01*
X358667D01*
X358852Y892233D01*
Y892058D01*
X357452D01*
Y892233D01*
G37*
G36*
G01X361129Y892231D02*
X361314Y892831D01*
X362344D01*
X362529Y892231D01*
Y892057D01*
X361129D01*
Y892231D01*
G37*
G36*
G01X370412Y895437D02*
X370597Y896037D01*
X371627D01*
X371812Y895437D01*
Y895262D01*
X370412D01*
Y895437D01*
G37*
G36*
G01X366712D02*
X366897Y896037D01*
X367927D01*
X368112Y895437D01*
Y895262D01*
X366712D01*
Y895437D01*
G37*
G36*
G01X364961Y893646D02*
X364534Y894106D01*
X365049Y894998D01*
X365661Y894858D01*
X365812Y894771D01*
X365112Y893559D01*
X364961Y893646D01*
G37*
G36*
G01X357452Y892233D02*
X357637Y892833D01*
X358667D01*
X358852Y892233D01*
Y892058D01*
X357452D01*
Y892233D01*
G37*
G36*
G01X361129Y892231D02*
X361314Y892831D01*
X362344D01*
X362529Y892231D01*
Y892057D01*
X361129D01*
Y892231D01*
G37*
G36*
G01X370412Y895437D02*
X370597Y896037D01*
X371627D01*
X371812Y895437D01*
Y895262D01*
X370412D01*
Y895437D01*
G37*
G36*
G01X359255Y895435D02*
X359440Y896035D01*
X360470D01*
X360655Y895435D01*
Y895261D01*
X359255D01*
Y895435D01*
G37*
G36*
G01X364795Y898641D02*
X364980Y899241D01*
X366010D01*
X366195Y898641D01*
Y898467D01*
X364795D01*
Y898641D01*
G37*
G36*
G01X363114Y896858D02*
X362687Y897318D01*
X363202Y898210D01*
X363814Y898070D01*
X363965Y897983D01*
X363265Y896771D01*
X363114Y896858D01*
G37*
G36*
G01X355612Y895437D02*
X355797Y896037D01*
X356827D01*
X357012Y895437D01*
Y895262D01*
X355612D01*
Y895437D01*
G37*
G36*
G01X359255Y895435D02*
X359440Y896035D01*
X360470D01*
X360655Y895435D01*
Y895261D01*
X359255D01*
Y895435D01*
G37*
G36*
G01X364795Y898641D02*
X364980Y899241D01*
X366010D01*
X366195Y898641D01*
Y898467D01*
X364795D01*
Y898641D01*
G37*
G36*
G01X363114Y896858D02*
X362687Y897318D01*
X363202Y898210D01*
X363814Y898070D01*
X363965Y897983D01*
X363265Y896771D01*
X363114Y896858D01*
G37*
G36*
G01X355612Y895437D02*
X355797Y896037D01*
X356827D01*
X357012Y895437D01*
Y895262D01*
X355612D01*
Y895437D01*
G37*
G36*
G01X360655Y890635D02*
X360470Y890035D01*
X359440D01*
X359255Y890635D01*
Y890810D01*
X360655D01*
Y890635D01*
G37*
G36*
G01X364379Y890637D02*
X364194Y890037D01*
X363164D01*
X362979Y890637D01*
Y890811D01*
X364379D01*
Y890637D01*
G37*
G36*
G01X357002D02*
X356817Y890037D01*
X355787D01*
X355602Y890637D01*
Y890811D01*
X357002D01*
Y890637D01*
G37*
G36*
G01X366097Y892426D02*
X366524Y891966D01*
X366009Y891074D01*
X365397Y891214D01*
X365246Y891301D01*
X365946Y892513D01*
X366097Y892426D01*
G37*
G36*
G01X369895Y893839D02*
X369710Y893239D01*
X368680D01*
X368495Y893839D01*
Y894014D01*
X369895D01*
Y893839D01*
G37*
G36*
G01X360655Y890635D02*
X360470Y890035D01*
X359440D01*
X359255Y890635D01*
Y890810D01*
X360655D01*
Y890635D01*
G37*
G36*
G01X364379Y890637D02*
X364194Y890037D01*
X363164D01*
X362979Y890637D01*
Y890811D01*
X364379D01*
Y890637D01*
G37*
G36*
G01X357002D02*
X356817Y890037D01*
X355787D01*
X355602Y890637D01*
Y890811D01*
X357002D01*
Y890637D01*
G37*
G36*
G01X366097Y892426D02*
X366524Y891966D01*
X366009Y891074D01*
X365397Y891214D01*
X365246Y891301D01*
X365946Y892513D01*
X366097Y892426D01*
G37*
G36*
G01X369895Y893839D02*
X369710Y893239D01*
X368680D01*
X368495Y893839D01*
Y894014D01*
X369895D01*
Y893839D01*
G37*
G36*
G01X360547Y902039D02*
X360974Y901579D01*
X360459Y900687D01*
X359847Y900827D01*
X359696Y900914D01*
X360396Y902126D01*
X360547Y902039D01*
G37*
G36*
G01X364412Y903453D02*
X364227Y902853D01*
X363197D01*
X363012Y903453D01*
Y903627D01*
X364412D01*
Y903453D01*
G37*
G36*
G01X368112D02*
X367927Y902853D01*
X366897D01*
X366712Y903453D01*
Y903627D01*
X368112D01*
Y903453D01*
G37*
G36*
G01X371802D02*
X371617Y902853D01*
X370587D01*
X370402Y903453D01*
Y903628D01*
X371802D01*
Y903453D01*
G37*
G36*
G01X360547Y902039D02*
X360974Y901579D01*
X360459Y900687D01*
X359847Y900827D01*
X359696Y900914D01*
X360396Y902126D01*
X360547Y902039D01*
G37*
G36*
G01X364412Y903453D02*
X364227Y902853D01*
X363197D01*
X363012Y903453D01*
Y903627D01*
X364412D01*
Y903453D01*
G37*
G36*
G01X368112D02*
X367927Y902853D01*
X366897D01*
X366712Y903453D01*
Y903627D01*
X368112D01*
Y903453D01*
G37*
G36*
G01X371802D02*
X371617Y902853D01*
X370587D01*
X370402Y903453D01*
Y903628D01*
X371802D01*
Y903453D01*
G37*
G36*
G01X366712Y901845D02*
X366897Y902445D01*
X367927D01*
X368112Y901845D01*
Y901671D01*
X366712D01*
Y901845D01*
G37*
G36*
G01X363012D02*
X363197Y902445D01*
X364227D01*
X364412Y901845D01*
Y901671D01*
X363012D01*
Y901845D01*
G37*
G36*
G01X370402D02*
X370587Y902445D01*
X371617D01*
X371802Y901845D01*
Y901670D01*
X370402D01*
Y901845D01*
G37*
G36*
G01X366712D02*
X366897Y902445D01*
X367927D01*
X368112Y901845D01*
Y901671D01*
X366712D01*
Y901845D01*
G37*
G36*
G01X363012D02*
X363197Y902445D01*
X364227D01*
X364412Y901845D01*
Y901671D01*
X363012D01*
Y901845D01*
G37*
G36*
G01X370402D02*
X370587Y902445D01*
X371617D01*
X371802Y901845D01*
Y901670D01*
X370402D01*
Y901845D01*
G37*
G36*
G01X359415Y903269D02*
X358988Y903729D01*
X359503Y904621D01*
X360115Y904481D01*
X360266Y904394D01*
X359566Y903182D01*
X359415Y903269D01*
G37*
G36*
G01X361095Y905049D02*
X361280Y905649D01*
X362310D01*
X362495Y905049D01*
Y904875D01*
X361095D01*
Y905049D01*
G37*
G36*
G01X364795D02*
X364980Y905649D01*
X366010D01*
X366195Y905049D01*
Y904875D01*
X364795D01*
Y905049D01*
G37*
G36*
G01X355612Y901845D02*
X355797Y902445D01*
X356827D01*
X357012Y901845D01*
Y901671D01*
X355612D01*
Y901845D01*
G37*
G36*
G01X368495Y905049D02*
X368680Y905649D01*
X369710D01*
X369895Y905049D01*
Y904875D01*
X368495D01*
Y905049D01*
G37*
G36*
G01X359415Y903269D02*
X358988Y903729D01*
X359503Y904621D01*
X360115Y904481D01*
X360266Y904394D01*
X359566Y903182D01*
X359415Y903269D01*
G37*
G36*
G01X361095Y905049D02*
X361280Y905649D01*
X362310D01*
X362495Y905049D01*
Y904875D01*
X361095D01*
Y905049D01*
G37*
G36*
G01X364795D02*
X364980Y905649D01*
X366010D01*
X366195Y905049D01*
Y904875D01*
X364795D01*
Y905049D01*
G37*
G36*
G01X355612Y901845D02*
X355797Y902445D01*
X356827D01*
X357012Y901845D01*
Y901671D01*
X355612D01*
Y901845D01*
G37*
G36*
G01X368495Y905049D02*
X368680Y905649D01*
X369710D01*
X369895Y905049D01*
Y904875D01*
X368495D01*
Y905049D01*
G37*
G36*
G01X357428Y911457D02*
X357613Y912057D01*
X358643D01*
X358828Y911457D01*
Y911283D01*
X357428D01*
Y911457D01*
G37*
G36*
G01X361095Y911459D02*
X361280Y912059D01*
X362310D01*
X362495Y911459D01*
Y911284D01*
X361095D01*
Y911459D01*
G37*
G36*
G01X364795D02*
X364980Y912059D01*
X366010D01*
X366195Y911459D01*
Y911284D01*
X364795D01*
Y911459D01*
G37*
G36*
G01X355718Y909683D02*
X355291Y910143D01*
X355806Y911035D01*
X356418Y910895D01*
X356569Y910808D01*
X355869Y909596D01*
X355718Y909683D01*
G37*
G36*
G01X368505Y911459D02*
X368690Y912059D01*
X369720D01*
X369905Y911459D01*
Y911284D01*
X368505D01*
Y911459D01*
G37*
G36*
G01X357428Y911457D02*
X357613Y912057D01*
X358643D01*
X358828Y911457D01*
Y911283D01*
X357428D01*
Y911457D01*
G37*
G36*
G01X361095Y911459D02*
X361280Y912059D01*
X362310D01*
X362495Y911459D01*
Y911284D01*
X361095D01*
Y911459D01*
G37*
G36*
G01X364795D02*
X364980Y912059D01*
X366010D01*
X366195Y911459D01*
Y911284D01*
X364795D01*
Y911459D01*
G37*
G36*
G01X355718Y909683D02*
X355291Y910143D01*
X355806Y911035D01*
X356418Y910895D01*
X356569Y910808D01*
X355869Y909596D01*
X355718Y909683D01*
G37*
G36*
G01X368505Y911459D02*
X368690Y912059D01*
X369720D01*
X369905Y911459D01*
Y911284D01*
X368505D01*
Y911459D01*
G37*
G36*
G01X357560Y906463D02*
X357133Y906923D01*
X357648Y907815D01*
X358260Y907675D01*
X358411Y907588D01*
X357711Y906376D01*
X357560Y906463D01*
G37*
G36*
G01X359302Y908253D02*
X359487Y908853D01*
X360517D01*
X360702Y908253D01*
Y908079D01*
X359302D01*
Y908253D01*
G37*
G36*
G01X363012D02*
X363197Y908853D01*
X364227D01*
X364412Y908253D01*
Y908079D01*
X363012D01*
Y908253D01*
G37*
G36*
G01X366712D02*
X366897Y908853D01*
X367927D01*
X368112Y908253D01*
Y908079D01*
X366712D01*
Y908253D01*
G37*
G36*
G01X370412D02*
X370597Y908853D01*
X371627D01*
X371812Y908253D01*
Y908079D01*
X370412D01*
Y908253D01*
G37*
G36*
G01X357560Y906463D02*
X357133Y906923D01*
X357648Y907815D01*
X358260Y907675D01*
X358411Y907588D01*
X357711Y906376D01*
X357560Y906463D01*
G37*
G36*
G01X359302Y908253D02*
X359487Y908853D01*
X360517D01*
X360702Y908253D01*
Y908079D01*
X359302D01*
Y908253D01*
G37*
G36*
G01X363012D02*
X363197Y908853D01*
X364227D01*
X364412Y908253D01*
Y908079D01*
X363012D01*
Y908253D01*
G37*
G36*
G01X366712D02*
X366897Y908853D01*
X367927D01*
X368112Y908253D01*
Y908079D01*
X366712D01*
Y908253D01*
G37*
G36*
G01X370412D02*
X370597Y908853D01*
X371627D01*
X371812Y908253D01*
Y908079D01*
X370412D01*
Y908253D01*
G37*
G36*
G01X356847Y908447D02*
X357274Y907987D01*
X356759Y907095D01*
X356147Y907235D01*
X355996Y907322D01*
X356696Y908534D01*
X356847Y908447D01*
G37*
G36*
G01X368112Y909861D02*
X367927Y909261D01*
X366897D01*
X366712Y909861D01*
Y910035D01*
X368112D01*
Y909861D01*
G37*
G36*
G01X360702D02*
X360517Y909261D01*
X359487D01*
X359302Y909861D01*
Y910035D01*
X360702D01*
Y909861D01*
G37*
G36*
G01X364412D02*
X364227Y909261D01*
X363197D01*
X363012Y909861D01*
Y910035D01*
X364412D01*
Y909861D01*
G37*
G36*
G01X371779D02*
X371594Y909261D01*
X370564D01*
X370379Y909861D01*
Y910036D01*
X371779D01*
Y909861D01*
G37*
G36*
G01X356847Y908447D02*
X357274Y907987D01*
X356759Y907095D01*
X356147Y907235D01*
X355996Y907322D01*
X356696Y908534D01*
X356847Y908447D01*
G37*
G36*
G01X368112Y909861D02*
X367927Y909261D01*
X366897D01*
X366712Y909861D01*
Y910035D01*
X368112D01*
Y909861D01*
G37*
G36*
G01X360702D02*
X360517Y909261D01*
X359487D01*
X359302Y909861D01*
Y910035D01*
X360702D01*
Y909861D01*
G37*
G36*
G01X364412D02*
X364227Y909261D01*
X363197D01*
X363012Y909861D01*
Y910035D01*
X364412D01*
Y909861D01*
G37*
G36*
G01X371779D02*
X371594Y909261D01*
X370564D01*
X370379Y909861D01*
Y910036D01*
X371779D01*
Y909861D01*
G37*
G36*
G01X358697Y905243D02*
X359124Y904783D01*
X358609Y903891D01*
X357997Y904031D01*
X357846Y904118D01*
X358546Y905330D01*
X358697Y905243D01*
G37*
G36*
G01X362495Y906657D02*
X362310Y906057D01*
X361280D01*
X361095Y906657D01*
Y906831D01*
X362495D01*
Y906657D01*
G37*
G36*
G01X366195D02*
X366010Y906057D01*
X364980D01*
X364795Y906657D01*
Y906831D01*
X366195D01*
Y906657D01*
G37*
G36*
G01X356979Y903453D02*
X356794Y902853D01*
X355764D01*
X355579Y903453D01*
Y903628D01*
X356979D01*
Y903453D01*
G37*
G36*
G01X369895Y906657D02*
X369710Y906057D01*
X368680D01*
X368495Y906657D01*
Y906831D01*
X369895D01*
Y906657D01*
G37*
G36*
G01X358697Y905243D02*
X359124Y904783D01*
X358609Y903891D01*
X357997Y904031D01*
X357846Y904118D01*
X358546Y905330D01*
X358697Y905243D01*
G37*
G36*
G01X362495Y906657D02*
X362310Y906057D01*
X361280D01*
X361095Y906657D01*
Y906831D01*
X362495D01*
Y906657D01*
G37*
G36*
G01X366195D02*
X366010Y906057D01*
X364980D01*
X364795Y906657D01*
Y906831D01*
X366195D01*
Y906657D01*
G37*
G36*
G01X356979Y903453D02*
X356794Y902853D01*
X355764D01*
X355579Y903453D01*
Y903628D01*
X356979D01*
Y903453D01*
G37*
G36*
G01X369895Y906657D02*
X369710Y906057D01*
X368680D01*
X368495Y906657D01*
Y906831D01*
X369895D01*
Y906657D01*
G37*
G36*
G01X360655Y916271D02*
X360470Y915671D01*
X359440D01*
X359255Y916271D01*
Y916445D01*
X360655D01*
Y916271D01*
G37*
G36*
G01X364402Y916269D02*
X364217Y915669D01*
X363187D01*
X363002Y916269D01*
Y916444D01*
X364402D01*
Y916269D01*
G37*
G36*
G01X357012D02*
X356827Y915669D01*
X355797D01*
X355612Y916269D01*
Y916444D01*
X357012D01*
Y916269D01*
G37*
G36*
G01X368112D02*
X367927Y915669D01*
X366897D01*
X366712Y916269D01*
Y916444D01*
X368112D01*
Y916269D01*
G37*
G36*
G01X360655Y916271D02*
X360470Y915671D01*
X359440D01*
X359255Y916271D01*
Y916445D01*
X360655D01*
Y916271D01*
G37*
G36*
G01X364402Y916269D02*
X364217Y915669D01*
X363187D01*
X363002Y916269D01*
Y916444D01*
X364402D01*
Y916269D01*
G37*
G36*
G01X357012D02*
X356827Y915669D01*
X355797D01*
X355612Y916269D01*
Y916444D01*
X357012D01*
Y916269D01*
G37*
G36*
G01X368112D02*
X367927Y915669D01*
X366897D01*
X366712Y916269D01*
Y916444D01*
X368112D01*
Y916269D01*
G37*
G36*
G01X359302Y914661D02*
X359487Y915261D01*
X360517D01*
X360702Y914661D01*
Y914487D01*
X359302D01*
Y914661D01*
G37*
G36*
G01X363002Y914663D02*
X363187Y915263D01*
X364217D01*
X364402Y914663D01*
Y914488D01*
X363002D01*
Y914663D01*
G37*
G36*
G01X355612D02*
X355797Y915263D01*
X356827D01*
X357012Y914663D01*
Y914488D01*
X355612D01*
Y914663D01*
G37*
G36*
G01X366712D02*
X366897Y915263D01*
X367927D01*
X368112Y914663D01*
Y914488D01*
X366712D01*
Y914663D01*
G37*
G36*
G01X370379Y914661D02*
X370564Y915261D01*
X371594D01*
X371779Y914661D01*
Y914487D01*
X370379D01*
Y914661D01*
G37*
G36*
G01X359302D02*
X359487Y915261D01*
X360517D01*
X360702Y914661D01*
Y914487D01*
X359302D01*
Y914661D01*
G37*
G36*
G01X363002Y914663D02*
X363187Y915263D01*
X364217D01*
X364402Y914663D01*
Y914488D01*
X363002D01*
Y914663D01*
G37*
G36*
G01X355612D02*
X355797Y915263D01*
X356827D01*
X357012Y914663D01*
Y914488D01*
X355612D01*
Y914663D01*
G37*
G36*
G01X366712D02*
X366897Y915263D01*
X367927D01*
X368112Y914663D01*
Y914488D01*
X366712D01*
Y914663D01*
G37*
G36*
G01X370379Y914661D02*
X370564Y915261D01*
X371594D01*
X371779Y914661D01*
Y914487D01*
X370379D01*
Y914661D01*
G37*
G36*
G01X358795Y913065D02*
X358610Y912465D01*
X357580D01*
X357395Y913065D01*
Y913240D01*
X358795D01*
Y913065D01*
G37*
G36*
G01X362528Y913067D02*
X362343Y912467D01*
X361313D01*
X361128Y913067D01*
Y913241D01*
X362528D01*
Y913067D01*
G37*
G36*
G01X366195Y913065D02*
X366010Y912465D01*
X364980D01*
X364795Y913065D01*
Y913240D01*
X366195D01*
Y913065D01*
G37*
G36*
G01X369905D02*
X369720Y912465D01*
X368690D01*
X368505Y913065D01*
Y913240D01*
X369905D01*
Y913065D01*
G37*
G36*
G01X358795D02*
X358610Y912465D01*
X357580D01*
X357395Y913065D01*
Y913240D01*
X358795D01*
Y913065D01*
G37*
G36*
G01X362528Y913067D02*
X362343Y912467D01*
X361313D01*
X361128Y913067D01*
Y913241D01*
X362528D01*
Y913067D01*
G37*
G36*
G01X366195Y913065D02*
X366010Y912465D01*
X364980D01*
X364795Y913065D01*
Y913240D01*
X366195D01*
Y913065D01*
G37*
G36*
G01X369905D02*
X369720Y912465D01*
X368690D01*
X368505Y913065D01*
Y913240D01*
X369905D01*
Y913065D01*
G37*
G36*
G01X357428Y930683D02*
X357613Y931283D01*
X358643D01*
X358828Y930683D01*
Y930509D01*
X357428D01*
Y930683D01*
G37*
G36*
G01X361095Y930685D02*
X361280Y931285D01*
X362310D01*
X362495Y930685D01*
Y930510D01*
X361095D01*
Y930685D01*
G37*
G36*
G01X364795D02*
X364980Y931285D01*
X366010D01*
X366195Y930685D01*
Y930510D01*
X364795D01*
Y930685D01*
G37*
G36*
G01X368505D02*
X368690Y931285D01*
X369720D01*
X369905Y930685D01*
Y930510D01*
X368505D01*
Y930685D01*
G37*
G36*
G01X357428Y930683D02*
X357613Y931283D01*
X358643D01*
X358828Y930683D01*
Y930509D01*
X357428D01*
Y930683D01*
G37*
G36*
G01X361095Y930685D02*
X361280Y931285D01*
X362310D01*
X362495Y930685D01*
Y930510D01*
X361095D01*
Y930685D01*
G37*
G36*
G01X364795D02*
X364980Y931285D01*
X366010D01*
X366195Y930685D01*
Y930510D01*
X364795D01*
Y930685D01*
G37*
G36*
G01X368505D02*
X368690Y931285D01*
X369720D01*
X369905Y930685D01*
Y930510D01*
X368505D01*
Y930685D01*
G37*
G36*
G01X359302Y927479D02*
X359487Y928079D01*
X360517D01*
X360702Y927479D01*
Y927305D01*
X359302D01*
Y927479D01*
G37*
G36*
G01X363012D02*
X363197Y928079D01*
X364227D01*
X364412Y927479D01*
Y927305D01*
X363012D01*
Y927479D01*
G37*
G36*
G01X355555D02*
X355740Y928079D01*
X356770D01*
X356955Y927479D01*
Y927304D01*
X355555D01*
Y927479D01*
G37*
G36*
G01X366712D02*
X366897Y928079D01*
X367927D01*
X368112Y927479D01*
Y927305D01*
X366712D01*
Y927479D01*
G37*
G36*
G01X370412D02*
X370597Y928079D01*
X371627D01*
X371812Y927479D01*
Y927305D01*
X370412D01*
Y927479D01*
G37*
G36*
G01X359302D02*
X359487Y928079D01*
X360517D01*
X360702Y927479D01*
Y927305D01*
X359302D01*
Y927479D01*
G37*
G36*
G01X363012D02*
X363197Y928079D01*
X364227D01*
X364412Y927479D01*
Y927305D01*
X363012D01*
Y927479D01*
G37*
G36*
G01X355555D02*
X355740Y928079D01*
X356770D01*
X356955Y927479D01*
Y927304D01*
X355555D01*
Y927479D01*
G37*
G36*
G01X366712D02*
X366897Y928079D01*
X367927D01*
X368112Y927479D01*
Y927305D01*
X366712D01*
Y927479D01*
G37*
G36*
G01X370412D02*
X370597Y928079D01*
X371627D01*
X371812Y927479D01*
Y927305D01*
X370412D01*
Y927479D01*
G37*
G36*
G01X360702Y929087D02*
X360517Y928487D01*
X359487D01*
X359302Y929087D01*
Y929261D01*
X360702D01*
Y929087D01*
G37*
G36*
G01X364412D02*
X364227Y928487D01*
X363197D01*
X363012Y929087D01*
Y929261D01*
X364412D01*
Y929087D01*
G37*
G36*
G01X357002D02*
X356817Y928487D01*
X355787D01*
X355602Y929087D01*
Y929262D01*
X357002D01*
Y929087D01*
G37*
G36*
G01X368112D02*
X367927Y928487D01*
X366897D01*
X366712Y929087D01*
Y929261D01*
X368112D01*
Y929087D01*
G37*
G36*
G01X371779D02*
X371594Y928487D01*
X370564D01*
X370379Y929087D01*
Y929262D01*
X371779D01*
Y929087D01*
G37*
G36*
G01X360702D02*
X360517Y928487D01*
X359487D01*
X359302Y929087D01*
Y929261D01*
X360702D01*
Y929087D01*
G37*
G36*
G01X364412D02*
X364227Y928487D01*
X363197D01*
X363012Y929087D01*
Y929261D01*
X364412D01*
Y929087D01*
G37*
G36*
G01X357002D02*
X356817Y928487D01*
X355787D01*
X355602Y929087D01*
Y929262D01*
X357002D01*
Y929087D01*
G37*
G36*
G01X368112D02*
X367927Y928487D01*
X366897D01*
X366712Y929087D01*
Y929261D01*
X368112D01*
Y929087D01*
G37*
G36*
G01X371779D02*
X371594Y928487D01*
X370564D01*
X370379Y929087D01*
Y929262D01*
X371779D01*
Y929087D01*
G37*
G36*
G01X358852Y925883D02*
X358667Y925283D01*
X357637D01*
X357452Y925883D01*
Y926058D01*
X358852D01*
Y925883D01*
G37*
G36*
G01X362495D02*
X362310Y925283D01*
X361280D01*
X361095Y925883D01*
Y926057D01*
X362495D01*
Y925883D01*
G37*
G36*
G01X366195D02*
X366010Y925283D01*
X364980D01*
X364795Y925883D01*
Y926057D01*
X366195D01*
Y925883D01*
G37*
G36*
G01X369895D02*
X369710Y925283D01*
X368680D01*
X368495Y925883D01*
Y926057D01*
X369895D01*
Y925883D01*
G37*
G36*
G01X358852D02*
X358667Y925283D01*
X357637D01*
X357452Y925883D01*
Y926058D01*
X358852D01*
Y925883D01*
G37*
G36*
G01X362495D02*
X362310Y925283D01*
X361280D01*
X361095Y925883D01*
Y926057D01*
X362495D01*
Y925883D01*
G37*
G36*
G01X366195D02*
X366010Y925283D01*
X364980D01*
X364795Y925883D01*
Y926057D01*
X366195D01*
Y925883D01*
G37*
G36*
G01X369895D02*
X369710Y925283D01*
X368680D01*
X368495Y925883D01*
Y926057D01*
X369895D01*
Y925883D01*
G37*
G36*
G01X358795Y932291D02*
X358610Y931691D01*
X357580D01*
X357395Y932291D01*
Y932465D01*
X358795D01*
Y932291D01*
G37*
G36*
G01X366195D02*
X366010Y931691D01*
X364980D01*
X364795Y932291D01*
Y932465D01*
X366195D01*
Y932291D01*
G37*
G36*
G01X362528D02*
X362343Y931691D01*
X361313D01*
X361128Y932291D01*
Y932466D01*
X362528D01*
Y932291D01*
G37*
G36*
G01X369905D02*
X369720Y931691D01*
X368690D01*
X368505Y932291D01*
Y932465D01*
X369905D01*
Y932291D01*
G37*
G36*
G01X358795D02*
X358610Y931691D01*
X357580D01*
X357395Y932291D01*
Y932465D01*
X358795D01*
Y932291D01*
G37*
G36*
G01X366195D02*
X366010Y931691D01*
X364980D01*
X364795Y932291D01*
Y932465D01*
X366195D01*
Y932291D01*
G37*
G36*
G01X362528D02*
X362343Y931691D01*
X361313D01*
X361128Y932291D01*
Y932466D01*
X362528D01*
Y932291D01*
G37*
G36*
G01X369905D02*
X369720Y931691D01*
X368690D01*
X368505Y932291D01*
Y932465D01*
X369905D01*
Y932291D01*
G37*
G36*
G01X357405Y924275D02*
X357590Y924875D01*
X358620D01*
X358805Y924275D01*
Y924100D01*
X357405D01*
Y924275D01*
G37*
G36*
G01X361095D02*
X361280Y924875D01*
X362310D01*
X362495Y924275D01*
Y924101D01*
X361095D01*
Y924275D01*
G37*
G36*
G01X364795D02*
X364980Y924875D01*
X366010D01*
X366195Y924275D01*
Y924101D01*
X364795D01*
Y924275D01*
G37*
G36*
G01X368495D02*
X368680Y924875D01*
X369710D01*
X369895Y924275D01*
Y924101D01*
X368495D01*
Y924275D01*
G37*
G36*
G01X357405D02*
X357590Y924875D01*
X358620D01*
X358805Y924275D01*
Y924100D01*
X357405D01*
Y924275D01*
G37*
G36*
G01X361095D02*
X361280Y924875D01*
X362310D01*
X362495Y924275D01*
Y924101D01*
X361095D01*
Y924275D01*
G37*
G36*
G01X364795D02*
X364980Y924875D01*
X366010D01*
X366195Y924275D01*
Y924101D01*
X364795D01*
Y924275D01*
G37*
G36*
G01X368495D02*
X368680Y924875D01*
X369710D01*
X369895Y924275D01*
Y924101D01*
X368495D01*
Y924275D01*
G37*
G36*
G01X359279Y921071D02*
X359464Y921671D01*
X360494D01*
X360679Y921071D01*
Y920896D01*
X359279D01*
Y921071D01*
G37*
G36*
G01X363012D02*
X363197Y921671D01*
X364227D01*
X364412Y921071D01*
Y920897D01*
X363012D01*
Y921071D01*
G37*
G36*
G01X355612D02*
X355797Y921671D01*
X356827D01*
X357012Y921071D01*
Y920897D01*
X355612D01*
Y921071D01*
G37*
G36*
G01X366712D02*
X366897Y921671D01*
X367927D01*
X368112Y921071D01*
Y920897D01*
X366712D01*
Y921071D01*
G37*
G36*
G01X370402D02*
X370587Y921671D01*
X371617D01*
X371802Y921071D01*
Y920896D01*
X370402D01*
Y921071D01*
G37*
G36*
G01X359279D02*
X359464Y921671D01*
X360494D01*
X360679Y921071D01*
Y920896D01*
X359279D01*
Y921071D01*
G37*
G36*
G01X363012D02*
X363197Y921671D01*
X364227D01*
X364412Y921071D01*
Y920897D01*
X363012D01*
Y921071D01*
G37*
G36*
G01X355612D02*
X355797Y921671D01*
X356827D01*
X357012Y921071D01*
Y920897D01*
X355612D01*
Y921071D01*
G37*
G36*
G01X366712D02*
X366897Y921671D01*
X367927D01*
X368112Y921071D01*
Y920897D01*
X366712D01*
Y921071D01*
G37*
G36*
G01X370402D02*
X370587Y921671D01*
X371617D01*
X371802Y921071D01*
Y920896D01*
X370402D01*
Y921071D01*
G37*
G36*
G01X360712Y922679D02*
X360527Y922079D01*
X359497D01*
X359312Y922679D01*
Y922853D01*
X360712D01*
Y922679D01*
G37*
G36*
G01X364412D02*
X364227Y922079D01*
X363197D01*
X363012Y922679D01*
Y922853D01*
X364412D01*
Y922679D01*
G37*
G36*
G01X356979D02*
X356794Y922079D01*
X355764D01*
X355579Y922679D01*
Y922854D01*
X356979D01*
Y922679D01*
G37*
G36*
G01X368112D02*
X367927Y922079D01*
X366897D01*
X366712Y922679D01*
Y922853D01*
X368112D01*
Y922679D01*
G37*
G36*
G01X371802D02*
X371617Y922079D01*
X370587D01*
X370402Y922679D01*
Y922854D01*
X371802D01*
Y922679D01*
G37*
G36*
G01X360712D02*
X360527Y922079D01*
X359497D01*
X359312Y922679D01*
Y922853D01*
X360712D01*
Y922679D01*
G37*
G36*
G01X364412D02*
X364227Y922079D01*
X363197D01*
X363012Y922679D01*
Y922853D01*
X364412D01*
Y922679D01*
G37*
G36*
G01X356979D02*
X356794Y922079D01*
X355764D01*
X355579Y922679D01*
Y922854D01*
X356979D01*
Y922679D01*
G37*
G36*
G01X368112D02*
X367927Y922079D01*
X366897D01*
X366712Y922679D01*
Y922853D01*
X368112D01*
Y922679D01*
G37*
G36*
G01X371802D02*
X371617Y922079D01*
X370587D01*
X370402Y922679D01*
Y922854D01*
X371802D01*
Y922679D01*
G37*
G36*
G01X358805Y919473D02*
X358620Y918873D01*
X357590D01*
X357405Y919473D01*
Y919648D01*
X358805D01*
Y919473D01*
G37*
G36*
G01X362505Y919475D02*
X362320Y918875D01*
X361290D01*
X361105Y919475D01*
Y919649D01*
X362505D01*
Y919475D01*
G37*
G36*
G01X366195Y919473D02*
X366010Y918873D01*
X364980D01*
X364795Y919473D01*
Y919648D01*
X366195D01*
Y919473D01*
G37*
G36*
G01X369895D02*
X369710Y918873D01*
X368680D01*
X368495Y919473D01*
Y919648D01*
X369895D01*
Y919473D01*
G37*
G36*
G01X358805D02*
X358620Y918873D01*
X357590D01*
X357405Y919473D01*
Y919648D01*
X358805D01*
Y919473D01*
G37*
G36*
G01X362505Y919475D02*
X362320Y918875D01*
X361290D01*
X361105Y919475D01*
Y919649D01*
X362505D01*
Y919475D01*
G37*
G36*
G01X366195Y919473D02*
X366010Y918873D01*
X364980D01*
X364795Y919473D01*
Y919648D01*
X366195D01*
Y919473D01*
G37*
G36*
G01X369895D02*
X369710Y918873D01*
X368680D01*
X368495Y919473D01*
Y919648D01*
X369895D01*
Y919473D01*
G37*
G36*
G01X364795Y917867D02*
X364980Y918467D01*
X366010D01*
X366195Y917867D01*
Y917692D01*
X364795D01*
Y917867D01*
G37*
G36*
G01X357405D02*
X357590Y918467D01*
X358620D01*
X358805Y917867D01*
Y917692D01*
X357405D01*
Y917867D01*
G37*
G36*
G01X361152Y917865D02*
X361337Y918465D01*
X362367D01*
X362552Y917865D01*
Y917691D01*
X361152D01*
Y917865D01*
G37*
G36*
G01X368495Y917867D02*
X368680Y918467D01*
X369710D01*
X369895Y917867D01*
Y917692D01*
X368495D01*
Y917867D01*
G37*
G36*
G01X364795D02*
X364980Y918467D01*
X366010D01*
X366195Y917867D01*
Y917692D01*
X364795D01*
Y917867D01*
G37*
G36*
G01X357405D02*
X357590Y918467D01*
X358620D01*
X358805Y917867D01*
Y917692D01*
X357405D01*
Y917867D01*
G37*
G36*
G01X361152Y917865D02*
X361337Y918465D01*
X362367D01*
X362552Y917865D01*
Y917691D01*
X361152D01*
Y917865D01*
G37*
G36*
G01X368495Y917867D02*
X368680Y918467D01*
X369710D01*
X369895Y917867D01*
Y917692D01*
X368495D01*
Y917867D01*
G37*
G36*
G01X360712Y941903D02*
X360527Y941303D01*
X359497D01*
X359312Y941903D01*
Y942078D01*
X360712D01*
Y941903D01*
G37*
G36*
G01X364412D02*
X364227Y941303D01*
X363197D01*
X363012Y941903D01*
Y942078D01*
X364412D01*
Y941903D01*
G37*
G36*
G01X356979Y941905D02*
X356794Y941305D01*
X355764D01*
X355579Y941905D01*
Y942079D01*
X356979D01*
Y941905D01*
G37*
G36*
G01X368112Y941903D02*
X367927Y941303D01*
X366897D01*
X366712Y941903D01*
Y942078D01*
X368112D01*
Y941903D01*
G37*
G36*
G01X371802Y941905D02*
X371617Y941305D01*
X370587D01*
X370402Y941905D01*
Y942079D01*
X371802D01*
Y941905D01*
G37*
G36*
G01X360712Y941903D02*
X360527Y941303D01*
X359497D01*
X359312Y941903D01*
Y942078D01*
X360712D01*
Y941903D01*
G37*
G36*
G01X364412D02*
X364227Y941303D01*
X363197D01*
X363012Y941903D01*
Y942078D01*
X364412D01*
Y941903D01*
G37*
G36*
G01X356979Y941905D02*
X356794Y941305D01*
X355764D01*
X355579Y941905D01*
Y942079D01*
X356979D01*
Y941905D01*
G37*
G36*
G01X368112Y941903D02*
X367927Y941303D01*
X366897D01*
X366712Y941903D01*
Y942078D01*
X368112D01*
Y941903D01*
G37*
G36*
G01X371802Y941905D02*
X371617Y941305D01*
X370587D01*
X370402Y941905D01*
Y942079D01*
X371802D01*
Y941905D01*
G37*
G36*
G01X358805Y938699D02*
X358620Y938099D01*
X357590D01*
X357405Y938699D01*
Y938874D01*
X358805D01*
Y938699D01*
G37*
G36*
G01X366195D02*
X366010Y938099D01*
X364980D01*
X364795Y938699D01*
Y938874D01*
X366195D01*
Y938699D01*
G37*
G36*
G01X362505Y938701D02*
X362320Y938101D01*
X361290D01*
X361105Y938701D01*
Y938875D01*
X362505D01*
Y938701D01*
G37*
G36*
G01X369895Y938699D02*
X369710Y938099D01*
X368680D01*
X368495Y938699D01*
Y938874D01*
X369895D01*
Y938699D01*
G37*
G36*
G01X358805D02*
X358620Y938099D01*
X357590D01*
X357405Y938699D01*
Y938874D01*
X358805D01*
Y938699D01*
G37*
G36*
G01X366195D02*
X366010Y938099D01*
X364980D01*
X364795Y938699D01*
Y938874D01*
X366195D01*
Y938699D01*
G37*
G36*
G01X362505Y938701D02*
X362320Y938101D01*
X361290D01*
X361105Y938701D01*
Y938875D01*
X362505D01*
Y938701D01*
G37*
G36*
G01X369895Y938699D02*
X369710Y938099D01*
X368680D01*
X368495Y938699D01*
Y938874D01*
X369895D01*
Y938699D01*
G37*
G36*
G01X359302Y946705D02*
X359487Y947305D01*
X360517D01*
X360702Y946705D01*
Y946531D01*
X359302D01*
Y946705D01*
G37*
G36*
G01X363012D02*
X363197Y947305D01*
X364227D01*
X364412Y946705D01*
Y946531D01*
X363012D01*
Y946705D01*
G37*
G36*
G01X355555D02*
X355740Y947305D01*
X356770D01*
X356955Y946705D01*
Y946530D01*
X355555D01*
Y946705D01*
G37*
G36*
G01X366712D02*
X366897Y947305D01*
X367927D01*
X368112Y946705D01*
Y946531D01*
X366712D01*
Y946705D01*
G37*
G36*
G01X370412D02*
X370597Y947305D01*
X371627D01*
X371812Y946705D01*
Y946531D01*
X370412D01*
Y946705D01*
G37*
G36*
G01X359302D02*
X359487Y947305D01*
X360517D01*
X360702Y946705D01*
Y946531D01*
X359302D01*
Y946705D01*
G37*
G36*
G01X363012D02*
X363197Y947305D01*
X364227D01*
X364412Y946705D01*
Y946531D01*
X363012D01*
Y946705D01*
G37*
G36*
G01X355555D02*
X355740Y947305D01*
X356770D01*
X356955Y946705D01*
Y946530D01*
X355555D01*
Y946705D01*
G37*
G36*
G01X366712D02*
X366897Y947305D01*
X367927D01*
X368112Y946705D01*
Y946531D01*
X366712D01*
Y946705D01*
G37*
G36*
G01X370412D02*
X370597Y947305D01*
X371627D01*
X371812Y946705D01*
Y946531D01*
X370412D01*
Y946705D01*
G37*
G36*
G01X357002Y948313D02*
X356817Y947713D01*
X355787D01*
X355602Y948313D01*
Y948488D01*
X357002D01*
Y948313D01*
G37*
G36*
G01X368112D02*
X367927Y947713D01*
X366897D01*
X366712Y948313D01*
Y948487D01*
X368112D01*
Y948313D01*
G37*
G36*
G01X360702D02*
X360517Y947713D01*
X359487D01*
X359302Y948313D01*
Y948487D01*
X360702D01*
Y948313D01*
G37*
G36*
G01X364412D02*
X364227Y947713D01*
X363197D01*
X363012Y948313D01*
Y948487D01*
X364412D01*
Y948313D01*
G37*
G36*
G01X371779D02*
X371594Y947713D01*
X370564D01*
X370379Y948313D01*
Y948488D01*
X371779D01*
Y948313D01*
G37*
G36*
G01X357002D02*
X356817Y947713D01*
X355787D01*
X355602Y948313D01*
Y948488D01*
X357002D01*
Y948313D01*
G37*
G36*
G01X368112D02*
X367927Y947713D01*
X366897D01*
X366712Y948313D01*
Y948487D01*
X368112D01*
Y948313D01*
G37*
G36*
G01X360702D02*
X360517Y947713D01*
X359487D01*
X359302Y948313D01*
Y948487D01*
X360702D01*
Y948313D01*
G37*
G36*
G01X364412D02*
X364227Y947713D01*
X363197D01*
X363012Y948313D01*
Y948487D01*
X364412D01*
Y948313D01*
G37*
G36*
G01X371779D02*
X371594Y947713D01*
X370564D01*
X370379Y948313D01*
Y948488D01*
X371779D01*
Y948313D01*
G37*
G36*
G01X358852Y945109D02*
X358667Y944509D01*
X357637D01*
X357452Y945109D01*
Y945283D01*
X358852D01*
Y945109D01*
G37*
G36*
G01X362495Y945107D02*
X362310Y944507D01*
X361280D01*
X361095Y945107D01*
Y945282D01*
X362495D01*
Y945107D01*
G37*
G36*
G01X366195D02*
X366010Y944507D01*
X364980D01*
X364795Y945107D01*
Y945282D01*
X366195D01*
Y945107D01*
G37*
G36*
G01X369895D02*
X369710Y944507D01*
X368680D01*
X368495Y945107D01*
Y945282D01*
X369895D01*
Y945107D01*
G37*
G36*
G01X358852Y945109D02*
X358667Y944509D01*
X357637D01*
X357452Y945109D01*
Y945283D01*
X358852D01*
Y945109D01*
G37*
G36*
G01X362495Y945107D02*
X362310Y944507D01*
X361280D01*
X361095Y945107D01*
Y945282D01*
X362495D01*
Y945107D01*
G37*
G36*
G01X366195D02*
X366010Y944507D01*
X364980D01*
X364795Y945107D01*
Y945282D01*
X366195D01*
Y945107D01*
G37*
G36*
G01X369895D02*
X369710Y944507D01*
X368680D01*
X368495Y945107D01*
Y945282D01*
X369895D01*
Y945107D01*
G37*
G36*
G01X357405Y943499D02*
X357590Y944099D01*
X358620D01*
X358805Y943499D01*
Y943325D01*
X357405D01*
Y943499D01*
G37*
G36*
G01X364795Y943501D02*
X364980Y944101D01*
X366010D01*
X366195Y943501D01*
Y943326D01*
X364795D01*
Y943501D01*
G37*
G36*
G01X361095D02*
X361280Y944101D01*
X362310D01*
X362495Y943501D01*
Y943326D01*
X361095D01*
Y943501D01*
G37*
G36*
G01X368495D02*
X368680Y944101D01*
X369710D01*
X369895Y943501D01*
Y943326D01*
X368495D01*
Y943501D01*
G37*
G36*
G01X357405Y943499D02*
X357590Y944099D01*
X358620D01*
X358805Y943499D01*
Y943325D01*
X357405D01*
Y943499D01*
G37*
G36*
G01X364795Y943501D02*
X364980Y944101D01*
X366010D01*
X366195Y943501D01*
Y943326D01*
X364795D01*
Y943501D01*
G37*
G36*
G01X361095D02*
X361280Y944101D01*
X362310D01*
X362495Y943501D01*
Y943326D01*
X361095D01*
Y943501D01*
G37*
G36*
G01X368495D02*
X368680Y944101D01*
X369710D01*
X369895Y943501D01*
Y943326D01*
X368495D01*
Y943501D01*
G37*
G36*
G01X359279Y940295D02*
X359464Y940895D01*
X360494D01*
X360679Y940295D01*
Y940121D01*
X359279D01*
Y940295D01*
G37*
G36*
G01X363012Y940297D02*
X363197Y940897D01*
X364227D01*
X364412Y940297D01*
Y940122D01*
X363012D01*
Y940297D01*
G37*
G36*
G01X355612D02*
X355797Y940897D01*
X356827D01*
X357012Y940297D01*
Y940122D01*
X355612D01*
Y940297D01*
G37*
G36*
G01X366712D02*
X366897Y940897D01*
X367927D01*
X368112Y940297D01*
Y940122D01*
X366712D01*
Y940297D01*
G37*
G36*
G01X370402Y940295D02*
X370587Y940895D01*
X371617D01*
X371802Y940295D01*
Y940121D01*
X370402D01*
Y940295D01*
G37*
G36*
G01X359279D02*
X359464Y940895D01*
X360494D01*
X360679Y940295D01*
Y940121D01*
X359279D01*
Y940295D01*
G37*
G36*
G01X363012Y940297D02*
X363197Y940897D01*
X364227D01*
X364412Y940297D01*
Y940122D01*
X363012D01*
Y940297D01*
G37*
G36*
G01X355612D02*
X355797Y940897D01*
X356827D01*
X357012Y940297D01*
Y940122D01*
X355612D01*
Y940297D01*
G37*
G36*
G01X366712D02*
X366897Y940897D01*
X367927D01*
X368112Y940297D01*
Y940122D01*
X366712D01*
Y940297D01*
G37*
G36*
G01X370402Y940295D02*
X370587Y940895D01*
X371617D01*
X371802Y940295D01*
Y940121D01*
X370402D01*
Y940295D01*
G37*
G36*
G01X360655Y935497D02*
X360470Y934897D01*
X359440D01*
X359255Y935497D01*
Y935671D01*
X360655D01*
Y935497D01*
G37*
G36*
G01X357012Y935495D02*
X356827Y934895D01*
X355797D01*
X355612Y935495D01*
Y935670D01*
X357012D01*
Y935495D01*
G37*
G36*
G01X368112D02*
X367927Y934895D01*
X366897D01*
X366712Y935495D01*
Y935669D01*
X368112D01*
Y935495D01*
G37*
G36*
G01X364354Y935497D02*
X364169Y934897D01*
X363139D01*
X362954Y935497D01*
Y935671D01*
X364354D01*
Y935497D01*
G37*
G36*
G01X360655D02*
X360470Y934897D01*
X359440D01*
X359255Y935497D01*
Y935671D01*
X360655D01*
Y935497D01*
G37*
G36*
G01X357012Y935495D02*
X356827Y934895D01*
X355797D01*
X355612Y935495D01*
Y935670D01*
X357012D01*
Y935495D01*
G37*
G36*
G01X368112D02*
X367927Y934895D01*
X366897D01*
X366712Y935495D01*
Y935669D01*
X368112D01*
Y935495D01*
G37*
G36*
G01X364354Y935497D02*
X364169Y934897D01*
X363139D01*
X362954Y935497D01*
Y935671D01*
X364354D01*
Y935497D01*
G37*
G36*
G01X359302Y933887D02*
X359487Y934487D01*
X360517D01*
X360702Y933887D01*
Y933713D01*
X359302D01*
Y933887D01*
G37*
G36*
G01X363002Y933889D02*
X363187Y934489D01*
X364217D01*
X364402Y933889D01*
Y933714D01*
X363002D01*
Y933889D01*
G37*
G36*
G01X355612D02*
X355797Y934489D01*
X356827D01*
X357012Y933889D01*
Y933714D01*
X355612D01*
Y933889D01*
G37*
G36*
G01X366712D02*
X366897Y934489D01*
X367927D01*
X368112Y933889D01*
Y933714D01*
X366712D01*
Y933889D01*
G37*
G36*
G01X370379Y933887D02*
X370564Y934487D01*
X371594D01*
X371779Y933887D01*
Y933713D01*
X370379D01*
Y933887D01*
G37*
G36*
G01X359302D02*
X359487Y934487D01*
X360517D01*
X360702Y933887D01*
Y933713D01*
X359302D01*
Y933887D01*
G37*
G36*
G01X363002Y933889D02*
X363187Y934489D01*
X364217D01*
X364402Y933889D01*
Y933714D01*
X363002D01*
Y933889D01*
G37*
G36*
G01X355612D02*
X355797Y934489D01*
X356827D01*
X357012Y933889D01*
Y933714D01*
X355612D01*
Y933889D01*
G37*
G36*
G01X366712D02*
X366897Y934489D01*
X367927D01*
X368112Y933889D01*
Y933714D01*
X366712D01*
Y933889D01*
G37*
G36*
G01X370379Y933887D02*
X370564Y934487D01*
X371594D01*
X371779Y933887D01*
Y933713D01*
X370379D01*
Y933887D01*
G37*
G36*
G01X357405Y937093D02*
X357590Y937693D01*
X358620D01*
X358805Y937093D01*
Y936918D01*
X357405D01*
Y937093D01*
G37*
G36*
G01X364795D02*
X364980Y937693D01*
X366010D01*
X366195Y937093D01*
Y936918D01*
X364795D01*
Y937093D01*
G37*
G36*
G01X361152Y937091D02*
X361337Y937691D01*
X362367D01*
X362552Y937091D01*
Y936917D01*
X361152D01*
Y937091D01*
G37*
G36*
G01X368497D02*
X368682Y937691D01*
X369712D01*
X369897Y937091D01*
Y936917D01*
X368497D01*
Y937091D01*
G37*
G36*
G01X357405Y937093D02*
X357590Y937693D01*
X358620D01*
X358805Y937093D01*
Y936918D01*
X357405D01*
Y937093D01*
G37*
G36*
G01X364795D02*
X364980Y937693D01*
X366010D01*
X366195Y937093D01*
Y936918D01*
X364795D01*
Y937093D01*
G37*
G36*
G01X361152Y937091D02*
X361337Y937691D01*
X362367D01*
X362552Y937091D01*
Y936917D01*
X361152D01*
Y937091D01*
G37*
G36*
G01X368497D02*
X368682Y937691D01*
X369712D01*
X369897Y937091D01*
Y936917D01*
X368497D01*
Y937091D01*
G37*
G36*
G01X357405Y962725D02*
X357590Y963325D01*
X358620D01*
X358805Y962725D01*
Y962551D01*
X357405D01*
Y962725D01*
G37*
G36*
G01X364805D02*
X364990Y963325D01*
X366020D01*
X366205Y962725D01*
Y962551D01*
X364805D01*
Y962725D01*
G37*
G36*
G01X361105Y962727D02*
X361290Y963327D01*
X362320D01*
X362505Y962727D01*
Y962552D01*
X361105D01*
Y962727D01*
G37*
G36*
G01X368495D02*
X368680Y963327D01*
X369710D01*
X369895Y962727D01*
Y962552D01*
X368495D01*
Y962727D01*
G37*
G36*
G01X357405Y962725D02*
X357590Y963325D01*
X358620D01*
X358805Y962725D01*
Y962551D01*
X357405D01*
Y962725D01*
G37*
G36*
G01X364805D02*
X364990Y963325D01*
X366020D01*
X366205Y962725D01*
Y962551D01*
X364805D01*
Y962725D01*
G37*
G36*
G01X361105Y962727D02*
X361290Y963327D01*
X362320D01*
X362505Y962727D01*
Y962552D01*
X361105D01*
Y962727D01*
G37*
G36*
G01X368495D02*
X368680Y963327D01*
X369710D01*
X369895Y962727D01*
Y962552D01*
X368495D01*
Y962727D01*
G37*
G36*
G01X359265Y959521D02*
X359450Y960121D01*
X360480D01*
X360665Y959521D01*
Y959347D01*
X359265D01*
Y959521D01*
G37*
G36*
G01X362965D02*
X363150Y960121D01*
X364180D01*
X364365Y959521D01*
Y959347D01*
X362965D01*
Y959521D01*
G37*
G36*
G01X355565D02*
X355750Y960121D01*
X356780D01*
X356965Y959521D01*
Y959347D01*
X355565D01*
Y959521D01*
G37*
G36*
G01X366665D02*
X366850Y960121D01*
X367880D01*
X368065Y959521D01*
Y959347D01*
X366665D01*
Y959521D01*
G37*
G36*
G01X370365D02*
X370550Y960121D01*
X371580D01*
X371765Y959521D01*
Y959347D01*
X370365D01*
Y959521D01*
G37*
G36*
G01X359265D02*
X359450Y960121D01*
X360480D01*
X360665Y959521D01*
Y959347D01*
X359265D01*
Y959521D01*
G37*
G36*
G01X362965D02*
X363150Y960121D01*
X364180D01*
X364365Y959521D01*
Y959347D01*
X362965D01*
Y959521D01*
G37*
G36*
G01X355565D02*
X355750Y960121D01*
X356780D01*
X356965Y959521D01*
Y959347D01*
X355565D01*
Y959521D01*
G37*
G36*
G01X366665D02*
X366850Y960121D01*
X367880D01*
X368065Y959521D01*
Y959347D01*
X366665D01*
Y959521D01*
G37*
G36*
G01X370365D02*
X370550Y960121D01*
X371580D01*
X371765Y959521D01*
Y959347D01*
X370365D01*
Y959521D01*
G37*
G36*
G01X360712Y961129D02*
X360527Y960529D01*
X359497D01*
X359312Y961129D01*
Y961304D01*
X360712D01*
Y961129D01*
G37*
G36*
G01X364379Y961131D02*
X364194Y960531D01*
X363164D01*
X362979Y961131D01*
Y961305D01*
X364379D01*
Y961131D01*
G37*
G36*
G01X356979D02*
X356794Y960531D01*
X355764D01*
X355579Y961131D01*
Y961305D01*
X356979D01*
Y961131D01*
G37*
G36*
G01X368112Y961129D02*
X367927Y960529D01*
X366897D01*
X366712Y961129D01*
Y961304D01*
X368112D01*
Y961129D01*
G37*
G36*
G01X371802Y961131D02*
X371617Y960531D01*
X370587D01*
X370402Y961131D01*
Y961305D01*
X371802D01*
Y961131D01*
G37*
G36*
G01X360712Y961129D02*
X360527Y960529D01*
X359497D01*
X359312Y961129D01*
Y961304D01*
X360712D01*
Y961129D01*
G37*
G36*
G01X364379Y961131D02*
X364194Y960531D01*
X363164D01*
X362979Y961131D01*
Y961305D01*
X364379D01*
Y961131D01*
G37*
G36*
G01X356979D02*
X356794Y960531D01*
X355764D01*
X355579Y961131D01*
Y961305D01*
X356979D01*
Y961131D01*
G37*
G36*
G01X368112Y961129D02*
X367927Y960529D01*
X366897D01*
X366712Y961129D01*
Y961304D01*
X368112D01*
Y961129D01*
G37*
G36*
G01X371802Y961131D02*
X371617Y960531D01*
X370587D01*
X370402Y961131D01*
Y961305D01*
X371802D01*
Y961131D01*
G37*
G36*
G01X358842Y957927D02*
X358657Y957327D01*
X357627D01*
X357442Y957927D01*
Y958101D01*
X358842D01*
Y957927D01*
G37*
G36*
G01X366242D02*
X366057Y957327D01*
X365027D01*
X364842Y957927D01*
Y958101D01*
X366242D01*
Y957927D01*
G37*
G36*
G01X362542D02*
X362357Y957327D01*
X361327D01*
X361142Y957927D01*
Y958101D01*
X362542D01*
Y957927D01*
G37*
G36*
G01X369942D02*
X369757Y957327D01*
X368727D01*
X368542Y957927D01*
Y958101D01*
X369942D01*
Y957927D01*
G37*
G36*
G01X358842D02*
X358657Y957327D01*
X357627D01*
X357442Y957927D01*
Y958101D01*
X358842D01*
Y957927D01*
G37*
G36*
G01X366242D02*
X366057Y957327D01*
X365027D01*
X364842Y957927D01*
Y958101D01*
X366242D01*
Y957927D01*
G37*
G36*
G01X362542D02*
X362357Y957327D01*
X361327D01*
X361142Y957927D01*
Y958101D01*
X362542D01*
Y957927D01*
G37*
G36*
G01X369942D02*
X369757Y957327D01*
X368727D01*
X368542Y957927D01*
Y958101D01*
X369942D01*
Y957927D01*
G37*
G36*
G01X361095Y949909D02*
X361280Y950509D01*
X362310D01*
X362495Y949909D01*
Y949735D01*
X361095D01*
Y949909D01*
G37*
G36*
G01X357428D02*
X357613Y950509D01*
X358643D01*
X358828Y949909D01*
Y949734D01*
X357428D01*
Y949909D01*
G37*
G36*
G01X364795D02*
X364980Y950509D01*
X366010D01*
X366195Y949909D01*
Y949735D01*
X364795D01*
Y949909D01*
G37*
G36*
G01X368505D02*
X368690Y950509D01*
X369720D01*
X369905Y949909D01*
Y949735D01*
X368505D01*
Y949909D01*
G37*
G36*
G01X361095D02*
X361280Y950509D01*
X362310D01*
X362495Y949909D01*
Y949735D01*
X361095D01*
Y949909D01*
G37*
G36*
G01X357428D02*
X357613Y950509D01*
X358643D01*
X358828Y949909D01*
Y949734D01*
X357428D01*
Y949909D01*
G37*
G36*
G01X364795D02*
X364980Y950509D01*
X366010D01*
X366195Y949909D01*
Y949735D01*
X364795D01*
Y949909D01*
G37*
G36*
G01X368505D02*
X368690Y950509D01*
X369720D01*
X369905Y949909D01*
Y949735D01*
X368505D01*
Y949909D01*
G37*
G36*
G01X360678Y954723D02*
X360493Y954123D01*
X359463D01*
X359278Y954723D01*
Y954897D01*
X360678D01*
Y954723D01*
G37*
G36*
G01X364412Y954721D02*
X364227Y954121D01*
X363197D01*
X363012Y954721D01*
Y954895D01*
X364412D01*
Y954721D01*
G37*
G36*
G01X356976Y954723D02*
X356791Y954123D01*
X355761D01*
X355576Y954723D01*
Y954897D01*
X356976D01*
Y954723D01*
G37*
G36*
G01X368112Y954721D02*
X367927Y954121D01*
X366897D01*
X366712Y954721D01*
Y954895D01*
X368112D01*
Y954721D01*
G37*
G36*
G01X360678Y954723D02*
X360493Y954123D01*
X359463D01*
X359278Y954723D01*
Y954897D01*
X360678D01*
Y954723D01*
G37*
G36*
G01X364412Y954721D02*
X364227Y954121D01*
X363197D01*
X363012Y954721D01*
Y954895D01*
X364412D01*
Y954721D01*
G37*
G36*
G01X356976Y954723D02*
X356791Y954123D01*
X355761D01*
X355576Y954723D01*
Y954897D01*
X356976D01*
Y954723D01*
G37*
G36*
G01X368112Y954721D02*
X367927Y954121D01*
X366897D01*
X366712Y954721D01*
Y954895D01*
X368112D01*
Y954721D01*
G37*
G36*
G01X355612Y953113D02*
X355797Y953713D01*
X356827D01*
X357012Y953113D01*
Y952939D01*
X355612D01*
Y953113D01*
G37*
G36*
G01X366712D02*
X366897Y953713D01*
X367927D01*
X368112Y953113D01*
Y952939D01*
X366712D01*
Y953113D01*
G37*
G36*
G01X359312D02*
X359497Y953713D01*
X360527D01*
X360712Y953113D01*
Y952939D01*
X359312D01*
Y953113D01*
G37*
G36*
G01X363012D02*
X363197Y953713D01*
X364227D01*
X364412Y953113D01*
Y952939D01*
X363012D01*
Y953113D01*
G37*
G36*
G01X370379D02*
X370564Y953713D01*
X371594D01*
X371779Y953113D01*
Y952938D01*
X370379D01*
Y953113D01*
G37*
G36*
G01X355612D02*
X355797Y953713D01*
X356827D01*
X357012Y953113D01*
Y952939D01*
X355612D01*
Y953113D01*
G37*
G36*
G01X366712D02*
X366897Y953713D01*
X367927D01*
X368112Y953113D01*
Y952939D01*
X366712D01*
Y953113D01*
G37*
G36*
G01X359312D02*
X359497Y953713D01*
X360527D01*
X360712Y953113D01*
Y952939D01*
X359312D01*
Y953113D01*
G37*
G36*
G01X363012D02*
X363197Y953713D01*
X364227D01*
X364412Y953113D01*
Y952939D01*
X363012D01*
Y953113D01*
G37*
G36*
G01X370379D02*
X370564Y953713D01*
X371594D01*
X371779Y953113D01*
Y952938D01*
X370379D01*
Y953113D01*
G37*
G36*
G01X357405Y956319D02*
X357590Y956919D01*
X358620D01*
X358805Y956319D01*
Y956144D01*
X357405D01*
Y956319D01*
G37*
G36*
G01X364795D02*
X364980Y956919D01*
X366010D01*
X366195Y956319D01*
Y956144D01*
X364795D01*
Y956319D01*
G37*
G36*
G01X361152Y956317D02*
X361337Y956917D01*
X362367D01*
X362552Y956317D01*
Y956143D01*
X361152D01*
Y956317D01*
G37*
G36*
G01X368497D02*
X368682Y956917D01*
X369712D01*
X369897Y956317D01*
Y956143D01*
X368497D01*
Y956317D01*
G37*
G36*
G01X357405Y956319D02*
X357590Y956919D01*
X358620D01*
X358805Y956319D01*
Y956144D01*
X357405D01*
Y956319D01*
G37*
G36*
G01X364795D02*
X364980Y956919D01*
X366010D01*
X366195Y956319D01*
Y956144D01*
X364795D01*
Y956319D01*
G37*
G36*
G01X361152Y956317D02*
X361337Y956917D01*
X362367D01*
X362552Y956317D01*
Y956143D01*
X361152D01*
Y956317D01*
G37*
G36*
G01X368497D02*
X368682Y956917D01*
X369712D01*
X369897Y956317D01*
Y956143D01*
X368497D01*
Y956317D01*
G37*
G36*
G01X358795Y951517D02*
X358610Y950917D01*
X357580D01*
X357395Y951517D01*
Y951691D01*
X358795D01*
Y951517D01*
G37*
G36*
G01X366195D02*
X366010Y950917D01*
X364980D01*
X364795Y951517D01*
Y951691D01*
X366195D01*
Y951517D01*
G37*
G36*
G01X362495D02*
X362310Y950917D01*
X361280D01*
X361095Y951517D01*
Y951691D01*
X362495D01*
Y951517D01*
G37*
G36*
G01X369905D02*
X369720Y950917D01*
X368690D01*
X368505Y951517D01*
Y951691D01*
X369905D01*
Y951517D01*
G37*
G36*
G01X358795D02*
X358610Y950917D01*
X357580D01*
X357395Y951517D01*
Y951691D01*
X358795D01*
Y951517D01*
G37*
G36*
G01X366195D02*
X366010Y950917D01*
X364980D01*
X364795Y951517D01*
Y951691D01*
X366195D01*
Y951517D01*
G37*
G36*
G01X362495D02*
X362310Y950917D01*
X361280D01*
X361095Y951517D01*
Y951691D01*
X362495D01*
Y951517D01*
G37*
G36*
G01X369905D02*
X369720Y950917D01*
X368690D01*
X368505Y951517D01*
Y951691D01*
X369905D01*
Y951517D01*
G37*
G36*
G01X358852Y964335D02*
X358667Y963735D01*
X357637D01*
X357452Y964335D01*
Y964509D01*
X358852D01*
Y964335D01*
G37*
G36*
G01X366252D02*
X366067Y963735D01*
X365037D01*
X364852Y964335D01*
Y964509D01*
X366252D01*
Y964335D01*
G37*
G36*
G01X362505Y964333D02*
X362320Y963733D01*
X361290D01*
X361105Y964333D01*
Y964508D01*
X362505D01*
Y964333D01*
G37*
G36*
G01X369895D02*
X369710Y963733D01*
X368680D01*
X368495Y964333D01*
Y964508D01*
X369895D01*
Y964333D01*
G37*
G36*
G01X358852Y964335D02*
X358667Y963735D01*
X357637D01*
X357452Y964335D01*
Y964509D01*
X358852D01*
Y964335D01*
G37*
G36*
G01X366252D02*
X366067Y963735D01*
X365037D01*
X364852Y964335D01*
Y964509D01*
X366252D01*
Y964335D01*
G37*
G36*
G01X362505Y964333D02*
X362320Y963733D01*
X361290D01*
X361105Y964333D01*
Y964508D01*
X362505D01*
Y964333D01*
G37*
G36*
G01X369895D02*
X369710Y963733D01*
X368680D01*
X368495Y964333D01*
Y964508D01*
X369895D01*
Y964333D01*
G37*
G36*
G01X358805Y977151D02*
X358620Y976551D01*
X357590D01*
X357405Y977151D01*
Y977325D01*
X358805D01*
Y977151D01*
G37*
G36*
G01X362505D02*
X362320Y976551D01*
X361290D01*
X361105Y977151D01*
Y977326D01*
X362505D01*
Y977151D01*
G37*
G36*
G01X366195D02*
X366010Y976551D01*
X364980D01*
X364795Y977151D01*
Y977325D01*
X366195D01*
Y977151D01*
G37*
G36*
G01X369895D02*
X369710Y976551D01*
X368680D01*
X368495Y977151D01*
Y977325D01*
X369895D01*
Y977151D01*
G37*
G36*
G01X358805D02*
X358620Y976551D01*
X357590D01*
X357405Y977151D01*
Y977325D01*
X358805D01*
Y977151D01*
G37*
G36*
G01X362505D02*
X362320Y976551D01*
X361290D01*
X361105Y977151D01*
Y977326D01*
X362505D01*
Y977151D01*
G37*
G36*
G01X366195D02*
X366010Y976551D01*
X364980D01*
X364795Y977151D01*
Y977325D01*
X366195D01*
Y977151D01*
G37*
G36*
G01X369895D02*
X369710Y976551D01*
X368680D01*
X368495Y977151D01*
Y977325D01*
X369895D01*
Y977151D01*
G37*
G36*
G01X357405Y975543D02*
X357590Y976143D01*
X358620D01*
X358805Y975543D01*
Y975369D01*
X357405D01*
Y975543D01*
G37*
G36*
G01X364795D02*
X364980Y976143D01*
X366010D01*
X366195Y975543D01*
Y975369D01*
X364795D01*
Y975543D01*
G37*
G36*
G01X361152D02*
X361337Y976143D01*
X362367D01*
X362552Y975543D01*
Y975368D01*
X361152D01*
Y975543D01*
G37*
G36*
G01X368495D02*
X368680Y976143D01*
X369710D01*
X369895Y975543D01*
Y975369D01*
X368495D01*
Y975543D01*
G37*
G36*
G01X357405D02*
X357590Y976143D01*
X358620D01*
X358805Y975543D01*
Y975369D01*
X357405D01*
Y975543D01*
G37*
G36*
G01X364795D02*
X364980Y976143D01*
X366010D01*
X366195Y975543D01*
Y975369D01*
X364795D01*
Y975543D01*
G37*
G36*
G01X361152D02*
X361337Y976143D01*
X362367D01*
X362552Y975543D01*
Y975368D01*
X361152D01*
Y975543D01*
G37*
G36*
G01X368495D02*
X368680Y976143D01*
X369710D01*
X369895Y975543D01*
Y975369D01*
X368495D01*
Y975543D01*
G37*
G36*
G01X359279Y978747D02*
X359464Y979347D01*
X360494D01*
X360679Y978747D01*
Y978573D01*
X359279D01*
Y978747D01*
G37*
G36*
G01X363012Y978749D02*
X363197Y979349D01*
X364227D01*
X364412Y978749D01*
Y978574D01*
X363012D01*
Y978749D01*
G37*
G36*
G01X355612D02*
X355797Y979349D01*
X356827D01*
X357012Y978749D01*
Y978574D01*
X355612D01*
Y978749D01*
G37*
G36*
G01X366712D02*
X366897Y979349D01*
X367927D01*
X368112Y978749D01*
Y978574D01*
X366712D01*
Y978749D01*
G37*
G36*
G01X370402Y978747D02*
X370587Y979347D01*
X371617D01*
X371802Y978747D01*
Y978573D01*
X370402D01*
Y978747D01*
G37*
G36*
G01X359279D02*
X359464Y979347D01*
X360494D01*
X360679Y978747D01*
Y978573D01*
X359279D01*
Y978747D01*
G37*
G36*
G01X363012Y978749D02*
X363197Y979349D01*
X364227D01*
X364412Y978749D01*
Y978574D01*
X363012D01*
Y978749D01*
G37*
G36*
G01X355612D02*
X355797Y979349D01*
X356827D01*
X357012Y978749D01*
Y978574D01*
X355612D01*
Y978749D01*
G37*
G36*
G01X366712D02*
X366897Y979349D01*
X367927D01*
X368112Y978749D01*
Y978574D01*
X366712D01*
Y978749D01*
G37*
G36*
G01X370402Y978747D02*
X370587Y979347D01*
X371617D01*
X371802Y978747D01*
Y978573D01*
X370402D01*
Y978747D01*
G37*
G36*
G01X360655Y973947D02*
X360470Y973347D01*
X359440D01*
X359255Y973947D01*
Y974122D01*
X360655D01*
Y973947D01*
G37*
G36*
G01X364402D02*
X364217Y973347D01*
X363187D01*
X363002Y973947D01*
Y974121D01*
X364402D01*
Y973947D01*
G37*
G36*
G01X357002D02*
X356817Y973347D01*
X355787D01*
X355602Y973947D01*
Y974121D01*
X357002D01*
Y973947D01*
G37*
G36*
G01X368112D02*
X367927Y973347D01*
X366897D01*
X366712Y973947D01*
Y974121D01*
X368112D01*
Y973947D01*
G37*
G36*
G01X371812D02*
X371627Y973347D01*
X370597D01*
X370412Y973947D01*
Y974121D01*
X371812D01*
Y973947D01*
G37*
G36*
G01X360655D02*
X360470Y973347D01*
X359440D01*
X359255Y973947D01*
Y974122D01*
X360655D01*
Y973947D01*
G37*
G36*
G01X364402D02*
X364217Y973347D01*
X363187D01*
X363002Y973947D01*
Y974121D01*
X364402D01*
Y973947D01*
G37*
G36*
G01X357002D02*
X356817Y973347D01*
X355787D01*
X355602Y973947D01*
Y974121D01*
X357002D01*
Y973947D01*
G37*
G36*
G01X368112D02*
X367927Y973347D01*
X366897D01*
X366712Y973947D01*
Y974121D01*
X368112D01*
Y973947D01*
G37*
G36*
G01X371812D02*
X371627Y973347D01*
X370597D01*
X370412Y973947D01*
Y974121D01*
X371812D01*
Y973947D01*
G37*
G36*
G01X366702Y965931D02*
X366887Y966531D01*
X367917D01*
X368102Y965931D01*
Y965757D01*
X366702D01*
Y965931D01*
G37*
G36*
G01X359302D02*
X359487Y966531D01*
X360517D01*
X360702Y965931D01*
Y965757D01*
X359302D01*
Y965931D01*
G37*
G36*
G01X362955D02*
X363140Y966531D01*
X364170D01*
X364355Y965931D01*
Y965756D01*
X362955D01*
Y965931D01*
G37*
G36*
G01X355555D02*
X355740Y966531D01*
X356770D01*
X356955Y965931D01*
Y965756D01*
X355555D01*
Y965931D01*
G37*
G36*
G01X370412D02*
X370597Y966531D01*
X371627D01*
X371812Y965931D01*
Y965757D01*
X370412D01*
Y965931D01*
G37*
G36*
G01X366702D02*
X366887Y966531D01*
X367917D01*
X368102Y965931D01*
Y965757D01*
X366702D01*
Y965931D01*
G37*
G36*
G01X359302D02*
X359487Y966531D01*
X360517D01*
X360702Y965931D01*
Y965757D01*
X359302D01*
Y965931D01*
G37*
G36*
G01X362955D02*
X363140Y966531D01*
X364170D01*
X364355Y965931D01*
Y965756D01*
X362955D01*
Y965931D01*
G37*
G36*
G01X355555D02*
X355740Y966531D01*
X356770D01*
X356955Y965931D01*
Y965756D01*
X355555D01*
Y965931D01*
G37*
G36*
G01X370412D02*
X370597Y966531D01*
X371627D01*
X371812Y965931D01*
Y965757D01*
X370412D01*
Y965931D01*
G37*
G36*
G01X357428Y969135D02*
X357613Y969735D01*
X358643D01*
X358828Y969135D01*
Y968960D01*
X357428D01*
Y969135D01*
G37*
G36*
G01X361095D02*
X361280Y969735D01*
X362310D01*
X362495Y969135D01*
Y968961D01*
X361095D01*
Y969135D01*
G37*
G36*
G01X364828D02*
X365013Y969735D01*
X366043D01*
X366228Y969135D01*
Y968960D01*
X364828D01*
Y969135D01*
G37*
G36*
G01X368505D02*
X368690Y969735D01*
X369720D01*
X369905Y969135D01*
Y968961D01*
X368505D01*
Y969135D01*
G37*
G36*
G01X357428D02*
X357613Y969735D01*
X358643D01*
X358828Y969135D01*
Y968960D01*
X357428D01*
Y969135D01*
G37*
G36*
G01X361095D02*
X361280Y969735D01*
X362310D01*
X362495Y969135D01*
Y968961D01*
X361095D01*
Y969135D01*
G37*
G36*
G01X364828D02*
X365013Y969735D01*
X366043D01*
X366228Y969135D01*
Y968960D01*
X364828D01*
Y969135D01*
G37*
G36*
G01X368505D02*
X368690Y969735D01*
X369720D01*
X369905Y969135D01*
Y968961D01*
X368505D01*
Y969135D01*
G37*
G36*
G01X360702Y967539D02*
X360517Y966939D01*
X359487D01*
X359302Y967539D01*
Y967713D01*
X360702D01*
Y967539D01*
G37*
G36*
G01X364402D02*
X364217Y966939D01*
X363187D01*
X363002Y967539D01*
Y967714D01*
X364402D01*
Y967539D01*
G37*
G36*
G01X357002D02*
X356817Y966939D01*
X355787D01*
X355602Y967539D01*
Y967714D01*
X357002D01*
Y967539D01*
G37*
G36*
G01X368102D02*
X367917Y966939D01*
X366887D01*
X366702Y967539D01*
Y967713D01*
X368102D01*
Y967539D01*
G37*
G36*
G01X371779D02*
X371594Y966939D01*
X370564D01*
X370379Y967539D01*
Y967714D01*
X371779D01*
Y967539D01*
G37*
G36*
G01X360702D02*
X360517Y966939D01*
X359487D01*
X359302Y967539D01*
Y967713D01*
X360702D01*
Y967539D01*
G37*
G36*
G01X364402D02*
X364217Y966939D01*
X363187D01*
X363002Y967539D01*
Y967714D01*
X364402D01*
Y967539D01*
G37*
G36*
G01X357002D02*
X356817Y966939D01*
X355787D01*
X355602Y967539D01*
Y967714D01*
X357002D01*
Y967539D01*
G37*
G36*
G01X368102D02*
X367917Y966939D01*
X366887D01*
X366702Y967539D01*
Y967713D01*
X368102D01*
Y967539D01*
G37*
G36*
G01X371779D02*
X371594Y966939D01*
X370564D01*
X370379Y967539D01*
Y967714D01*
X371779D01*
Y967539D01*
G37*
G36*
G01X356035Y1005289D02*
X356220Y1005889D01*
X357250D01*
X357435Y1005289D01*
Y1005115D01*
X356035D01*
Y1005289D01*
G37*
G36*
G01X359688D02*
X359873Y1005889D01*
X360903D01*
X361088Y1005289D01*
Y1005114D01*
X359688D01*
Y1005289D01*
G37*
G36*
G01X363435D02*
X363620Y1005889D01*
X364650D01*
X364835Y1005289D01*
Y1005115D01*
X363435D01*
Y1005289D01*
G37*
G36*
G01X367145D02*
X367330Y1005889D01*
X368360D01*
X368545Y1005289D01*
Y1005115D01*
X367145D01*
Y1005289D01*
G37*
G36*
G01X356035D02*
X356220Y1005889D01*
X357250D01*
X357435Y1005289D01*
Y1005115D01*
X356035D01*
Y1005289D01*
G37*
G36*
G01X359688D02*
X359873Y1005889D01*
X360903D01*
X361088Y1005289D01*
Y1005114D01*
X359688D01*
Y1005289D01*
G37*
G36*
G01X363435D02*
X363620Y1005889D01*
X364650D01*
X364835Y1005289D01*
Y1005115D01*
X363435D01*
Y1005289D01*
G37*
G36*
G01X367145D02*
X367330Y1005889D01*
X368360D01*
X368545Y1005289D01*
Y1005115D01*
X367145D01*
Y1005289D01*
G37*
G36*
G01X357838Y1002085D02*
X358023Y1002685D01*
X359053D01*
X359238Y1002085D01*
Y1001910D01*
X357838D01*
Y1002085D01*
G37*
G36*
G01X365228D02*
X365413Y1002685D01*
X366443D01*
X366628Y1002085D01*
Y1001910D01*
X365228D01*
Y1002085D01*
G37*
G36*
G01X361538Y1002083D02*
X361723Y1002683D01*
X362753D01*
X362938Y1002083D01*
Y1001909D01*
X361538D01*
Y1002083D01*
G37*
G36*
G01X368928Y1002085D02*
X369113Y1002685D01*
X370143D01*
X370328Y1002085D01*
Y1001910D01*
X368928D01*
Y1002085D01*
G37*
G36*
G01X357838D02*
X358023Y1002685D01*
X359053D01*
X359238Y1002085D01*
Y1001910D01*
X357838D01*
Y1002085D01*
G37*
G36*
G01X365228D02*
X365413Y1002685D01*
X366443D01*
X366628Y1002085D01*
Y1001910D01*
X365228D01*
Y1002085D01*
G37*
G36*
G01X361538Y1002083D02*
X361723Y1002683D01*
X362753D01*
X362938Y1002083D01*
Y1001909D01*
X361538D01*
Y1002083D01*
G37*
G36*
G01X368928Y1002085D02*
X369113Y1002685D01*
X370143D01*
X370328Y1002085D01*
Y1001910D01*
X368928D01*
Y1002085D01*
G37*
G36*
G01X359238Y1003691D02*
X359053Y1003091D01*
X358023D01*
X357838Y1003691D01*
Y1003866D01*
X359238D01*
Y1003691D01*
G37*
G36*
G01X366628D02*
X366443Y1003091D01*
X365413D01*
X365228Y1003691D01*
Y1003866D01*
X366628D01*
Y1003691D01*
G37*
G36*
G01X362985Y1003693D02*
X362800Y1003093D01*
X361770D01*
X361585Y1003693D01*
Y1003867D01*
X362985D01*
Y1003693D01*
G37*
G36*
G01X370328Y1003691D02*
X370143Y1003091D01*
X369113D01*
X368928Y1003691D01*
Y1003866D01*
X370328D01*
Y1003691D01*
G37*
G36*
G01X359238D02*
X359053Y1003091D01*
X358023D01*
X357838Y1003691D01*
Y1003866D01*
X359238D01*
Y1003691D01*
G37*
G36*
G01X366628D02*
X366443Y1003091D01*
X365413D01*
X365228Y1003691D01*
Y1003866D01*
X366628D01*
Y1003691D01*
G37*
G36*
G01X362985Y1003693D02*
X362800Y1003093D01*
X361770D01*
X361585Y1003693D01*
Y1003867D01*
X362985D01*
Y1003693D01*
G37*
G36*
G01X370328Y1003691D02*
X370143Y1003091D01*
X369113D01*
X368928Y1003691D01*
Y1003866D01*
X370328D01*
Y1003691D01*
G37*
G36*
G01X357435Y1000487D02*
X357250Y999887D01*
X356220D01*
X356035Y1000487D01*
Y1000662D01*
X357435D01*
Y1000487D01*
G37*
G36*
G01X361112Y1000489D02*
X360927Y999889D01*
X359897D01*
X359712Y1000489D01*
Y1000663D01*
X361112D01*
Y1000489D01*
G37*
G36*
G01X364845Y1000487D02*
X364660Y999887D01*
X363630D01*
X363445Y1000487D01*
Y1000662D01*
X364845D01*
Y1000487D01*
G37*
G36*
G01X368545D02*
X368360Y999887D01*
X367330D01*
X367145Y1000487D01*
Y1000662D01*
X368545D01*
Y1000487D01*
G37*
G36*
G01X357435D02*
X357250Y999887D01*
X356220D01*
X356035Y1000487D01*
Y1000662D01*
X357435D01*
Y1000487D01*
G37*
G36*
G01X361112Y1000489D02*
X360927Y999889D01*
X359897D01*
X359712Y1000489D01*
Y1000663D01*
X361112D01*
Y1000489D01*
G37*
G36*
G01X364845Y1000487D02*
X364660Y999887D01*
X363630D01*
X363445Y1000487D01*
Y1000662D01*
X364845D01*
Y1000487D01*
G37*
G36*
G01X368545D02*
X368360Y999887D01*
X367330D01*
X367145Y1000487D01*
Y1000662D01*
X368545D01*
Y1000487D01*
G37*
G36*
G01X367135Y1011697D02*
X367320Y1012297D01*
X368350D01*
X368535Y1011697D01*
Y1011523D01*
X367135D01*
Y1011697D01*
G37*
G36*
G01X356011D02*
X356196Y1012297D01*
X357226D01*
X357411Y1011697D01*
Y1011522D01*
X356011D01*
Y1011697D01*
G37*
G36*
G01X359735D02*
X359920Y1012297D01*
X360950D01*
X361135Y1011697D01*
Y1011523D01*
X359735D01*
Y1011697D01*
G37*
G36*
G01X363435D02*
X363620Y1012297D01*
X364650D01*
X364835Y1011697D01*
Y1011522D01*
X363435D01*
Y1011697D01*
G37*
G36*
G01X367135D02*
X367320Y1012297D01*
X368350D01*
X368535Y1011697D01*
Y1011523D01*
X367135D01*
Y1011697D01*
G37*
G36*
G01X356011D02*
X356196Y1012297D01*
X357226D01*
X357411Y1011697D01*
Y1011522D01*
X356011D01*
Y1011697D01*
G37*
G36*
G01X359735D02*
X359920Y1012297D01*
X360950D01*
X361135Y1011697D01*
Y1011523D01*
X359735D01*
Y1011697D01*
G37*
G36*
G01X363435D02*
X363620Y1012297D01*
X364650D01*
X364835Y1011697D01*
Y1011522D01*
X363435D01*
Y1011697D01*
G37*
G36*
G01X357828Y1008493D02*
X358013Y1009093D01*
X359043D01*
X359228Y1008493D01*
Y1008319D01*
X357828D01*
Y1008493D01*
G37*
G36*
G01X361561D02*
X361746Y1009093D01*
X362776D01*
X362961Y1008493D01*
Y1008318D01*
X361561D01*
Y1008493D01*
G37*
G36*
G01X365228D02*
X365413Y1009093D01*
X366443D01*
X366628Y1008493D01*
Y1008319D01*
X365228D01*
Y1008493D01*
G37*
G36*
G01X368938D02*
X369123Y1009093D01*
X370153D01*
X370338Y1008493D01*
Y1008319D01*
X368938D01*
Y1008493D01*
G37*
G36*
G01X357828D02*
X358013Y1009093D01*
X359043D01*
X359228Y1008493D01*
Y1008319D01*
X357828D01*
Y1008493D01*
G37*
G36*
G01X361561D02*
X361746Y1009093D01*
X362776D01*
X362961Y1008493D01*
Y1008318D01*
X361561D01*
Y1008493D01*
G37*
G36*
G01X365228D02*
X365413Y1009093D01*
X366443D01*
X366628Y1008493D01*
Y1008319D01*
X365228D01*
Y1008493D01*
G37*
G36*
G01X368938D02*
X369123Y1009093D01*
X370153D01*
X370338Y1008493D01*
Y1008319D01*
X368938D01*
Y1008493D01*
G37*
G36*
G01X359261Y1010101D02*
X359076Y1009501D01*
X358046D01*
X357861Y1010101D01*
Y1010276D01*
X359261D01*
Y1010101D01*
G37*
G36*
G01X362928D02*
X362743Y1009501D01*
X361713D01*
X361528Y1010101D01*
Y1010275D01*
X362928D01*
Y1010101D01*
G37*
G36*
G01X366661D02*
X366476Y1009501D01*
X365446D01*
X365261Y1010101D01*
Y1010276D01*
X366661D01*
Y1010101D01*
G37*
G36*
G01X370338D02*
X370153Y1009501D01*
X369123D01*
X368938Y1010101D01*
Y1010275D01*
X370338D01*
Y1010101D01*
G37*
G36*
G01X359261D02*
X359076Y1009501D01*
X358046D01*
X357861Y1010101D01*
Y1010276D01*
X359261D01*
Y1010101D01*
G37*
G36*
G01X362928D02*
X362743Y1009501D01*
X361713D01*
X361528Y1010101D01*
Y1010275D01*
X362928D01*
Y1010101D01*
G37*
G36*
G01X366661D02*
X366476Y1009501D01*
X365446D01*
X365261Y1010101D01*
Y1010276D01*
X366661D01*
Y1010101D01*
G37*
G36*
G01X370338D02*
X370153Y1009501D01*
X369123D01*
X368938Y1010101D01*
Y1010275D01*
X370338D01*
Y1010101D01*
G37*
G36*
G01X357435Y1006897D02*
X357250Y1006297D01*
X356220D01*
X356035Y1006897D01*
Y1007071D01*
X357435D01*
Y1006897D01*
G37*
G36*
G01X361135D02*
X360950Y1006297D01*
X359920D01*
X359735Y1006897D01*
Y1007072D01*
X361135D01*
Y1006897D01*
G37*
G36*
G01X364835D02*
X364650Y1006297D01*
X363620D01*
X363435Y1006897D01*
Y1007071D01*
X364835D01*
Y1006897D01*
G37*
G36*
G01X368545D02*
X368360Y1006297D01*
X367330D01*
X367145Y1006897D01*
Y1007071D01*
X368545D01*
Y1006897D01*
G37*
G36*
G01X357435D02*
X357250Y1006297D01*
X356220D01*
X356035Y1006897D01*
Y1007071D01*
X357435D01*
Y1006897D01*
G37*
G36*
G01X361135D02*
X360950Y1006297D01*
X359920D01*
X359735Y1006897D01*
Y1007072D01*
X361135D01*
Y1006897D01*
G37*
G36*
G01X364835D02*
X364650Y1006297D01*
X363620D01*
X363435Y1006897D01*
Y1007071D01*
X364835D01*
Y1006897D01*
G37*
G36*
G01X368545D02*
X368360Y1006297D01*
X367330D01*
X367145Y1006897D01*
Y1007071D01*
X368545D01*
Y1006897D01*
G37*
G36*
G01X359261Y1029327D02*
X359076Y1028727D01*
X358046D01*
X357861Y1029327D01*
Y1029502D01*
X359261D01*
Y1029327D01*
G37*
G36*
G01X366628D02*
X366443Y1028727D01*
X365413D01*
X365228Y1029327D01*
Y1029501D01*
X366628D01*
Y1029327D01*
G37*
G36*
G01X362928D02*
X362743Y1028727D01*
X361713D01*
X361528Y1029327D01*
Y1029501D01*
X362928D01*
Y1029327D01*
G37*
G36*
G01X370328D02*
X370143Y1028727D01*
X369113D01*
X368928Y1029327D01*
Y1029501D01*
X370328D01*
Y1029327D01*
G37*
G36*
G01X359261D02*
X359076Y1028727D01*
X358046D01*
X357861Y1029327D01*
Y1029502D01*
X359261D01*
Y1029327D01*
G37*
G36*
G01X366628D02*
X366443Y1028727D01*
X365413D01*
X365228Y1029327D01*
Y1029501D01*
X366628D01*
Y1029327D01*
G37*
G36*
G01X362928D02*
X362743Y1028727D01*
X361713D01*
X361528Y1029327D01*
Y1029501D01*
X362928D01*
Y1029327D01*
G37*
G36*
G01X370328D02*
X370143Y1028727D01*
X369113D01*
X368928Y1029327D01*
Y1029501D01*
X370328D01*
Y1029327D01*
G37*
G36*
G01X357435Y1019713D02*
X357250Y1019113D01*
X356220D01*
X356035Y1019713D01*
Y1019888D01*
X357435D01*
Y1019713D01*
G37*
G36*
G01X361112Y1019715D02*
X360927Y1019115D01*
X359897D01*
X359712Y1019715D01*
Y1019889D01*
X361112D01*
Y1019715D01*
G37*
G36*
G01X364845Y1019713D02*
X364660Y1019113D01*
X363630D01*
X363445Y1019713D01*
Y1019888D01*
X364845D01*
Y1019713D01*
G37*
G36*
G01X368545D02*
X368360Y1019113D01*
X367330D01*
X367145Y1019713D01*
Y1019888D01*
X368545D01*
Y1019713D01*
G37*
G36*
G01X357435D02*
X357250Y1019113D01*
X356220D01*
X356035Y1019713D01*
Y1019888D01*
X357435D01*
Y1019713D01*
G37*
G36*
G01X361112Y1019715D02*
X360927Y1019115D01*
X359897D01*
X359712Y1019715D01*
Y1019889D01*
X361112D01*
Y1019715D01*
G37*
G36*
G01X364845Y1019713D02*
X364660Y1019113D01*
X363630D01*
X363445Y1019713D01*
Y1019888D01*
X364845D01*
Y1019713D01*
G37*
G36*
G01X368545D02*
X368360Y1019113D01*
X367330D01*
X367145Y1019713D01*
Y1019888D01*
X368545D01*
Y1019713D01*
G37*
G36*
G01X359238Y1016509D02*
X359053Y1015909D01*
X358023D01*
X357838Y1016509D01*
Y1016684D01*
X359238D01*
Y1016509D01*
G37*
G36*
G01X362938D02*
X362753Y1015909D01*
X361723D01*
X361538Y1016509D01*
Y1016683D01*
X362938D01*
Y1016509D01*
G37*
G36*
G01X366638D02*
X366453Y1015909D01*
X365423D01*
X365238Y1016509D01*
Y1016684D01*
X366638D01*
Y1016509D01*
G37*
G36*
G01X355585D02*
X355400Y1015909D01*
X354370D01*
X354185Y1016509D01*
Y1016683D01*
X355585D01*
Y1016509D01*
G37*
G36*
G01X370328D02*
X370143Y1015909D01*
X369113D01*
X368928Y1016509D01*
Y1016683D01*
X370328D01*
Y1016509D01*
G37*
G36*
G01X359238D02*
X359053Y1015909D01*
X358023D01*
X357838Y1016509D01*
Y1016684D01*
X359238D01*
Y1016509D01*
G37*
G36*
G01X362938D02*
X362753Y1015909D01*
X361723D01*
X361538Y1016509D01*
Y1016683D01*
X362938D01*
Y1016509D01*
G37*
G36*
G01X366638D02*
X366453Y1015909D01*
X365423D01*
X365238Y1016509D01*
Y1016684D01*
X366638D01*
Y1016509D01*
G37*
G36*
G01X355585D02*
X355400Y1015909D01*
X354370D01*
X354185Y1016509D01*
Y1016683D01*
X355585D01*
Y1016509D01*
G37*
G36*
G01X370328D02*
X370143Y1015909D01*
X369113D01*
X368928Y1016509D01*
Y1016683D01*
X370328D01*
Y1016509D01*
G37*
G36*
G01X365228Y1021311D02*
X365413Y1021911D01*
X366443D01*
X366628Y1021311D01*
Y1021136D01*
X365228D01*
Y1021311D01*
G37*
G36*
G01X357838D02*
X358023Y1021911D01*
X359053D01*
X359238Y1021311D01*
Y1021136D01*
X357838D01*
Y1021311D01*
G37*
G36*
G01X361538Y1021309D02*
X361723Y1021909D01*
X362753D01*
X362938Y1021309D01*
Y1021135D01*
X361538D01*
Y1021309D01*
G37*
G36*
G01X368928Y1021311D02*
X369113Y1021911D01*
X370143D01*
X370328Y1021311D01*
Y1021136D01*
X368928D01*
Y1021311D01*
G37*
G36*
G01X365228D02*
X365413Y1021911D01*
X366443D01*
X366628Y1021311D01*
Y1021136D01*
X365228D01*
Y1021311D01*
G37*
G36*
G01X357838D02*
X358023Y1021911D01*
X359053D01*
X359238Y1021311D01*
Y1021136D01*
X357838D01*
Y1021311D01*
G37*
G36*
G01X361538Y1021309D02*
X361723Y1021909D01*
X362753D01*
X362938Y1021309D01*
Y1021135D01*
X361538D01*
Y1021309D01*
G37*
G36*
G01X368928Y1021311D02*
X369113Y1021911D01*
X370143D01*
X370328Y1021311D01*
Y1021136D01*
X368928D01*
Y1021311D01*
G37*
G36*
G01X359745Y1018107D02*
X359930Y1018707D01*
X360960D01*
X361145Y1018107D01*
Y1017932D01*
X359745D01*
Y1018107D01*
G37*
G36*
G01X355988D02*
X356173Y1018707D01*
X357203D01*
X357388Y1018107D01*
Y1017932D01*
X355988D01*
Y1018107D01*
G37*
G36*
G01X363412Y1018105D02*
X363597Y1018705D01*
X364627D01*
X364812Y1018105D01*
Y1017931D01*
X363412D01*
Y1018105D01*
G37*
G36*
G01X367145Y1018107D02*
X367330Y1018707D01*
X368360D01*
X368545Y1018107D01*
Y1017932D01*
X367145D01*
Y1018107D01*
G37*
G36*
G01X359745D02*
X359930Y1018707D01*
X360960D01*
X361145Y1018107D01*
Y1017932D01*
X359745D01*
Y1018107D01*
G37*
G36*
G01X355988D02*
X356173Y1018707D01*
X357203D01*
X357388Y1018107D01*
Y1017932D01*
X355988D01*
Y1018107D01*
G37*
G36*
G01X363412Y1018105D02*
X363597Y1018705D01*
X364627D01*
X364812Y1018105D01*
Y1017931D01*
X363412D01*
Y1018105D01*
G37*
G36*
G01X367145Y1018107D02*
X367330Y1018707D01*
X368360D01*
X368545Y1018107D01*
Y1017932D01*
X367145D01*
Y1018107D01*
G37*
G36*
G01X359238Y1022917D02*
X359053Y1022317D01*
X358023D01*
X357838Y1022917D01*
Y1023092D01*
X359238D01*
Y1022917D01*
G37*
G36*
G01X366628D02*
X366443Y1022317D01*
X365413D01*
X365228Y1022917D01*
Y1023092D01*
X366628D01*
Y1022917D01*
G37*
G36*
G01X362985Y1022919D02*
X362800Y1022319D01*
X361770D01*
X361585Y1022919D01*
Y1023093D01*
X362985D01*
Y1022919D01*
G37*
G36*
G01X359238Y1022917D02*
X359053Y1022317D01*
X358023D01*
X357838Y1022917D01*
Y1023092D01*
X359238D01*
Y1022917D01*
G37*
G36*
G01X366628D02*
X366443Y1022317D01*
X365413D01*
X365228Y1022917D01*
Y1023092D01*
X366628D01*
Y1022917D01*
G37*
G36*
G01X362985Y1022919D02*
X362800Y1022319D01*
X361770D01*
X361585Y1022919D01*
Y1023093D01*
X362985D01*
Y1022919D01*
G37*
G36*
G01X357828Y1027719D02*
X358013Y1028319D01*
X359043D01*
X359228Y1027719D01*
Y1027545D01*
X357828D01*
Y1027719D01*
G37*
G36*
G01X365228D02*
X365413Y1028319D01*
X366443D01*
X366628Y1027719D01*
Y1027545D01*
X365228D01*
Y1027719D01*
G37*
G36*
G01X361561D02*
X361746Y1028319D01*
X362776D01*
X362961Y1027719D01*
Y1027544D01*
X361561D01*
Y1027719D01*
G37*
G36*
G01X368928D02*
X369113Y1028319D01*
X370143D01*
X370328Y1027719D01*
Y1027545D01*
X368928D01*
Y1027719D01*
G37*
G36*
G01X357828D02*
X358013Y1028319D01*
X359043D01*
X359228Y1027719D01*
Y1027545D01*
X357828D01*
Y1027719D01*
G37*
G36*
G01X365228D02*
X365413Y1028319D01*
X366443D01*
X366628Y1027719D01*
Y1027545D01*
X365228D01*
Y1027719D01*
G37*
G36*
G01X361561D02*
X361746Y1028319D01*
X362776D01*
X362961Y1027719D01*
Y1027544D01*
X361561D01*
Y1027719D01*
G37*
G36*
G01X368928D02*
X369113Y1028319D01*
X370143D01*
X370328Y1027719D01*
Y1027545D01*
X368928D01*
Y1027719D01*
G37*
G36*
G01X356045Y1024515D02*
X356230Y1025115D01*
X357260D01*
X357445Y1024515D01*
Y1024340D01*
X356045D01*
Y1024515D01*
G37*
G36*
G01X359688Y1024513D02*
X359873Y1025113D01*
X360903D01*
X361088Y1024513D01*
Y1024339D01*
X359688D01*
Y1024513D01*
G37*
G36*
G01X363435Y1024515D02*
X363620Y1025115D01*
X364650D01*
X364835Y1024515D01*
Y1024340D01*
X363435D01*
Y1024515D01*
G37*
G36*
G01X367145D02*
X367330Y1025115D01*
X368360D01*
X368545Y1024515D01*
Y1024340D01*
X367145D01*
Y1024515D01*
G37*
G36*
G01X356045D02*
X356230Y1025115D01*
X357260D01*
X357445Y1024515D01*
Y1024340D01*
X356045D01*
Y1024515D01*
G37*
G36*
G01X359688Y1024513D02*
X359873Y1025113D01*
X360903D01*
X361088Y1024513D01*
Y1024339D01*
X359688D01*
Y1024513D01*
G37*
G36*
G01X363435Y1024515D02*
X363620Y1025115D01*
X364650D01*
X364835Y1024515D01*
Y1024340D01*
X363435D01*
Y1024515D01*
G37*
G36*
G01X367145D02*
X367330Y1025115D01*
X368360D01*
X368545Y1024515D01*
Y1024340D01*
X367145D01*
Y1024515D01*
G37*
G36*
G01X357445Y1026121D02*
X357260Y1025521D01*
X356230D01*
X356045Y1026121D01*
Y1026296D01*
X357445D01*
Y1026121D01*
G37*
G36*
G01X361135Y1026123D02*
X360950Y1025523D01*
X359920D01*
X359735Y1026123D01*
Y1026297D01*
X361135D01*
Y1026123D01*
G37*
G36*
G01X364835Y1026121D02*
X364650Y1025521D01*
X363620D01*
X363435Y1026121D01*
Y1026296D01*
X364835D01*
Y1026121D01*
G37*
G36*
G01X368545D02*
X368360Y1025521D01*
X367330D01*
X367145Y1026121D01*
Y1026296D01*
X368545D01*
Y1026121D01*
G37*
G36*
G01X357445D02*
X357260Y1025521D01*
X356230D01*
X356045Y1026121D01*
Y1026296D01*
X357445D01*
Y1026121D01*
G37*
G36*
G01X361135Y1026123D02*
X360950Y1025523D01*
X359920D01*
X359735Y1026123D01*
Y1026297D01*
X361135D01*
Y1026123D01*
G37*
G36*
G01X364835Y1026121D02*
X364650Y1025521D01*
X363620D01*
X363435Y1026121D01*
Y1026296D01*
X364835D01*
Y1026121D01*
G37*
G36*
G01X368545D02*
X368360Y1025521D01*
X367330D01*
X367145Y1026121D01*
Y1026296D01*
X368545D01*
Y1026121D01*
G37*
G36*
G01Y1032531D02*
X368360Y1031931D01*
X367330D01*
X367145Y1032531D01*
Y1032705D01*
X368545D01*
Y1032531D01*
G37*
G36*
G01X361135D02*
X360950Y1031931D01*
X359920D01*
X359735Y1032531D01*
Y1032705D01*
X361135D01*
Y1032531D01*
G37*
G36*
G01X364845D02*
X364660Y1031931D01*
X363630D01*
X363445Y1032531D01*
Y1032705D01*
X364845D01*
Y1032531D01*
G37*
G36*
G01X357378D02*
X357193Y1031931D01*
X356163D01*
X355978Y1032531D01*
Y1032705D01*
X357378D01*
Y1032531D01*
G37*
G36*
G01X368545D02*
X368360Y1031931D01*
X367330D01*
X367145Y1032531D01*
Y1032705D01*
X368545D01*
Y1032531D01*
G37*
G36*
G01X361135D02*
X360950Y1031931D01*
X359920D01*
X359735Y1032531D01*
Y1032705D01*
X361135D01*
Y1032531D01*
G37*
G36*
G01X364845D02*
X364660Y1031931D01*
X363630D01*
X363445Y1032531D01*
Y1032705D01*
X364845D01*
Y1032531D01*
G37*
G36*
G01X357378D02*
X357193Y1031931D01*
X356163D01*
X355978Y1032531D01*
Y1032705D01*
X357378D01*
Y1032531D01*
G37*
G36*
G01X357885Y1034127D02*
X358070Y1034727D01*
X359100D01*
X359285Y1034127D01*
Y1033952D01*
X357885D01*
Y1034127D01*
G37*
G36*
G01X361528D02*
X361713Y1034727D01*
X362743D01*
X362928Y1034127D01*
Y1033953D01*
X361528D01*
Y1034127D01*
G37*
G36*
G01X365228D02*
X365413Y1034727D01*
X366443D01*
X366628Y1034127D01*
Y1033953D01*
X365228D01*
Y1034127D01*
G37*
G36*
G01X354185D02*
X354370Y1034727D01*
X355400D01*
X355585Y1034127D01*
Y1033953D01*
X354185D01*
Y1034127D01*
G37*
G36*
G01X368928D02*
X369113Y1034727D01*
X370143D01*
X370328Y1034127D01*
Y1033953D01*
X368928D01*
Y1034127D01*
G37*
G36*
G01X357885D02*
X358070Y1034727D01*
X359100D01*
X359285Y1034127D01*
Y1033952D01*
X357885D01*
Y1034127D01*
G37*
G36*
G01X361528D02*
X361713Y1034727D01*
X362743D01*
X362928Y1034127D01*
Y1033953D01*
X361528D01*
Y1034127D01*
G37*
G36*
G01X365228D02*
X365413Y1034727D01*
X366443D01*
X366628Y1034127D01*
Y1033953D01*
X365228D01*
Y1034127D01*
G37*
G36*
G01X354185D02*
X354370Y1034727D01*
X355400D01*
X355585Y1034127D01*
Y1033953D01*
X354185D01*
Y1034127D01*
G37*
G36*
G01X368928D02*
X369113Y1034727D01*
X370143D01*
X370328Y1034127D01*
Y1033953D01*
X368928D01*
Y1034127D01*
G37*
G36*
G01X359735Y1030923D02*
X359920Y1031523D01*
X360950D01*
X361135Y1030923D01*
Y1030749D01*
X359735D01*
Y1030923D01*
G37*
G36*
G01X363445D02*
X363630Y1031523D01*
X364660D01*
X364845Y1030923D01*
Y1030749D01*
X363445D01*
Y1030923D01*
G37*
G36*
G01X367145D02*
X367330Y1031523D01*
X368360D01*
X368545Y1030923D01*
Y1030749D01*
X367145D01*
Y1030923D01*
G37*
G36*
G01X356011D02*
X356196Y1031523D01*
X357226D01*
X357411Y1030923D01*
Y1030748D01*
X356011D01*
Y1030923D01*
G37*
G36*
G01X359735D02*
X359920Y1031523D01*
X360950D01*
X361135Y1030923D01*
Y1030749D01*
X359735D01*
Y1030923D01*
G37*
G36*
G01X363445D02*
X363630Y1031523D01*
X364660D01*
X364845Y1030923D01*
Y1030749D01*
X363445D01*
Y1030923D01*
G37*
G36*
G01X367145D02*
X367330Y1031523D01*
X368360D01*
X368545Y1030923D01*
Y1030749D01*
X367145D01*
Y1030923D01*
G37*
G36*
G01X356011D02*
X356196Y1031523D01*
X357226D01*
X357411Y1030923D01*
Y1030748D01*
X356011D01*
Y1030923D01*
G37*
G36*
G01X357838Y1040537D02*
X358023Y1041137D01*
X359053D01*
X359238Y1040537D01*
Y1040362D01*
X357838D01*
Y1040537D01*
G37*
G36*
G01X361538Y1040535D02*
X361723Y1041135D01*
X362753D01*
X362938Y1040535D01*
Y1040361D01*
X361538D01*
Y1040535D01*
G37*
G36*
G01X365228Y1040537D02*
X365413Y1041137D01*
X366443D01*
X366628Y1040537D01*
Y1040362D01*
X365228D01*
Y1040537D01*
G37*
G36*
G01X368928D02*
X369113Y1041137D01*
X370143D01*
X370328Y1040537D01*
Y1040362D01*
X368928D01*
Y1040537D01*
G37*
G36*
G01X357838D02*
X358023Y1041137D01*
X359053D01*
X359238Y1040537D01*
Y1040362D01*
X357838D01*
Y1040537D01*
G37*
G36*
G01X361538Y1040535D02*
X361723Y1041135D01*
X362753D01*
X362938Y1040535D01*
Y1040361D01*
X361538D01*
Y1040535D01*
G37*
G36*
G01X365228Y1040537D02*
X365413Y1041137D01*
X366443D01*
X366628Y1040537D01*
Y1040362D01*
X365228D01*
Y1040537D01*
G37*
G36*
G01X368928D02*
X369113Y1041137D01*
X370143D01*
X370328Y1040537D01*
Y1040362D01*
X368928D01*
Y1040537D01*
G37*
G36*
G01X355998Y1037331D02*
X356183Y1037931D01*
X357213D01*
X357398Y1037331D01*
Y1037156D01*
X355998D01*
Y1037331D01*
G37*
G36*
G01X359698D02*
X359883Y1037931D01*
X360913D01*
X361098Y1037331D01*
Y1037156D01*
X359698D01*
Y1037331D01*
G37*
G36*
G01X363398D02*
X363583Y1037931D01*
X364613D01*
X364798Y1037331D01*
Y1037156D01*
X363398D01*
Y1037331D01*
G37*
G36*
G01X367098D02*
X367283Y1037931D01*
X368313D01*
X368498Y1037331D01*
Y1037156D01*
X367098D01*
Y1037331D01*
G37*
G36*
G01X355998D02*
X356183Y1037931D01*
X357213D01*
X357398Y1037331D01*
Y1037156D01*
X355998D01*
Y1037331D01*
G37*
G36*
G01X359698D02*
X359883Y1037931D01*
X360913D01*
X361098Y1037331D01*
Y1037156D01*
X359698D01*
Y1037331D01*
G37*
G36*
G01X363398D02*
X363583Y1037931D01*
X364613D01*
X364798Y1037331D01*
Y1037156D01*
X363398D01*
Y1037331D01*
G37*
G36*
G01X367098D02*
X367283Y1037931D01*
X368313D01*
X368498Y1037331D01*
Y1037156D01*
X367098D01*
Y1037331D01*
G37*
G36*
G01X357435Y1038939D02*
X357250Y1038339D01*
X356220D01*
X356035Y1038939D01*
Y1039114D01*
X357435D01*
Y1038939D01*
G37*
G36*
G01X361112Y1038941D02*
X360927Y1038341D01*
X359897D01*
X359712Y1038941D01*
Y1039115D01*
X361112D01*
Y1038941D01*
G37*
G36*
G01X364845Y1038939D02*
X364660Y1038339D01*
X363630D01*
X363445Y1038939D01*
Y1039114D01*
X364845D01*
Y1038939D01*
G37*
G36*
G01X368545D02*
X368360Y1038339D01*
X367330D01*
X367145Y1038939D01*
Y1039114D01*
X368545D01*
Y1038939D01*
G37*
G36*
G01X357435D02*
X357250Y1038339D01*
X356220D01*
X356035Y1038939D01*
Y1039114D01*
X357435D01*
Y1038939D01*
G37*
G36*
G01X361112Y1038941D02*
X360927Y1038341D01*
X359897D01*
X359712Y1038941D01*
Y1039115D01*
X361112D01*
Y1038941D01*
G37*
G36*
G01X364845Y1038939D02*
X364660Y1038339D01*
X363630D01*
X363445Y1038939D01*
Y1039114D01*
X364845D01*
Y1038939D01*
G37*
G36*
G01X368545D02*
X368360Y1038339D01*
X367330D01*
X367145Y1038939D01*
Y1039114D01*
X368545D01*
Y1038939D01*
G37*
G36*
G01X359275Y1035737D02*
X359090Y1035137D01*
X358060D01*
X357875Y1035737D01*
Y1035911D01*
X359275D01*
Y1035737D01*
G37*
G36*
G01X366675D02*
X366490Y1035137D01*
X365460D01*
X365275Y1035737D01*
Y1035911D01*
X366675D01*
Y1035737D01*
G37*
G36*
G01X362975D02*
X362790Y1035137D01*
X361760D01*
X361575Y1035737D01*
Y1035911D01*
X362975D01*
Y1035737D01*
G37*
G36*
G01X355570Y1035735D02*
X355385Y1035135D01*
X354355D01*
X354170Y1035735D01*
Y1035910D01*
X355570D01*
Y1035735D01*
G37*
G36*
G01X370375Y1035737D02*
X370190Y1035137D01*
X369160D01*
X368975Y1035737D01*
Y1035911D01*
X370375D01*
Y1035737D01*
G37*
G36*
G01X359275D02*
X359090Y1035137D01*
X358060D01*
X357875Y1035737D01*
Y1035911D01*
X359275D01*
Y1035737D01*
G37*
G36*
G01X366675D02*
X366490Y1035137D01*
X365460D01*
X365275Y1035737D01*
Y1035911D01*
X366675D01*
Y1035737D01*
G37*
G36*
G01X362975D02*
X362790Y1035137D01*
X361760D01*
X361575Y1035737D01*
Y1035911D01*
X362975D01*
Y1035737D01*
G37*
G36*
G01X355570Y1035735D02*
X355385Y1035135D01*
X354355D01*
X354170Y1035735D01*
Y1035910D01*
X355570D01*
Y1035735D01*
G37*
G36*
G01X370375Y1035737D02*
X370190Y1035137D01*
X369160D01*
X368975Y1035737D01*
Y1035911D01*
X370375D01*
Y1035737D01*
G37*
G36*
G01X357435Y1045347D02*
X357250Y1044747D01*
X356220D01*
X356035Y1045347D01*
Y1045522D01*
X357435D01*
Y1045347D01*
G37*
G36*
G01X361135Y1045349D02*
X360950Y1044749D01*
X359920D01*
X359735Y1045349D01*
Y1045523D01*
X361135D01*
Y1045349D01*
G37*
G36*
G01X364835Y1045347D02*
X364650Y1044747D01*
X363620D01*
X363435Y1045347D01*
Y1045522D01*
X364835D01*
Y1045347D01*
G37*
G36*
G01X368545D02*
X368360Y1044747D01*
X367330D01*
X367145Y1045347D01*
Y1045522D01*
X368545D01*
Y1045347D01*
G37*
G36*
G01X357435D02*
X357250Y1044747D01*
X356220D01*
X356035Y1045347D01*
Y1045522D01*
X357435D01*
Y1045347D01*
G37*
G36*
G01X361135Y1045349D02*
X360950Y1044749D01*
X359920D01*
X359735Y1045349D01*
Y1045523D01*
X361135D01*
Y1045349D01*
G37*
G36*
G01X364835Y1045347D02*
X364650Y1044747D01*
X363620D01*
X363435Y1045347D01*
Y1045522D01*
X364835D01*
Y1045347D01*
G37*
G36*
G01X368545D02*
X368360Y1044747D01*
X367330D01*
X367145Y1045347D01*
Y1045522D01*
X368545D01*
Y1045347D01*
G37*
G36*
G01X367145Y1043741D02*
X367330Y1044341D01*
X368360D01*
X368545Y1043741D01*
Y1043566D01*
X367145D01*
Y1043741D01*
G37*
G36*
G01X356035D02*
X356220Y1044341D01*
X357250D01*
X357435Y1043741D01*
Y1043566D01*
X356035D01*
Y1043741D01*
G37*
G36*
G01X359688Y1043739D02*
X359873Y1044339D01*
X360903D01*
X361088Y1043739D01*
Y1043565D01*
X359688D01*
Y1043739D01*
G37*
G36*
G01X363435Y1043741D02*
X363620Y1044341D01*
X364650D01*
X364835Y1043741D01*
Y1043566D01*
X363435D01*
Y1043741D01*
G37*
G36*
G01X367145D02*
X367330Y1044341D01*
X368360D01*
X368545Y1043741D01*
Y1043566D01*
X367145D01*
Y1043741D01*
G37*
G36*
G01X356035D02*
X356220Y1044341D01*
X357250D01*
X357435Y1043741D01*
Y1043566D01*
X356035D01*
Y1043741D01*
G37*
G36*
G01X359688Y1043739D02*
X359873Y1044339D01*
X360903D01*
X361088Y1043739D01*
Y1043565D01*
X359688D01*
Y1043739D01*
G37*
G36*
G01X363435Y1043741D02*
X363620Y1044341D01*
X364650D01*
X364835Y1043741D01*
Y1043566D01*
X363435D01*
Y1043741D01*
G37*
G36*
G01X357828Y1046945D02*
X358013Y1047545D01*
X359043D01*
X359228Y1046945D01*
Y1046770D01*
X357828D01*
Y1046945D01*
G37*
G36*
G01X365228D02*
X365413Y1047545D01*
X366443D01*
X366628Y1046945D01*
Y1046771D01*
X365228D01*
Y1046945D01*
G37*
G36*
G01X361561Y1046943D02*
X361746Y1047543D01*
X362776D01*
X362961Y1046943D01*
Y1046769D01*
X361561D01*
Y1046943D01*
G37*
G36*
G01X368930Y1046945D02*
X369115Y1047545D01*
X370145D01*
X370330Y1046945D01*
Y1046770D01*
X368930D01*
Y1046945D01*
G37*
G36*
G01X357828D02*
X358013Y1047545D01*
X359043D01*
X359228Y1046945D01*
Y1046770D01*
X357828D01*
Y1046945D01*
G37*
G36*
G01X365228D02*
X365413Y1047545D01*
X366443D01*
X366628Y1046945D01*
Y1046771D01*
X365228D01*
Y1046945D01*
G37*
G36*
G01X361561Y1046943D02*
X361746Y1047543D01*
X362776D01*
X362961Y1046943D01*
Y1046769D01*
X361561D01*
Y1046943D01*
G37*
G36*
G01X368930Y1046945D02*
X369115Y1047545D01*
X370145D01*
X370330Y1046945D01*
Y1046770D01*
X368930D01*
Y1046945D01*
G37*
G36*
G01X359238Y1042143D02*
X359053Y1041543D01*
X358023D01*
X357838Y1042143D01*
Y1042318D01*
X359238D01*
Y1042143D01*
G37*
G36*
G01X366628D02*
X366443Y1041543D01*
X365413D01*
X365228Y1042143D01*
Y1042318D01*
X366628D01*
Y1042143D01*
G37*
G36*
G01X362985Y1042145D02*
X362800Y1041545D01*
X361770D01*
X361585Y1042145D01*
Y1042319D01*
X362985D01*
Y1042145D01*
G37*
G36*
G01X370328Y1042143D02*
X370143Y1041543D01*
X369113D01*
X368928Y1042143D01*
Y1042318D01*
X370328D01*
Y1042143D01*
G37*
G36*
G01X359238D02*
X359053Y1041543D01*
X358023D01*
X357838Y1042143D01*
Y1042318D01*
X359238D01*
Y1042143D01*
G37*
G36*
G01X366628D02*
X366443Y1041543D01*
X365413D01*
X365228Y1042143D01*
Y1042318D01*
X366628D01*
Y1042143D01*
G37*
G36*
G01X362985Y1042145D02*
X362800Y1041545D01*
X361770D01*
X361585Y1042145D01*
Y1042319D01*
X362985D01*
Y1042145D01*
G37*
G36*
G01X370328Y1042143D02*
X370143Y1041543D01*
X369113D01*
X368928Y1042143D01*
Y1042318D01*
X370328D01*
Y1042143D01*
G37*
G36*
G01X357838Y1059761D02*
X358023Y1060361D01*
X359053D01*
X359238Y1059761D01*
Y1059587D01*
X357838D01*
Y1059761D01*
G37*
G36*
G01X365228D02*
X365413Y1060361D01*
X366443D01*
X366628Y1059761D01*
Y1059587D01*
X365228D01*
Y1059761D01*
G37*
G36*
G01X361538D02*
X361723Y1060361D01*
X362753D01*
X362938Y1059761D01*
Y1059586D01*
X361538D01*
Y1059761D01*
G37*
G36*
G01X368928D02*
X369113Y1060361D01*
X370143D01*
X370328Y1059761D01*
Y1059587D01*
X368928D01*
Y1059761D01*
G37*
G36*
G01X357838D02*
X358023Y1060361D01*
X359053D01*
X359238Y1059761D01*
Y1059587D01*
X357838D01*
Y1059761D01*
G37*
G36*
G01X365228D02*
X365413Y1060361D01*
X366443D01*
X366628Y1059761D01*
Y1059587D01*
X365228D01*
Y1059761D01*
G37*
G36*
G01X361538D02*
X361723Y1060361D01*
X362753D01*
X362938Y1059761D01*
Y1059586D01*
X361538D01*
Y1059761D01*
G37*
G36*
G01X368928D02*
X369113Y1060361D01*
X370143D01*
X370328Y1059761D01*
Y1059587D01*
X368928D01*
Y1059761D01*
G37*
G36*
G01X355988Y1056557D02*
X356173Y1057157D01*
X357203D01*
X357388Y1056557D01*
Y1056383D01*
X355988D01*
Y1056557D01*
G37*
G36*
G01X359745D02*
X359930Y1057157D01*
X360960D01*
X361145Y1056557D01*
Y1056383D01*
X359745D01*
Y1056557D01*
G37*
G36*
G01X363445D02*
X363630Y1057157D01*
X364660D01*
X364845Y1056557D01*
Y1056383D01*
X363445D01*
Y1056557D01*
G37*
G36*
G01X367145D02*
X367330Y1057157D01*
X368360D01*
X368545Y1056557D01*
Y1056383D01*
X367145D01*
Y1056557D01*
G37*
G36*
G01X355988D02*
X356173Y1057157D01*
X357203D01*
X357388Y1056557D01*
Y1056383D01*
X355988D01*
Y1056557D01*
G37*
G36*
G01X359745D02*
X359930Y1057157D01*
X360960D01*
X361145Y1056557D01*
Y1056383D01*
X359745D01*
Y1056557D01*
G37*
G36*
G01X363445D02*
X363630Y1057157D01*
X364660D01*
X364845Y1056557D01*
Y1056383D01*
X363445D01*
Y1056557D01*
G37*
G36*
G01X367145D02*
X367330Y1057157D01*
X368360D01*
X368545Y1056557D01*
Y1056383D01*
X367145D01*
Y1056557D01*
G37*
G36*
G01X368545Y1058165D02*
X368360Y1057565D01*
X367330D01*
X367145Y1058165D01*
Y1058339D01*
X368545D01*
Y1058165D01*
G37*
G36*
G01X357435D02*
X357250Y1057565D01*
X356220D01*
X356035Y1058165D01*
Y1058339D01*
X357435D01*
Y1058165D01*
G37*
G36*
G01X361112D02*
X360927Y1057565D01*
X359897D01*
X359712Y1058165D01*
Y1058340D01*
X361112D01*
Y1058165D01*
G37*
G36*
G01X364845D02*
X364660Y1057565D01*
X363630D01*
X363445Y1058165D01*
Y1058339D01*
X364845D01*
Y1058165D01*
G37*
G36*
G01X368545D02*
X368360Y1057565D01*
X367330D01*
X367145Y1058165D01*
Y1058339D01*
X368545D01*
Y1058165D01*
G37*
G36*
G01X357435D02*
X357250Y1057565D01*
X356220D01*
X356035Y1058165D01*
Y1058339D01*
X357435D01*
Y1058165D01*
G37*
G36*
G01X361112D02*
X360927Y1057565D01*
X359897D01*
X359712Y1058165D01*
Y1058340D01*
X361112D01*
Y1058165D01*
G37*
G36*
G01X364845D02*
X364660Y1057565D01*
X363630D01*
X363445Y1058165D01*
Y1058339D01*
X364845D01*
Y1058165D01*
G37*
G36*
G01X359238Y1054961D02*
X359053Y1054361D01*
X358023D01*
X357838Y1054961D01*
Y1055136D01*
X359238D01*
Y1054961D01*
G37*
G36*
G01X362928D02*
X362743Y1054361D01*
X361713D01*
X361528Y1054961D01*
Y1055135D01*
X362928D01*
Y1054961D01*
G37*
G36*
G01X366628D02*
X366443Y1054361D01*
X365413D01*
X365228Y1054961D01*
Y1055135D01*
X366628D01*
Y1054961D01*
G37*
G36*
G01X355585D02*
X355400Y1054361D01*
X354370D01*
X354185Y1054961D01*
Y1055135D01*
X355585D01*
Y1054961D01*
G37*
G36*
G01X370328D02*
X370143Y1054361D01*
X369113D01*
X368928Y1054961D01*
Y1055135D01*
X370328D01*
Y1054961D01*
G37*
G36*
G01X359238D02*
X359053Y1054361D01*
X358023D01*
X357838Y1054961D01*
Y1055136D01*
X359238D01*
Y1054961D01*
G37*
G36*
G01X362928D02*
X362743Y1054361D01*
X361713D01*
X361528Y1054961D01*
Y1055135D01*
X362928D01*
Y1054961D01*
G37*
G36*
G01X366628D02*
X366443Y1054361D01*
X365413D01*
X365228Y1054961D01*
Y1055135D01*
X366628D01*
Y1054961D01*
G37*
G36*
G01X355585D02*
X355400Y1054361D01*
X354370D01*
X354185Y1054961D01*
Y1055135D01*
X355585D01*
Y1054961D01*
G37*
G36*
G01X370328D02*
X370143Y1054361D01*
X369113D01*
X368928Y1054961D01*
Y1055135D01*
X370328D01*
Y1054961D01*
G37*
G36*
G01X357885Y1053353D02*
X358070Y1053953D01*
X359100D01*
X359285Y1053353D01*
Y1053178D01*
X357885D01*
Y1053353D01*
G37*
G36*
G01X361528D02*
X361713Y1053953D01*
X362743D01*
X362928Y1053353D01*
Y1053179D01*
X361528D01*
Y1053353D01*
G37*
G36*
G01X365228D02*
X365413Y1053953D01*
X366443D01*
X366628Y1053353D01*
Y1053179D01*
X365228D01*
Y1053353D01*
G37*
G36*
G01X354185D02*
X354370Y1053953D01*
X355400D01*
X355585Y1053353D01*
Y1053179D01*
X354185D01*
Y1053353D01*
G37*
G36*
G01X368928D02*
X369113Y1053953D01*
X370143D01*
X370328Y1053353D01*
Y1053179D01*
X368928D01*
Y1053353D01*
G37*
G36*
G01X357885D02*
X358070Y1053953D01*
X359100D01*
X359285Y1053353D01*
Y1053178D01*
X357885D01*
Y1053353D01*
G37*
G36*
G01X361528D02*
X361713Y1053953D01*
X362743D01*
X362928Y1053353D01*
Y1053179D01*
X361528D01*
Y1053353D01*
G37*
G36*
G01X365228D02*
X365413Y1053953D01*
X366443D01*
X366628Y1053353D01*
Y1053179D01*
X365228D01*
Y1053353D01*
G37*
G36*
G01X354185D02*
X354370Y1053953D01*
X355400D01*
X355585Y1053353D01*
Y1053179D01*
X354185D01*
Y1053353D01*
G37*
G36*
G01X368928D02*
X369113Y1053953D01*
X370143D01*
X370328Y1053353D01*
Y1053179D01*
X368928D01*
Y1053353D01*
G37*
G36*
G01X356011Y1050149D02*
X356196Y1050749D01*
X357226D01*
X357411Y1050149D01*
Y1049974D01*
X356011D01*
Y1050149D01*
G37*
G36*
G01X359735D02*
X359920Y1050749D01*
X360950D01*
X361135Y1050149D01*
Y1049975D01*
X359735D01*
Y1050149D01*
G37*
G36*
G01X363445D02*
X363630Y1050749D01*
X364660D01*
X364845Y1050149D01*
Y1049975D01*
X363445D01*
Y1050149D01*
G37*
G36*
G01X367145D02*
X367330Y1050749D01*
X368360D01*
X368545Y1050149D01*
Y1049975D01*
X367145D01*
Y1050149D01*
G37*
G36*
G01X356011D02*
X356196Y1050749D01*
X357226D01*
X357411Y1050149D01*
Y1049974D01*
X356011D01*
Y1050149D01*
G37*
G36*
G01X359735D02*
X359920Y1050749D01*
X360950D01*
X361135Y1050149D01*
Y1049975D01*
X359735D01*
Y1050149D01*
G37*
G36*
G01X363445D02*
X363630Y1050749D01*
X364660D01*
X364845Y1050149D01*
Y1049975D01*
X363445D01*
Y1050149D01*
G37*
G36*
G01X367145D02*
X367330Y1050749D01*
X368360D01*
X368545Y1050149D01*
Y1049975D01*
X367145D01*
Y1050149D01*
G37*
G36*
G01X361135Y1051755D02*
X360950Y1051155D01*
X359920D01*
X359735Y1051755D01*
Y1051930D01*
X361135D01*
Y1051755D01*
G37*
G36*
G01X364845D02*
X364660Y1051155D01*
X363630D01*
X363445Y1051755D01*
Y1051930D01*
X364845D01*
Y1051755D01*
G37*
G36*
G01X357378D02*
X357193Y1051155D01*
X356163D01*
X355978Y1051755D01*
Y1051930D01*
X357378D01*
Y1051755D01*
G37*
G36*
G01X368545D02*
X368360Y1051155D01*
X367330D01*
X367145Y1051755D01*
Y1051930D01*
X368545D01*
Y1051755D01*
G37*
G36*
G01X361135D02*
X360950Y1051155D01*
X359920D01*
X359735Y1051755D01*
Y1051930D01*
X361135D01*
Y1051755D01*
G37*
G36*
G01X364845D02*
X364660Y1051155D01*
X363630D01*
X363445Y1051755D01*
Y1051930D01*
X364845D01*
Y1051755D01*
G37*
G36*
G01X357378D02*
X357193Y1051155D01*
X356163D01*
X355978Y1051755D01*
Y1051930D01*
X357378D01*
Y1051755D01*
G37*
G36*
G01X368545D02*
X368360Y1051155D01*
X367330D01*
X367145Y1051755D01*
Y1051930D01*
X368545D01*
Y1051755D01*
G37*
G36*
G01X359261Y1048553D02*
X359076Y1047953D01*
X358046D01*
X357861Y1048553D01*
Y1048727D01*
X359261D01*
Y1048553D01*
G37*
G36*
G01X366628Y1048551D02*
X366443Y1047951D01*
X365413D01*
X365228Y1048551D01*
Y1048726D01*
X366628D01*
Y1048551D01*
G37*
G36*
G01X362928D02*
X362743Y1047951D01*
X361713D01*
X361528Y1048551D01*
Y1048726D01*
X362928D01*
Y1048551D01*
G37*
G36*
G01X370328D02*
X370143Y1047951D01*
X369113D01*
X368928Y1048551D01*
Y1048726D01*
X370328D01*
Y1048551D01*
G37*
G36*
G01X359261Y1048553D02*
X359076Y1047953D01*
X358046D01*
X357861Y1048553D01*
Y1048727D01*
X359261D01*
Y1048553D01*
G37*
G36*
G01X366628Y1048551D02*
X366443Y1047951D01*
X365413D01*
X365228Y1048551D01*
Y1048726D01*
X366628D01*
Y1048551D01*
G37*
G36*
G01X362928D02*
X362743Y1047951D01*
X361713D01*
X361528Y1048551D01*
Y1048726D01*
X362928D01*
Y1048551D01*
G37*
G36*
G01X370328D02*
X370143Y1047951D01*
X369113D01*
X368928Y1048551D01*
Y1048726D01*
X370328D01*
Y1048551D01*
G37*
G36*
G01X356035Y1062967D02*
X356220Y1063567D01*
X357250D01*
X357435Y1062967D01*
Y1062792D01*
X356035D01*
Y1062967D01*
G37*
G36*
G01X359688Y1062965D02*
X359873Y1063565D01*
X360903D01*
X361088Y1062965D01*
Y1062791D01*
X359688D01*
Y1062965D01*
G37*
G36*
G01X363435Y1062967D02*
X363620Y1063567D01*
X364650D01*
X364835Y1062967D01*
Y1062792D01*
X363435D01*
Y1062967D01*
G37*
G36*
G01X367145D02*
X367330Y1063567D01*
X368360D01*
X368545Y1062967D01*
Y1062792D01*
X367145D01*
Y1062967D01*
G37*
G36*
G01X356035D02*
X356220Y1063567D01*
X357250D01*
X357435Y1062967D01*
Y1062792D01*
X356035D01*
Y1062967D01*
G37*
G36*
G01X359688Y1062965D02*
X359873Y1063565D01*
X360903D01*
X361088Y1062965D01*
Y1062791D01*
X359688D01*
Y1062965D01*
G37*
G36*
G01X363435Y1062967D02*
X363620Y1063567D01*
X364650D01*
X364835Y1062967D01*
Y1062792D01*
X363435D01*
Y1062967D01*
G37*
G36*
G01X367145D02*
X367330Y1063567D01*
X368360D01*
X368545Y1062967D01*
Y1062792D01*
X367145D01*
Y1062967D01*
G37*
G36*
G01X359238Y1061369D02*
X359053Y1060769D01*
X358023D01*
X357838Y1061369D01*
Y1061543D01*
X359238D01*
Y1061369D01*
G37*
G36*
G01X366628D02*
X366443Y1060769D01*
X365413D01*
X365228Y1061369D01*
Y1061543D01*
X366628D01*
Y1061369D01*
G37*
G36*
G01X362985D02*
X362800Y1060769D01*
X361770D01*
X361585Y1061369D01*
Y1061544D01*
X362985D01*
Y1061369D01*
G37*
G36*
G01X370328D02*
X370143Y1060769D01*
X369113D01*
X368928Y1061369D01*
Y1061543D01*
X370328D01*
Y1061369D01*
G37*
G36*
G01X359238D02*
X359053Y1060769D01*
X358023D01*
X357838Y1061369D01*
Y1061543D01*
X359238D01*
Y1061369D01*
G37*
G36*
G01X366628D02*
X366443Y1060769D01*
X365413D01*
X365228Y1061369D01*
Y1061543D01*
X366628D01*
Y1061369D01*
G37*
G36*
G01X362985D02*
X362800Y1060769D01*
X361770D01*
X361585Y1061369D01*
Y1061544D01*
X362985D01*
Y1061369D01*
G37*
G36*
G01X370328D02*
X370143Y1060769D01*
X369113D01*
X368928Y1061369D01*
Y1061543D01*
X370328D01*
Y1061369D01*
G37*
G36*
G01X357378Y1070981D02*
X357193Y1070381D01*
X356163D01*
X355978Y1070981D01*
Y1071156D01*
X357378D01*
Y1070981D01*
G37*
G36*
G01X368545D02*
X368360Y1070381D01*
X367330D01*
X367145Y1070981D01*
Y1071156D01*
X368545D01*
Y1070981D01*
G37*
G36*
G01X361135D02*
X360950Y1070381D01*
X359920D01*
X359735Y1070981D01*
Y1071156D01*
X361135D01*
Y1070981D01*
G37*
G36*
G01X364845D02*
X364660Y1070381D01*
X363630D01*
X363445Y1070981D01*
Y1071156D01*
X364845D01*
Y1070981D01*
G37*
G36*
G01X357378D02*
X357193Y1070381D01*
X356163D01*
X355978Y1070981D01*
Y1071156D01*
X357378D01*
Y1070981D01*
G37*
G36*
G01X368545D02*
X368360Y1070381D01*
X367330D01*
X367145Y1070981D01*
Y1071156D01*
X368545D01*
Y1070981D01*
G37*
G36*
G01X361135D02*
X360950Y1070381D01*
X359920D01*
X359735Y1070981D01*
Y1071156D01*
X361135D01*
Y1070981D01*
G37*
G36*
G01X364845D02*
X364660Y1070381D01*
X363630D01*
X363445Y1070981D01*
Y1071156D01*
X364845D01*
Y1070981D01*
G37*
G36*
G01X359261Y1067779D02*
X359076Y1067179D01*
X358046D01*
X357861Y1067779D01*
Y1067953D01*
X359261D01*
Y1067779D01*
G37*
G36*
G01X366628Y1067777D02*
X366443Y1067177D01*
X365413D01*
X365228Y1067777D01*
Y1067952D01*
X366628D01*
Y1067777D01*
G37*
G36*
G01X362928D02*
X362743Y1067177D01*
X361713D01*
X361528Y1067777D01*
Y1067952D01*
X362928D01*
Y1067777D01*
G37*
G36*
G01X370338D02*
X370153Y1067177D01*
X369123D01*
X368938Y1067777D01*
Y1067952D01*
X370338D01*
Y1067777D01*
G37*
G36*
G01X359261Y1067779D02*
X359076Y1067179D01*
X358046D01*
X357861Y1067779D01*
Y1067953D01*
X359261D01*
Y1067779D01*
G37*
G36*
G01X366628Y1067777D02*
X366443Y1067177D01*
X365413D01*
X365228Y1067777D01*
Y1067952D01*
X366628D01*
Y1067777D01*
G37*
G36*
G01X362928D02*
X362743Y1067177D01*
X361713D01*
X361528Y1067777D01*
Y1067952D01*
X362928D01*
Y1067777D01*
G37*
G36*
G01X370338D02*
X370153Y1067177D01*
X369123D01*
X368938Y1067777D01*
Y1067952D01*
X370338D01*
Y1067777D01*
G37*
G36*
G01X357885Y1072579D02*
X358070Y1073179D01*
X359100D01*
X359285Y1072579D01*
Y1072404D01*
X357885D01*
Y1072579D01*
G37*
G36*
G01X361528D02*
X361713Y1073179D01*
X362743D01*
X362928Y1072579D01*
Y1072405D01*
X361528D01*
Y1072579D01*
G37*
G36*
G01X365228D02*
X365413Y1073179D01*
X366443D01*
X366628Y1072579D01*
Y1072405D01*
X365228D01*
Y1072579D01*
G37*
G36*
G01X354185D02*
X354370Y1073179D01*
X355400D01*
X355585Y1072579D01*
Y1072405D01*
X354185D01*
Y1072579D01*
G37*
G36*
G01X368928D02*
X369113Y1073179D01*
X370143D01*
X370328Y1072579D01*
Y1072405D01*
X368928D01*
Y1072579D01*
G37*
G36*
G01X357885D02*
X358070Y1073179D01*
X359100D01*
X359285Y1072579D01*
Y1072404D01*
X357885D01*
Y1072579D01*
G37*
G36*
G01X361528D02*
X361713Y1073179D01*
X362743D01*
X362928Y1072579D01*
Y1072405D01*
X361528D01*
Y1072579D01*
G37*
G36*
G01X365228D02*
X365413Y1073179D01*
X366443D01*
X366628Y1072579D01*
Y1072405D01*
X365228D01*
Y1072579D01*
G37*
G36*
G01X354185D02*
X354370Y1073179D01*
X355400D01*
X355585Y1072579D01*
Y1072405D01*
X354185D01*
Y1072579D01*
G37*
G36*
G01X368928D02*
X369113Y1073179D01*
X370143D01*
X370328Y1072579D01*
Y1072405D01*
X368928D01*
Y1072579D01*
G37*
G36*
G01X356011Y1069373D02*
X356196Y1069973D01*
X357226D01*
X357411Y1069373D01*
Y1069199D01*
X356011D01*
Y1069373D01*
G37*
G36*
G01X359735Y1069375D02*
X359920Y1069975D01*
X360950D01*
X361135Y1069375D01*
Y1069200D01*
X359735D01*
Y1069375D01*
G37*
G36*
G01X363445D02*
X363630Y1069975D01*
X364660D01*
X364845Y1069375D01*
Y1069200D01*
X363445D01*
Y1069375D01*
G37*
G36*
G01X367145D02*
X367330Y1069975D01*
X368360D01*
X368545Y1069375D01*
Y1069200D01*
X367145D01*
Y1069375D01*
G37*
G36*
G01X356011Y1069373D02*
X356196Y1069973D01*
X357226D01*
X357411Y1069373D01*
Y1069199D01*
X356011D01*
Y1069373D01*
G37*
G36*
G01X359735Y1069375D02*
X359920Y1069975D01*
X360950D01*
X361135Y1069375D01*
Y1069200D01*
X359735D01*
Y1069375D01*
G37*
G36*
G01X363445D02*
X363630Y1069975D01*
X364660D01*
X364845Y1069375D01*
Y1069200D01*
X363445D01*
Y1069375D01*
G37*
G36*
G01X367145D02*
X367330Y1069975D01*
X368360D01*
X368545Y1069375D01*
Y1069200D01*
X367145D01*
Y1069375D01*
G37*
G36*
G01X357435Y1064573D02*
X357250Y1063973D01*
X356220D01*
X356035Y1064573D01*
Y1064748D01*
X357435D01*
Y1064573D01*
G37*
G36*
G01X361135Y1064575D02*
X360950Y1063975D01*
X359920D01*
X359735Y1064575D01*
Y1064749D01*
X361135D01*
Y1064575D01*
G37*
G36*
G01X364835Y1064573D02*
X364650Y1063973D01*
X363620D01*
X363435Y1064573D01*
Y1064748D01*
X364835D01*
Y1064573D01*
G37*
G36*
G01X368545D02*
X368360Y1063973D01*
X367330D01*
X367145Y1064573D01*
Y1064748D01*
X368545D01*
Y1064573D01*
G37*
G36*
G01X357435D02*
X357250Y1063973D01*
X356220D01*
X356035Y1064573D01*
Y1064748D01*
X357435D01*
Y1064573D01*
G37*
G36*
G01X361135Y1064575D02*
X360950Y1063975D01*
X359920D01*
X359735Y1064575D01*
Y1064749D01*
X361135D01*
Y1064575D01*
G37*
G36*
G01X364835Y1064573D02*
X364650Y1063973D01*
X363620D01*
X363435Y1064573D01*
Y1064748D01*
X364835D01*
Y1064573D01*
G37*
G36*
G01X368545D02*
X368360Y1063973D01*
X367330D01*
X367145Y1064573D01*
Y1064748D01*
X368545D01*
Y1064573D01*
G37*
G36*
G01X357828Y1066171D02*
X358013Y1066771D01*
X359043D01*
X359228Y1066171D01*
Y1065996D01*
X357828D01*
Y1066171D01*
G37*
G36*
G01X365228D02*
X365413Y1066771D01*
X366443D01*
X366628Y1066171D01*
Y1065996D01*
X365228D01*
Y1066171D01*
G37*
G36*
G01X361561Y1066169D02*
X361746Y1066769D01*
X362776D01*
X362961Y1066169D01*
Y1065995D01*
X361561D01*
Y1066169D01*
G37*
G36*
G01X368930Y1066171D02*
X369115Y1066771D01*
X370145D01*
X370330Y1066171D01*
Y1065996D01*
X368930D01*
Y1066171D01*
G37*
G36*
G01X357828D02*
X358013Y1066771D01*
X359043D01*
X359228Y1066171D01*
Y1065996D01*
X357828D01*
Y1066171D01*
G37*
G36*
G01X365228D02*
X365413Y1066771D01*
X366443D01*
X366628Y1066171D01*
Y1065996D01*
X365228D01*
Y1066171D01*
G37*
G36*
G01X361561Y1066169D02*
X361746Y1066769D01*
X362776D01*
X362961Y1066169D01*
Y1065995D01*
X361561D01*
Y1066169D01*
G37*
G36*
G01X368930Y1066171D02*
X369115Y1066771D01*
X370145D01*
X370330Y1066171D01*
Y1065996D01*
X368930D01*
Y1066171D01*
G37*
G36*
G01X357838Y1078987D02*
X358023Y1079587D01*
X359053D01*
X359238Y1078987D01*
Y1078813D01*
X357838D01*
Y1078987D01*
G37*
G36*
G01X361538D02*
X361723Y1079587D01*
X362753D01*
X362938Y1078987D01*
Y1078812D01*
X361538D01*
Y1078987D01*
G37*
G36*
G01X365228D02*
X365413Y1079587D01*
X366443D01*
X366628Y1078987D01*
Y1078813D01*
X365228D01*
Y1078987D01*
G37*
G36*
G01X368928D02*
X369113Y1079587D01*
X370143D01*
X370328Y1078987D01*
Y1078813D01*
X368928D01*
Y1078987D01*
G37*
G36*
G01X357838D02*
X358023Y1079587D01*
X359053D01*
X359238Y1078987D01*
Y1078813D01*
X357838D01*
Y1078987D01*
G37*
G36*
G01X361538D02*
X361723Y1079587D01*
X362753D01*
X362938Y1078987D01*
Y1078812D01*
X361538D01*
Y1078987D01*
G37*
G36*
G01X365228D02*
X365413Y1079587D01*
X366443D01*
X366628Y1078987D01*
Y1078813D01*
X365228D01*
Y1078987D01*
G37*
G36*
G01X368928D02*
X369113Y1079587D01*
X370143D01*
X370328Y1078987D01*
Y1078813D01*
X368928D01*
Y1078987D01*
G37*
G36*
G01X355988Y1075783D02*
X356173Y1076383D01*
X357203D01*
X357388Y1075783D01*
Y1075609D01*
X355988D01*
Y1075783D01*
G37*
G36*
G01X359745D02*
X359930Y1076383D01*
X360960D01*
X361145Y1075783D01*
Y1075609D01*
X359745D01*
Y1075783D01*
G37*
G36*
G01X363445D02*
X363630Y1076383D01*
X364660D01*
X364845Y1075783D01*
Y1075609D01*
X363445D01*
Y1075783D01*
G37*
G36*
G01X367145D02*
X367330Y1076383D01*
X368360D01*
X368545Y1075783D01*
Y1075609D01*
X367145D01*
Y1075783D01*
G37*
G36*
G01X355988D02*
X356173Y1076383D01*
X357203D01*
X357388Y1075783D01*
Y1075609D01*
X355988D01*
Y1075783D01*
G37*
G36*
G01X359745D02*
X359930Y1076383D01*
X360960D01*
X361145Y1075783D01*
Y1075609D01*
X359745D01*
Y1075783D01*
G37*
G36*
G01X363445D02*
X363630Y1076383D01*
X364660D01*
X364845Y1075783D01*
Y1075609D01*
X363445D01*
Y1075783D01*
G37*
G36*
G01X367145D02*
X367330Y1076383D01*
X368360D01*
X368545Y1075783D01*
Y1075609D01*
X367145D01*
Y1075783D01*
G37*
G36*
G01X357435Y1077391D02*
X357250Y1076791D01*
X356220D01*
X356035Y1077391D01*
Y1077565D01*
X357435D01*
Y1077391D01*
G37*
G36*
G01X361112D02*
X360927Y1076791D01*
X359897D01*
X359712Y1077391D01*
Y1077566D01*
X361112D01*
Y1077391D01*
G37*
G36*
G01X364845D02*
X364660Y1076791D01*
X363630D01*
X363445Y1077391D01*
Y1077565D01*
X364845D01*
Y1077391D01*
G37*
G36*
G01X368545D02*
X368360Y1076791D01*
X367330D01*
X367145Y1077391D01*
Y1077565D01*
X368545D01*
Y1077391D01*
G37*
G36*
G01X357435D02*
X357250Y1076791D01*
X356220D01*
X356035Y1077391D01*
Y1077565D01*
X357435D01*
Y1077391D01*
G37*
G36*
G01X361112D02*
X360927Y1076791D01*
X359897D01*
X359712Y1077391D01*
Y1077566D01*
X361112D01*
Y1077391D01*
G37*
G36*
G01X364845D02*
X364660Y1076791D01*
X363630D01*
X363445Y1077391D01*
Y1077565D01*
X364845D01*
Y1077391D01*
G37*
G36*
G01X368545D02*
X368360Y1076791D01*
X367330D01*
X367145Y1077391D01*
Y1077565D01*
X368545D01*
Y1077391D01*
G37*
G36*
G01X359238Y1074187D02*
X359053Y1073587D01*
X358023D01*
X357838Y1074187D01*
Y1074362D01*
X359238D01*
Y1074187D01*
G37*
G36*
G01X366628D02*
X366443Y1073587D01*
X365413D01*
X365228Y1074187D01*
Y1074361D01*
X366628D01*
Y1074187D01*
G37*
G36*
G01X362928D02*
X362743Y1073587D01*
X361713D01*
X361528Y1074187D01*
Y1074361D01*
X362928D01*
Y1074187D01*
G37*
G36*
G01X355585D02*
X355400Y1073587D01*
X354370D01*
X354185Y1074187D01*
Y1074361D01*
X355585D01*
Y1074187D01*
G37*
G36*
G01X370328D02*
X370143Y1073587D01*
X369113D01*
X368928Y1074187D01*
Y1074361D01*
X370328D01*
Y1074187D01*
G37*
G36*
G01X359238D02*
X359053Y1073587D01*
X358023D01*
X357838Y1074187D01*
Y1074362D01*
X359238D01*
Y1074187D01*
G37*
G36*
G01X366628D02*
X366443Y1073587D01*
X365413D01*
X365228Y1074187D01*
Y1074361D01*
X366628D01*
Y1074187D01*
G37*
G36*
G01X362928D02*
X362743Y1073587D01*
X361713D01*
X361528Y1074187D01*
Y1074361D01*
X362928D01*
Y1074187D01*
G37*
G36*
G01X355585D02*
X355400Y1073587D01*
X354370D01*
X354185Y1074187D01*
Y1074361D01*
X355585D01*
Y1074187D01*
G37*
G36*
G01X370328D02*
X370143Y1073587D01*
X369113D01*
X368928Y1074187D01*
Y1074361D01*
X370328D01*
Y1074187D01*
G37*
G36*
G01X358426Y1094438D02*
X359038Y1094578D01*
X359553Y1093686D01*
X359126Y1093226D01*
X358975Y1093139D01*
X358275Y1094351D01*
X358426Y1094438D01*
G37*
G36*
G01X361528Y1091804D02*
X361713Y1092404D01*
X362743D01*
X362928Y1091804D01*
Y1091630D01*
X361528D01*
Y1091804D01*
G37*
G36*
G01X365228D02*
X365413Y1092404D01*
X366443D01*
X366628Y1091804D01*
Y1091630D01*
X365228D01*
Y1091804D01*
G37*
G36*
G01X368928D02*
X369113Y1092404D01*
X370143D01*
X370328Y1091804D01*
Y1091630D01*
X368928D01*
Y1091804D01*
G37*
G36*
G01X358426Y1094438D02*
X359038Y1094578D01*
X359553Y1093686D01*
X359126Y1093226D01*
X358975Y1093139D01*
X358275Y1094351D01*
X358426Y1094438D01*
G37*
G36*
G01X361528Y1091804D02*
X361713Y1092404D01*
X362743D01*
X362928Y1091804D01*
Y1091630D01*
X361528D01*
Y1091804D01*
G37*
G36*
G01X365228D02*
X365413Y1092404D01*
X366443D01*
X366628Y1091804D01*
Y1091630D01*
X365228D01*
Y1091804D01*
G37*
G36*
G01X368928D02*
X369113Y1092404D01*
X370143D01*
X370328Y1091804D01*
Y1091630D01*
X368928D01*
Y1091804D01*
G37*
G36*
G01X359735Y1088600D02*
X359920Y1089200D01*
X360950D01*
X361135Y1088600D01*
Y1088426D01*
X359735D01*
Y1088600D01*
G37*
G36*
G01X356575Y1091236D02*
X357187Y1091376D01*
X357702Y1090484D01*
X357275Y1090024D01*
X357124Y1089937D01*
X356424Y1091149D01*
X356575Y1091236D01*
G37*
G36*
G01X363445Y1088600D02*
X363630Y1089200D01*
X364660D01*
X364845Y1088600D01*
Y1088426D01*
X363445D01*
Y1088600D01*
G37*
G36*
G01X367145D02*
X367330Y1089200D01*
X368360D01*
X368545Y1088600D01*
Y1088426D01*
X367145D01*
Y1088600D01*
G37*
G36*
G01X354732Y1094427D02*
X355344Y1094567D01*
X355859Y1093675D01*
X355432Y1093215D01*
X355281Y1093128D01*
X354581Y1094340D01*
X354732Y1094427D01*
G37*
G36*
G01X359735Y1088600D02*
X359920Y1089200D01*
X360950D01*
X361135Y1088600D01*
Y1088426D01*
X359735D01*
Y1088600D01*
G37*
G36*
G01X356575Y1091236D02*
X357187Y1091376D01*
X357702Y1090484D01*
X357275Y1090024D01*
X357124Y1089937D01*
X356424Y1091149D01*
X356575Y1091236D01*
G37*
G36*
G01X363445Y1088600D02*
X363630Y1089200D01*
X364660D01*
X364845Y1088600D01*
Y1088426D01*
X363445D01*
Y1088600D01*
G37*
G36*
G01X367145D02*
X367330Y1089200D01*
X368360D01*
X368545Y1088600D01*
Y1088426D01*
X367145D01*
Y1088600D01*
G37*
G36*
G01X354732Y1094427D02*
X355344Y1094567D01*
X355859Y1093675D01*
X355432Y1093215D01*
X355281Y1093128D01*
X354581Y1094340D01*
X354732Y1094427D01*
G37*
G36*
G01X356847Y1093983D02*
X356235Y1093843D01*
X355720Y1094735D01*
X356147Y1095195D01*
X356298Y1095282D01*
X356998Y1094070D01*
X356847Y1093983D01*
G37*
G36*
G01X361135Y1090207D02*
X360950Y1089607D01*
X359920D01*
X359735Y1090207D01*
Y1090382D01*
X361135D01*
Y1090207D01*
G37*
G36*
G01X358693Y1090786D02*
X358081Y1090646D01*
X357566Y1091538D01*
X357993Y1091998D01*
X358144Y1092085D01*
X358844Y1090873D01*
X358693Y1090786D01*
G37*
G36*
G01X364845Y1090207D02*
X364660Y1089607D01*
X363630D01*
X363445Y1090207D01*
Y1090382D01*
X364845D01*
Y1090207D01*
G37*
G36*
G01X368545D02*
X368360Y1089607D01*
X367330D01*
X367145Y1090207D01*
Y1090382D01*
X368545D01*
Y1090207D01*
G37*
G36*
G01X356847Y1093983D02*
X356235Y1093843D01*
X355720Y1094735D01*
X356147Y1095195D01*
X356298Y1095282D01*
X356998Y1094070D01*
X356847Y1093983D01*
G37*
G36*
G01X361135Y1090207D02*
X360950Y1089607D01*
X359920D01*
X359735Y1090207D01*
Y1090382D01*
X361135D01*
Y1090207D01*
G37*
G36*
G01X358693Y1090786D02*
X358081Y1090646D01*
X357566Y1091538D01*
X357993Y1091998D01*
X358144Y1092085D01*
X358844Y1090873D01*
X358693Y1090786D01*
G37*
G36*
G01X364845Y1090207D02*
X364660Y1089607D01*
X363630D01*
X363445Y1090207D01*
Y1090382D01*
X364845D01*
Y1090207D01*
G37*
G36*
G01X368545D02*
X368360Y1089607D01*
X367330D01*
X367145Y1090207D01*
Y1090382D01*
X368545D01*
Y1090207D01*
G37*
G36*
G01X362928Y1087003D02*
X362743Y1086403D01*
X361713D01*
X361528Y1087003D01*
Y1087178D01*
X362928D01*
Y1087003D01*
G37*
G36*
G01X366628D02*
X366443Y1086403D01*
X365413D01*
X365228Y1087003D01*
Y1087178D01*
X366628D01*
Y1087003D01*
G37*
G36*
G01X359261Y1087005D02*
X359076Y1086405D01*
X358046D01*
X357861Y1087005D01*
Y1087179D01*
X359261D01*
Y1087005D01*
G37*
G36*
G01X356843Y1087582D02*
X356231Y1087442D01*
X355716Y1088334D01*
X356143Y1088794D01*
X356294Y1088881D01*
X356994Y1087669D01*
X356843Y1087582D01*
G37*
G36*
G01X370338Y1087003D02*
X370153Y1086403D01*
X369123D01*
X368938Y1087003D01*
Y1087178D01*
X370338D01*
Y1087003D01*
G37*
G36*
G01X362928D02*
X362743Y1086403D01*
X361713D01*
X361528Y1087003D01*
Y1087178D01*
X362928D01*
Y1087003D01*
G37*
G36*
G01X366628D02*
X366443Y1086403D01*
X365413D01*
X365228Y1087003D01*
Y1087178D01*
X366628D01*
Y1087003D01*
G37*
G36*
G01X359261Y1087005D02*
X359076Y1086405D01*
X358046D01*
X357861Y1087005D01*
Y1087179D01*
X359261D01*
Y1087005D01*
G37*
G36*
G01X356843Y1087582D02*
X356231Y1087442D01*
X355716Y1088334D01*
X356143Y1088794D01*
X356294Y1088881D01*
X356994Y1087669D01*
X356843Y1087582D01*
G37*
G36*
G01X370338Y1087003D02*
X370153Y1086403D01*
X369123D01*
X368938Y1087003D01*
Y1087178D01*
X370338D01*
Y1087003D01*
G37*
G36*
G01X361135Y1083799D02*
X360950Y1083199D01*
X359920D01*
X359735Y1083799D01*
Y1083974D01*
X361135D01*
Y1083799D01*
G37*
G36*
G01X364835D02*
X364650Y1083199D01*
X363620D01*
X363435Y1083799D01*
Y1083973D01*
X364835D01*
Y1083799D01*
G37*
G36*
G01X357435D02*
X357250Y1083199D01*
X356220D01*
X356035Y1083799D01*
Y1083973D01*
X357435D01*
Y1083799D01*
G37*
G36*
G01X368545D02*
X368360Y1083199D01*
X367330D01*
X367145Y1083799D01*
Y1083973D01*
X368545D01*
Y1083799D01*
G37*
G36*
G01X361135D02*
X360950Y1083199D01*
X359920D01*
X359735Y1083799D01*
Y1083974D01*
X361135D01*
Y1083799D01*
G37*
G36*
G01X364835D02*
X364650Y1083199D01*
X363620D01*
X363435Y1083799D01*
Y1083973D01*
X364835D01*
Y1083799D01*
G37*
G36*
G01X357435D02*
X357250Y1083199D01*
X356220D01*
X356035Y1083799D01*
Y1083973D01*
X357435D01*
Y1083799D01*
G37*
G36*
G01X368545D02*
X368360Y1083199D01*
X367330D01*
X367145Y1083799D01*
Y1083973D01*
X368545D01*
Y1083799D01*
G37*
G36*
G01X356035Y1082191D02*
X356220Y1082791D01*
X357250D01*
X357435Y1082191D01*
Y1082017D01*
X356035D01*
Y1082191D01*
G37*
G36*
G01X367145D02*
X367330Y1082791D01*
X368360D01*
X368545Y1082191D01*
Y1082017D01*
X367145D01*
Y1082191D01*
G37*
G36*
G01X359688D02*
X359873Y1082791D01*
X360903D01*
X361088Y1082191D01*
Y1082016D01*
X359688D01*
Y1082191D01*
G37*
G36*
G01X363435D02*
X363620Y1082791D01*
X364650D01*
X364835Y1082191D01*
Y1082017D01*
X363435D01*
Y1082191D01*
G37*
G36*
G01X356035D02*
X356220Y1082791D01*
X357250D01*
X357435Y1082191D01*
Y1082017D01*
X356035D01*
Y1082191D01*
G37*
G36*
G01X367145D02*
X367330Y1082791D01*
X368360D01*
X368545Y1082191D01*
Y1082017D01*
X367145D01*
Y1082191D01*
G37*
G36*
G01X359688D02*
X359873Y1082791D01*
X360903D01*
X361088Y1082191D01*
Y1082016D01*
X359688D01*
Y1082191D01*
G37*
G36*
G01X363435D02*
X363620Y1082791D01*
X364650D01*
X364835Y1082191D01*
Y1082017D01*
X363435D01*
Y1082191D01*
G37*
G36*
G01X365228Y1085396D02*
X365413Y1085996D01*
X366443D01*
X366628Y1085396D01*
Y1085222D01*
X365228D01*
Y1085396D01*
G37*
G36*
G01X361561Y1085395D02*
X361746Y1085995D01*
X362776D01*
X362961Y1085395D01*
Y1085220D01*
X361561D01*
Y1085395D01*
G37*
G36*
G01X357828Y1085396D02*
X358013Y1085996D01*
X359043D01*
X359228Y1085396D01*
Y1085221D01*
X357828D01*
Y1085396D01*
G37*
G36*
G01X354729Y1088022D02*
X355341Y1088162D01*
X355856Y1087270D01*
X355429Y1086810D01*
X355278Y1086723D01*
X354578Y1087935D01*
X354729Y1088022D01*
G37*
G36*
G01X368930Y1085396D02*
X369115Y1085996D01*
X370145D01*
X370330Y1085396D01*
Y1085221D01*
X368930D01*
Y1085396D01*
G37*
G36*
G01X365228D02*
X365413Y1085996D01*
X366443D01*
X366628Y1085396D01*
Y1085222D01*
X365228D01*
Y1085396D01*
G37*
G36*
G01X361561Y1085395D02*
X361746Y1085995D01*
X362776D01*
X362961Y1085395D01*
Y1085220D01*
X361561D01*
Y1085395D01*
G37*
G36*
G01X357828Y1085396D02*
X358013Y1085996D01*
X359043D01*
X359228Y1085396D01*
Y1085221D01*
X357828D01*
Y1085396D01*
G37*
G36*
G01X354729Y1088022D02*
X355341Y1088162D01*
X355856Y1087270D01*
X355429Y1086810D01*
X355278Y1086723D01*
X354578Y1087935D01*
X354729Y1088022D01*
G37*
G36*
G01X368930Y1085396D02*
X369115Y1085996D01*
X370145D01*
X370330Y1085396D01*
Y1085221D01*
X368930D01*
Y1085396D01*
G37*
G36*
G01X359238Y1080595D02*
X359053Y1079995D01*
X358023D01*
X357838Y1080595D01*
Y1080769D01*
X359238D01*
Y1080595D01*
G37*
G36*
G01X366628D02*
X366443Y1079995D01*
X365413D01*
X365228Y1080595D01*
Y1080769D01*
X366628D01*
Y1080595D01*
G37*
G36*
G01X362985D02*
X362800Y1079995D01*
X361770D01*
X361585Y1080595D01*
Y1080770D01*
X362985D01*
Y1080595D01*
G37*
G36*
G01X370328D02*
X370143Y1079995D01*
X369113D01*
X368928Y1080595D01*
Y1080769D01*
X370328D01*
Y1080595D01*
G37*
G36*
G01X359238D02*
X359053Y1079995D01*
X358023D01*
X357838Y1080595D01*
Y1080769D01*
X359238D01*
Y1080595D01*
G37*
G36*
G01X366628D02*
X366443Y1079995D01*
X365413D01*
X365228Y1080595D01*
Y1080769D01*
X366628D01*
Y1080595D01*
G37*
G36*
G01X362985D02*
X362800Y1079995D01*
X361770D01*
X361585Y1080595D01*
Y1080770D01*
X362985D01*
Y1080595D01*
G37*
G36*
G01X370328D02*
X370143Y1079995D01*
X369113D01*
X368928Y1080595D01*
Y1080769D01*
X370328D01*
Y1080595D01*
G37*
G36*
G01X356579Y1097635D02*
X357191Y1097775D01*
X357706Y1096883D01*
X357279Y1096423D01*
X357128Y1096336D01*
X356428Y1097548D01*
X356579Y1097635D01*
G37*
G36*
G01D02*
X357191Y1097775D01*
X357706Y1096883D01*
X357279Y1096423D01*
X357128Y1096336D01*
X356428Y1097548D01*
X356579Y1097635D01*
G37*
G36*
G01X354729Y1100839D02*
X355341Y1100979D01*
X355856Y1100087D01*
X355429Y1099627D01*
X355278Y1099540D01*
X354578Y1100752D01*
X354729Y1100839D01*
G37*
G36*
G01X373595Y887431D02*
X373410Y886831D01*
X372380D01*
X372195Y887431D01*
Y887605D01*
X373595D01*
Y887431D01*
G37*
G36*
G01X375343Y889214D02*
X375770Y888754D01*
X375255Y887862D01*
X374643Y888002D01*
X374492Y888089D01*
X375192Y889301D01*
X375343Y889214D01*
G37*
G36*
G01X373595Y887431D02*
X373410Y886831D01*
X372380D01*
X372195Y887431D01*
Y887605D01*
X373595D01*
Y887431D01*
G37*
G36*
G01X375343Y889214D02*
X375770Y888754D01*
X375255Y887862D01*
X374643Y888002D01*
X374492Y888089D01*
X375192Y889301D01*
X375343Y889214D01*
G37*
G36*
G01X372228Y905049D02*
X372413Y905649D01*
X373443D01*
X373628Y905049D01*
Y904874D01*
X372228D01*
Y905049D01*
G37*
G36*
G01D02*
X372413Y905649D01*
X373443D01*
X373628Y905049D01*
Y904874D01*
X372228D01*
Y905049D01*
G37*
G36*
G01X373595Y906657D02*
X373410Y906057D01*
X372380D01*
X372195Y906657D01*
Y906831D01*
X373595D01*
Y906657D01*
G37*
G36*
G01D02*
X373410Y906057D01*
X372380D01*
X372195Y906657D01*
Y906831D01*
X373595D01*
Y906657D01*
G37*
G36*
G01Y925883D02*
X373410Y925283D01*
X372380D01*
X372195Y925883D01*
Y926057D01*
X373595D01*
Y925883D01*
G37*
G36*
G01D02*
X373410Y925283D01*
X372380D01*
X372195Y925883D01*
Y926057D01*
X373595D01*
Y925883D01*
G37*
G36*
G01X372228Y924275D02*
X372413Y924875D01*
X373443D01*
X373628Y924275D01*
Y924100D01*
X372228D01*
Y924275D01*
G37*
G36*
G01D02*
X372413Y924875D01*
X373443D01*
X373628Y924275D01*
Y924100D01*
X372228D01*
Y924275D01*
G37*
G36*
G01X374112Y946705D02*
X374297Y947305D01*
X375327D01*
X375512Y946705D01*
Y946531D01*
X374112D01*
Y946705D01*
G37*
G36*
G01D02*
X374297Y947305D01*
X375327D01*
X375512Y946705D01*
Y946531D01*
X374112D01*
Y946705D01*
G37*
G36*
G01X377295Y945107D02*
X377110Y944507D01*
X376080D01*
X375895Y945107D01*
Y945282D01*
X377295D01*
Y945107D01*
G37*
G36*
G01X373595D02*
X373410Y944507D01*
X372380D01*
X372195Y945107D01*
Y945282D01*
X373595D01*
Y945107D01*
G37*
G36*
G01X377295D02*
X377110Y944507D01*
X376080D01*
X375895Y945107D01*
Y945282D01*
X377295D01*
Y945107D01*
G37*
G36*
G01X373595D02*
X373410Y944507D01*
X372380D01*
X372195Y945107D01*
Y945282D01*
X373595D01*
Y945107D01*
G37*
G36*
G01X372228Y962725D02*
X372413Y963325D01*
X373443D01*
X373628Y962725D01*
Y962551D01*
X372228D01*
Y962725D01*
G37*
G36*
G01D02*
X372413Y963325D01*
X373443D01*
X373628Y962725D01*
Y962551D01*
X372228D01*
Y962725D01*
G37*
G36*
G01X373605Y951517D02*
X373420Y950917D01*
X372390D01*
X372205Y951517D01*
Y951692D01*
X373605D01*
Y951517D01*
G37*
G36*
G01X377295D02*
X377110Y950917D01*
X376080D01*
X375895Y951517D01*
Y951691D01*
X377295D01*
Y951517D01*
G37*
G36*
G01X373605D02*
X373420Y950917D01*
X372390D01*
X372205Y951517D01*
Y951692D01*
X373605D01*
Y951517D01*
G37*
G36*
G01X377295D02*
X377110Y950917D01*
X376080D01*
X375895Y951517D01*
Y951691D01*
X377295D01*
Y951517D01*
G37*
G36*
G01X373595Y964333D02*
X373410Y963733D01*
X372380D01*
X372195Y964333D01*
Y964508D01*
X373595D01*
Y964333D01*
G37*
G36*
G01D02*
X373410Y963733D01*
X372380D01*
X372195Y964333D01*
Y964508D01*
X373595D01*
Y964333D01*
G37*
G36*
G01X373628Y977151D02*
X373443Y976551D01*
X372413D01*
X372228Y977151D01*
Y977326D01*
X373628D01*
Y977151D01*
G37*
G36*
G01X377305D02*
X377120Y976551D01*
X376090D01*
X375905Y977151D01*
Y977325D01*
X377305D01*
Y977151D01*
G37*
G36*
G01X381005D02*
X380820Y976551D01*
X379790D01*
X379605Y977151D01*
Y977326D01*
X381005D01*
Y977151D01*
G37*
G36*
G01X373628D02*
X373443Y976551D01*
X372413D01*
X372228Y977151D01*
Y977326D01*
X373628D01*
Y977151D01*
G37*
G36*
G01X377305D02*
X377120Y976551D01*
X376090D01*
X375905Y977151D01*
Y977325D01*
X377305D01*
Y977151D01*
G37*
G36*
G01X381005D02*
X380820Y976551D01*
X379790D01*
X379605Y977151D01*
Y977326D01*
X381005D01*
Y977151D01*
G37*
G36*
G01X384705D02*
X384520Y976551D01*
X383490D01*
X383305Y977151D01*
Y977325D01*
X384705D01*
Y977151D01*
G37*
G36*
G01D02*
X384520Y976551D01*
X383490D01*
X383305Y977151D01*
Y977325D01*
X384705D01*
Y977151D01*
G37*
G36*
G01X375905Y975543D02*
X376090Y976143D01*
X377120D01*
X377305Y975543D01*
Y975369D01*
X375905D01*
Y975543D01*
G37*
G36*
G01X372195D02*
X372380Y976143D01*
X373410D01*
X373595Y975543D01*
Y975369D01*
X372195D01*
Y975543D01*
G37*
G36*
G01X379652D02*
X379837Y976143D01*
X380867D01*
X381052Y975543D01*
Y975368D01*
X379652D01*
Y975543D01*
G37*
G36*
G01X375905D02*
X376090Y976143D01*
X377120D01*
X377305Y975543D01*
Y975369D01*
X375905D01*
Y975543D01*
G37*
G36*
G01X372195D02*
X372380Y976143D01*
X373410D01*
X373595Y975543D01*
Y975369D01*
X372195D01*
Y975543D01*
G37*
G36*
G01X379652D02*
X379837Y976143D01*
X380867D01*
X381052Y975543D01*
Y975368D01*
X379652D01*
Y975543D01*
G37*
G36*
G01X383305D02*
X383490Y976143D01*
X384520D01*
X384705Y975543D01*
Y975369D01*
X383305D01*
Y975543D01*
G37*
G36*
G01D02*
X383490Y976143D01*
X384520D01*
X384705Y975543D01*
Y975369D01*
X383305D01*
Y975543D01*
G37*
G36*
G01X377779Y978747D02*
X377964Y979347D01*
X378994D01*
X379179Y978747D01*
Y978573D01*
X377779D01*
Y978747D01*
G37*
G36*
G01X374102Y978749D02*
X374287Y979349D01*
X375317D01*
X375502Y978749D01*
Y978574D01*
X374102D01*
Y978749D01*
G37*
G36*
G01X377779Y978747D02*
X377964Y979347D01*
X378994D01*
X379179Y978747D01*
Y978573D01*
X377779D01*
Y978747D01*
G37*
G36*
G01X374102Y978749D02*
X374287Y979349D01*
X375317D01*
X375502Y978749D01*
Y978574D01*
X374102D01*
Y978749D01*
G37*
G36*
G01X381512D02*
X381697Y979349D01*
X382727D01*
X382912Y978749D01*
Y978574D01*
X381512D01*
Y978749D01*
G37*
G36*
G01X385179Y978747D02*
X385364Y979347D01*
X386394D01*
X386579Y978747D01*
Y978573D01*
X385179D01*
Y978747D01*
G37*
G36*
G01X381512Y978749D02*
X381697Y979349D01*
X382727D01*
X382912Y978749D01*
Y978574D01*
X381512D01*
Y978749D01*
G37*
G36*
G01X385179Y978747D02*
X385364Y979347D01*
X386394D01*
X386579Y978747D01*
Y978573D01*
X385179D01*
Y978747D01*
G37*
G36*
G01X379155Y973947D02*
X378970Y973347D01*
X377940D01*
X377755Y973947D01*
Y974122D01*
X379155D01*
Y973947D01*
G37*
G36*
G01X375512D02*
X375327Y973347D01*
X374297D01*
X374112Y973947D01*
Y974121D01*
X375512D01*
Y973947D01*
G37*
G36*
G01X379155D02*
X378970Y973347D01*
X377940D01*
X377755Y973947D01*
Y974122D01*
X379155D01*
Y973947D01*
G37*
G36*
G01X375512D02*
X375327Y973347D01*
X374297D01*
X374112Y973947D01*
Y974121D01*
X375512D01*
Y973947D01*
G37*
G36*
G01X382902D02*
X382717Y973347D01*
X381687D01*
X381502Y973947D01*
Y974121D01*
X382902D01*
Y973947D01*
G37*
G36*
G01X386555D02*
X386370Y973347D01*
X385340D01*
X385155Y973947D01*
Y974122D01*
X386555D01*
Y973947D01*
G37*
G36*
G01X382902D02*
X382717Y973347D01*
X381687D01*
X381502Y973947D01*
Y974121D01*
X382902D01*
Y973947D01*
G37*
G36*
G01X386555D02*
X386370Y973347D01*
X385340D01*
X385155Y973947D01*
Y974122D01*
X386555D01*
Y973947D01*
G37*
G36*
G01X374112Y972339D02*
X374297Y972939D01*
X375327D01*
X375512Y972339D01*
Y972165D01*
X374112D01*
Y972339D01*
G37*
G36*
G01X376492Y971771D02*
X377104Y971911D01*
X377619Y971019D01*
X377192Y970559D01*
X377041Y970472D01*
X376341Y971684D01*
X376492Y971771D01*
G37*
G36*
G01X372343Y970521D02*
X371916Y970981D01*
X372431Y971873D01*
X373043Y971733D01*
X373194Y971646D01*
X372494Y970434D01*
X372343Y970521D01*
G37*
G36*
G01X374112Y972339D02*
X374297Y972939D01*
X375327D01*
X375512Y972339D01*
Y972165D01*
X374112D01*
Y972339D01*
G37*
G36*
G01X376492Y971771D02*
X377104Y971911D01*
X377619Y971019D01*
X377192Y970559D01*
X377041Y970472D01*
X376341Y971684D01*
X376492Y971771D01*
G37*
G36*
G01X372343Y970521D02*
X371916Y970981D01*
X372431Y971873D01*
X373043Y971733D01*
X373194Y971646D01*
X372494Y970434D01*
X372343Y970521D01*
G37*
G36*
G01X373497Y969329D02*
X373924Y968869D01*
X373409Y967977D01*
X372797Y968117D01*
X372646Y968204D01*
X373346Y969416D01*
X373497Y969329D01*
G37*
G36*
G01X376743Y968145D02*
X376131Y968005D01*
X375616Y968897D01*
X376043Y969357D01*
X376194Y969444D01*
X376894Y968232D01*
X376743Y968145D01*
G37*
G36*
G01X373497Y969329D02*
X373924Y968869D01*
X373409Y967977D01*
X372797Y968117D01*
X372646Y968204D01*
X373346Y969416D01*
X373497Y969329D01*
G37*
G36*
G01X376743Y968145D02*
X376131Y968005D01*
X375616Y968897D01*
X376043Y969357D01*
X376194Y969444D01*
X376894Y968232D01*
X376743Y968145D01*
G37*
G36*
G01X374027Y997283D02*
X373842Y996683D01*
X372812D01*
X372627Y997283D01*
Y997458D01*
X374027D01*
Y997283D01*
G37*
G36*
G01X377728D02*
X377543Y996683D01*
X376513D01*
X376328Y997283D01*
Y997458D01*
X377728D01*
Y997283D01*
G37*
G36*
G01X371647Y997852D02*
X371035Y997712D01*
X370520Y998604D01*
X370947Y999064D01*
X371098Y999151D01*
X371798Y997939D01*
X371647Y997852D01*
G37*
G36*
G01X374027Y997283D02*
X373842Y996683D01*
X372812D01*
X372627Y997283D01*
Y997458D01*
X374027D01*
Y997283D01*
G37*
G36*
G01X377728D02*
X377543Y996683D01*
X376513D01*
X376328Y997283D01*
Y997458D01*
X377728D01*
Y997283D01*
G37*
G36*
G01X371647Y997852D02*
X371035Y997712D01*
X370520Y998604D01*
X370947Y999064D01*
X371098Y999151D01*
X371798Y997939D01*
X371647Y997852D01*
G37*
G36*
G01X370845Y1005289D02*
X371030Y1005889D01*
X372060D01*
X372245Y1005289D01*
Y1005115D01*
X370845D01*
Y1005289D01*
G37*
G36*
G01D02*
X371030Y1005889D01*
X372060D01*
X372245Y1005289D01*
Y1005115D01*
X370845D01*
Y1005289D01*
G37*
G36*
G01X374544Y998881D02*
X374729Y999481D01*
X375759D01*
X375944Y998881D01*
Y998706D01*
X374544D01*
Y998881D01*
G37*
G36*
G01X371397Y1001478D02*
X372009Y1001618D01*
X372524Y1000726D01*
X372097Y1000266D01*
X371946Y1000179D01*
X371246Y1001391D01*
X371397Y1001478D01*
G37*
G36*
G01X374544Y998881D02*
X374729Y999481D01*
X375759D01*
X375944Y998881D01*
Y998706D01*
X374544D01*
Y998881D01*
G37*
G36*
G01X371397Y1001478D02*
X372009Y1001618D01*
X372524Y1000726D01*
X372097Y1000266D01*
X371946Y1000179D01*
X371246Y1001391D01*
X371397Y1001478D01*
G37*
G36*
G01X375912Y1000489D02*
X375727Y999889D01*
X374697D01*
X374512Y1000489D01*
Y1000663D01*
X375912D01*
Y1000489D01*
G37*
G36*
G01D02*
X375727Y999889D01*
X374697D01*
X374512Y1000489D01*
Y1000663D01*
X375912D01*
Y1000489D01*
G37*
G36*
G01X370812Y1011697D02*
X370997Y1012297D01*
X372027D01*
X372212Y1011697D01*
Y1011522D01*
X370812D01*
Y1011697D01*
G37*
G36*
G01X374545D02*
X374730Y1012297D01*
X375760D01*
X375945Y1011697D01*
Y1011523D01*
X374545D01*
Y1011697D01*
G37*
G36*
G01X370812D02*
X370997Y1012297D01*
X372027D01*
X372212Y1011697D01*
Y1011522D01*
X370812D01*
Y1011697D01*
G37*
G36*
G01X374545D02*
X374730Y1012297D01*
X375760D01*
X375945Y1011697D01*
Y1011523D01*
X374545D01*
Y1011697D01*
G37*
G36*
G01X374038Y1010101D02*
X373853Y1009501D01*
X372823D01*
X372638Y1010101D01*
Y1010276D01*
X374038D01*
Y1010101D01*
G37*
G36*
G01X377728D02*
X377543Y1009501D01*
X376513D01*
X376328Y1010101D01*
Y1010275D01*
X377728D01*
Y1010101D01*
G37*
G36*
G01X374038D02*
X373853Y1009501D01*
X372823D01*
X372638Y1010101D01*
Y1010276D01*
X374038D01*
Y1010101D01*
G37*
G36*
G01X377728D02*
X377543Y1009501D01*
X376513D01*
X376328Y1010101D01*
Y1010275D01*
X377728D01*
Y1010101D01*
G37*
G36*
G01X375945Y1006897D02*
X375760Y1006297D01*
X374730D01*
X374545Y1006897D01*
Y1007071D01*
X375945D01*
Y1006897D01*
G37*
G36*
G01X372212D02*
X372027Y1006297D01*
X370997D01*
X370812Y1006897D01*
Y1007072D01*
X372212D01*
Y1006897D01*
G37*
G36*
G01X375945D02*
X375760Y1006297D01*
X374730D01*
X374545Y1006897D01*
Y1007071D01*
X375945D01*
Y1006897D01*
G37*
G36*
G01X372212D02*
X372027Y1006297D01*
X370997D01*
X370812Y1006897D01*
Y1007072D01*
X372212D01*
Y1006897D01*
G37*
G36*
G01X372235Y1019715D02*
X372050Y1019115D01*
X371020D01*
X370835Y1019715D01*
Y1019889D01*
X372235D01*
Y1019715D01*
G37*
G36*
G01D02*
X372050Y1019115D01*
X371020D01*
X370835Y1019715D01*
Y1019889D01*
X372235D01*
Y1019715D01*
G37*
G36*
G01X374061Y1016509D02*
X373876Y1015909D01*
X372846D01*
X372661Y1016509D01*
Y1016684D01*
X374061D01*
Y1016509D01*
G37*
G36*
G01X375782Y1018303D02*
X376209Y1017843D01*
X375694Y1016951D01*
X375082Y1017091D01*
X374931Y1017178D01*
X375631Y1018390D01*
X375782Y1018303D01*
G37*
G36*
G01X374061Y1016509D02*
X373876Y1015909D01*
X372846D01*
X372661Y1016509D01*
Y1016684D01*
X374061D01*
Y1016509D01*
G37*
G36*
G01X375782Y1018303D02*
X376209Y1017843D01*
X375694Y1016951D01*
X375082Y1017091D01*
X374931Y1017178D01*
X375631Y1018390D01*
X375782Y1018303D01*
G37*
G36*
G01X370835Y1018105D02*
X371020Y1018705D01*
X372050D01*
X372235Y1018105D01*
Y1017931D01*
X370835D01*
Y1018105D01*
G37*
G36*
G01X374626Y1019491D02*
X374199Y1019951D01*
X374714Y1020843D01*
X375326Y1020703D01*
X375477Y1020616D01*
X374777Y1019404D01*
X374626Y1019491D01*
G37*
G36*
G01X370835Y1018105D02*
X371020Y1018705D01*
X372050D01*
X372235Y1018105D01*
Y1017931D01*
X370835D01*
Y1018105D01*
G37*
G36*
G01X374626Y1019491D02*
X374199Y1019951D01*
X374714Y1020843D01*
X375326Y1020703D01*
X375477Y1020616D01*
X374777Y1019404D01*
X374626Y1019491D01*
G37*
G36*
G01X372694Y1027719D02*
X372879Y1028319D01*
X373909D01*
X374094Y1027719D01*
Y1027545D01*
X372694D01*
Y1027719D01*
G37*
G36*
G01D02*
X372879Y1028319D01*
X373909D01*
X374094Y1027719D01*
Y1027545D01*
X372694D01*
Y1027719D01*
G37*
G36*
G01X372211Y1026123D02*
X372026Y1025523D01*
X370996D01*
X370811Y1026123D01*
Y1026297D01*
X372211D01*
Y1026123D01*
G37*
G36*
G01D02*
X372026Y1025523D01*
X370996D01*
X370811Y1026123D01*
Y1026297D01*
X372211D01*
Y1026123D01*
G37*
G36*
G01X375945Y1032531D02*
X375760Y1031931D01*
X374730D01*
X374545Y1032531D01*
Y1032705D01*
X375945D01*
Y1032531D01*
G37*
G36*
G01X372245D02*
X372060Y1031931D01*
X371030D01*
X370845Y1032531D01*
Y1032705D01*
X372245D01*
Y1032531D01*
G37*
G36*
G01X375945D02*
X375760Y1031931D01*
X374730D01*
X374545Y1032531D01*
Y1032705D01*
X375945D01*
Y1032531D01*
G37*
G36*
G01X372245D02*
X372060Y1031931D01*
X371030D01*
X370845Y1032531D01*
Y1032705D01*
X372245D01*
Y1032531D01*
G37*
G36*
G01X372628Y1034127D02*
X372813Y1034727D01*
X373843D01*
X374028Y1034127D01*
Y1033953D01*
X372628D01*
Y1034127D01*
G37*
G36*
G01X376328D02*
X376513Y1034727D01*
X377543D01*
X377728Y1034127D01*
Y1033953D01*
X376328D01*
Y1034127D01*
G37*
G36*
G01X372628D02*
X372813Y1034727D01*
X373843D01*
X374028Y1034127D01*
Y1033953D01*
X372628D01*
Y1034127D01*
G37*
G36*
G01X376328D02*
X376513Y1034727D01*
X377543D01*
X377728Y1034127D01*
Y1033953D01*
X376328D01*
Y1034127D01*
G37*
G36*
G01X374545Y1030923D02*
X374730Y1031523D01*
X375760D01*
X375945Y1030923D01*
Y1030749D01*
X374545D01*
Y1030923D01*
G37*
G36*
G01X370845D02*
X371030Y1031523D01*
X372060D01*
X372245Y1030923D01*
Y1030749D01*
X370845D01*
Y1030923D01*
G37*
G36*
G01X374545D02*
X374730Y1031523D01*
X375760D01*
X375945Y1030923D01*
Y1030749D01*
X374545D01*
Y1030923D01*
G37*
G36*
G01X370845D02*
X371030Y1031523D01*
X372060D01*
X372245Y1030923D01*
Y1030749D01*
X370845D01*
Y1030923D01*
G37*
G36*
G01X370798Y1037331D02*
X370983Y1037931D01*
X372013D01*
X372198Y1037331D01*
Y1037156D01*
X370798D01*
Y1037331D01*
G37*
G36*
G01D02*
X370983Y1037931D01*
X372013D01*
X372198Y1037331D01*
Y1037156D01*
X370798D01*
Y1037331D01*
G37*
G36*
G01X372235Y1038941D02*
X372050Y1038341D01*
X371020D01*
X370835Y1038941D01*
Y1039115D01*
X372235D01*
Y1038941D01*
G37*
G36*
G01D02*
X372050Y1038341D01*
X371020D01*
X370835Y1038941D01*
Y1039115D01*
X372235D01*
Y1038941D01*
G37*
G36*
G01X374075Y1035737D02*
X373890Y1035137D01*
X372860D01*
X372675Y1035737D01*
Y1035911D01*
X374075D01*
Y1035737D01*
G37*
G36*
G01D02*
X373890Y1035137D01*
X372860D01*
X372675Y1035737D01*
Y1035911D01*
X374075D01*
Y1035737D01*
G37*
G36*
G01X370845Y1043741D02*
X371030Y1044341D01*
X372060D01*
X372245Y1043741D01*
Y1043566D01*
X370845D01*
Y1043741D01*
G37*
G36*
G01D02*
X371030Y1044341D01*
X372060D01*
X372245Y1043741D01*
Y1043566D01*
X370845D01*
Y1043741D01*
G37*
G36*
G01X374535Y1056557D02*
X374720Y1057157D01*
X375750D01*
X375935Y1056557D01*
Y1056383D01*
X374535D01*
Y1056557D01*
G37*
G36*
G01X370835D02*
X371020Y1057157D01*
X372050D01*
X372235Y1056557D01*
Y1056382D01*
X370835D01*
Y1056557D01*
G37*
G36*
G01X374535D02*
X374720Y1057157D01*
X375750D01*
X375935Y1056557D01*
Y1056383D01*
X374535D01*
Y1056557D01*
G37*
G36*
G01X370835D02*
X371020Y1057157D01*
X372050D01*
X372235Y1056557D01*
Y1056382D01*
X370835D01*
Y1056557D01*
G37*
G36*
G01X372235Y1058165D02*
X372050Y1057565D01*
X371020D01*
X370835Y1058165D01*
Y1058340D01*
X372235D01*
Y1058165D01*
G37*
G36*
G01X375878D02*
X375693Y1057565D01*
X374663D01*
X374478Y1058165D01*
Y1058339D01*
X375878D01*
Y1058165D01*
G37*
G36*
G01X372235D02*
X372050Y1057565D01*
X371020D01*
X370835Y1058165D01*
Y1058340D01*
X372235D01*
Y1058165D01*
G37*
G36*
G01X375878D02*
X375693Y1057565D01*
X374663D01*
X374478Y1058165D01*
Y1058339D01*
X375878D01*
Y1058165D01*
G37*
G36*
G01X374061Y1054961D02*
X373876Y1054361D01*
X372846D01*
X372661Y1054961D01*
Y1055136D01*
X374061D01*
Y1054961D01*
G37*
G36*
G01D02*
X373876Y1054361D01*
X372846D01*
X372661Y1054961D01*
Y1055136D01*
X374061D01*
Y1054961D01*
G37*
G36*
G01X372628Y1053353D02*
X372813Y1053953D01*
X373843D01*
X374028Y1053353D01*
Y1053179D01*
X372628D01*
Y1053353D01*
G37*
G36*
G01D02*
X372813Y1053953D01*
X373843D01*
X374028Y1053353D01*
Y1053179D01*
X372628D01*
Y1053353D01*
G37*
G36*
G01X370845Y1050149D02*
X371030Y1050749D01*
X372060D01*
X372245Y1050149D01*
Y1049975D01*
X370845D01*
Y1050149D01*
G37*
G36*
G01D02*
X371030Y1050749D01*
X372060D01*
X372245Y1050149D01*
Y1049975D01*
X370845D01*
Y1050149D01*
G37*
G36*
G01X372245Y1051755D02*
X372060Y1051155D01*
X371030D01*
X370845Y1051755D01*
Y1051930D01*
X372245D01*
Y1051755D01*
G37*
G36*
G01D02*
X372060Y1051155D01*
X371030D01*
X370845Y1051755D01*
Y1051930D01*
X372245D01*
Y1051755D01*
G37*
G36*
G01X370845Y1062967D02*
X371030Y1063567D01*
X372060D01*
X372245Y1062967D01*
Y1062792D01*
X370845D01*
Y1062967D01*
G37*
G36*
G01D02*
X371030Y1063567D01*
X372060D01*
X372245Y1062967D01*
Y1062792D01*
X370845D01*
Y1062967D01*
G37*
G36*
G01X372245Y1070981D02*
X372060Y1070381D01*
X371030D01*
X370845Y1070981D01*
Y1071156D01*
X372245D01*
Y1070981D01*
G37*
G36*
G01D02*
X372060Y1070381D01*
X371030D01*
X370845Y1070981D01*
Y1071156D01*
X372245D01*
Y1070981D01*
G37*
G36*
G01X372628Y1072579D02*
X372813Y1073179D01*
X373843D01*
X374028Y1072579D01*
Y1072405D01*
X372628D01*
Y1072579D01*
G37*
G36*
G01D02*
X372813Y1073179D01*
X373843D01*
X374028Y1072579D01*
Y1072405D01*
X372628D01*
Y1072579D01*
G37*
G36*
G01X370812Y1069373D02*
X370997Y1069973D01*
X372027D01*
X372212Y1069373D01*
Y1069199D01*
X370812D01*
Y1069373D01*
G37*
G36*
G01D02*
X370997Y1069973D01*
X372027D01*
X372212Y1069373D01*
Y1069199D01*
X370812D01*
Y1069373D01*
G37*
G36*
G01X374535Y1075783D02*
X374720Y1076383D01*
X375750D01*
X375935Y1075783D01*
Y1075609D01*
X374535D01*
Y1075783D01*
G37*
G36*
G01X370835D02*
X371020Y1076383D01*
X372050D01*
X372235Y1075783D01*
Y1075608D01*
X370835D01*
Y1075783D01*
G37*
G36*
G01X374535D02*
X374720Y1076383D01*
X375750D01*
X375935Y1075783D01*
Y1075609D01*
X374535D01*
Y1075783D01*
G37*
G36*
G01X370835D02*
X371020Y1076383D01*
X372050D01*
X372235Y1075783D01*
Y1075608D01*
X370835D01*
Y1075783D01*
G37*
G36*
G01X375878Y1077391D02*
X375693Y1076791D01*
X374663D01*
X374478Y1077391D01*
Y1077565D01*
X375878D01*
Y1077391D01*
G37*
G36*
G01X372235D02*
X372050Y1076791D01*
X371020D01*
X370835Y1077391D01*
Y1077566D01*
X372235D01*
Y1077391D01*
G37*
G36*
G01X375878D02*
X375693Y1076791D01*
X374663D01*
X374478Y1077391D01*
Y1077565D01*
X375878D01*
Y1077391D01*
G37*
G36*
G01X372235D02*
X372050Y1076791D01*
X371020D01*
X370835Y1077391D01*
Y1077566D01*
X372235D01*
Y1077391D01*
G37*
G36*
G01X374061Y1074187D02*
X373876Y1073587D01*
X372846D01*
X372661Y1074187D01*
Y1074362D01*
X374061D01*
Y1074187D01*
G37*
G36*
G01D02*
X373876Y1073587D01*
X372846D01*
X372661Y1074187D01*
Y1074362D01*
X374061D01*
Y1074187D01*
G37*
G36*
G01X372662Y1091803D02*
X372847Y1092403D01*
X373877D01*
X374062Y1091803D01*
Y1091629D01*
X372662D01*
Y1091803D01*
G37*
G36*
G01D02*
X372847Y1092403D01*
X373877D01*
X374062Y1091803D01*
Y1091629D01*
X372662D01*
Y1091803D01*
G37*
G36*
G01X370845Y1082191D02*
X371030Y1082791D01*
X372060D01*
X372245Y1082191D01*
Y1082017D01*
X370845D01*
Y1082191D01*
G37*
G36*
G01X374545D02*
X374730Y1082791D01*
X375760D01*
X375945Y1082191D01*
Y1082017D01*
X374545D01*
Y1082191D01*
G37*
G36*
G01X370845D02*
X371030Y1082791D01*
X372060D01*
X372245Y1082191D01*
Y1082017D01*
X370845D01*
Y1082191D01*
G37*
G36*
G01X374545D02*
X374730Y1082791D01*
X375760D01*
X375945Y1082191D01*
Y1082017D01*
X374545D01*
Y1082191D01*
G37*
G36*
G01X431658Y875204D02*
X432599D01*
G02X432923Y874570I0J-400D01*
G03X432678Y873810I1056J-760D01*
G03X433739Y872531I1301J0D01*
G01X433829Y872514D01*
X434632Y871123D01*
X434601Y871037D01*
G03X434528Y870606I1228J-430D01*
G03X435829Y869305I1301J0D01*
G03X436423Y869449I-1J1301D01*
G02X437006Y869093I183J-356D01*
G01Y868515D01*
G03Y866287I672J-1114D01*
G01Y865710D01*
G02X436423Y865354I-400J0D01*
G03X435829Y865498I-595J-1157D01*
G03Y862896I0J-1301D01*
G03X436423Y863040I-1J1301D01*
G02X437006Y862684I183J-356D01*
G01Y862105D01*
G03Y859879I674J-1113D01*
G01Y859302D01*
G02X436423Y858946I-400J0D01*
G03X435829Y859090I-595J-1157D01*
G03X434528Y857789I0J-1301D01*
G03X435589Y856510I1301J0D01*
G01X435679Y856493D01*
X436482Y855102D01*
X436452Y855015D01*
G03X436378Y854584I1227J-432D01*
G03X437006Y853471I1300J0D01*
G01Y852893D01*
G02X436423Y852537I-400J0D01*
G03X435829Y852681I-595J-1157D01*
G03X434534Y851509I0J-1301D01*
G02X434118Y851149I-398J39D01*
G03X433978Y851152I-134J-2973D01*
G01X433821D01*
G02X433423Y851512I0J400D01*
G03X430835I-1294J-132D01*
G02X430437Y851152I-398J40D01*
G01X430278D01*
G03X430140Y851149I-4J-2976D01*
G02X429724Y851509I-18J400D01*
G03X427134I-1295J-129D01*
G02X426718Y851149I-398J39D01*
G03X426578Y851152I-134J-2973D01*
G03X426440Y851149I-4J-2976D01*
G02X426024Y851509I-18J400D01*
G03X424729Y852681I-1295J-129D01*
G03X423428Y851380I0J-1301D01*
G03X423969Y850324I1301J0D01*
G02X424073Y849783I-233J-325D01*
G03X423602Y848176I2506J-1607D01*
G03X423634Y847739I2976J-2D01*
G03X423215Y847535I1089J-2770D01*
G02X422943Y847602I-102J172D01*
G03X422625Y848027I-2533J-1563D01*
G03X422372Y848597I-2832J-916D01*
G01X421756Y849664D01*
G03X421684Y849782I-2576J-1491D01*
G02X421787Y850323I337J216D01*
G03X422330Y851380I-757J1057D01*
G03X421029Y852681I-1301J0D01*
G03X419734Y851509I0J-1301D01*
G02X419318Y851149I-398J39D01*
G03X419178Y851152I-134J-2973D01*
G03X419040Y851149I-4J-2976D01*
G02X418624Y851509I-18J400D01*
G03X417329Y852681I-1295J-129D01*
G03X416028Y851380I0J-1301D01*
G03X416569Y850324I1301J0D01*
G02X416673Y849783I-233J-325D01*
G03X416202Y848176I2506J-1607D01*
G03X416234Y847739I2976J-2D01*
G03X415815Y847535I1089J-2770D01*
G02X415543Y847602I-102J172D01*
G03X415225Y848027I-2533J-1563D01*
G03X414972Y848597I-2832J-916D01*
G01X414356Y849664D01*
G03X414284Y849782I-2576J-1491D01*
G02X414387Y850323I337J216D01*
G03X414930Y851380I-757J1057D01*
G03X413629Y852681I-1301J0D01*
G03X412334Y851509I0J-1301D01*
G02X411918Y851149I-398J39D01*
G03X411778Y851152I-134J-2973D01*
G03X411640Y851149I-4J-2976D01*
G02X411224Y851509I-18J400D01*
G03X409929Y852681I-1295J-129D01*
G03X408628Y851380I0J-1301D01*
G03X409169Y850324I1301J0D01*
G02X409273Y849783I-233J-325D01*
G03X408802Y848176I2506J-1607D01*
G03X408834Y847739I2976J-2D01*
G03X408415Y847535I1089J-2770D01*
G02X408143Y847602I-102J172D01*
G03X407825Y848027I-2533J-1563D01*
G03X407572Y848597I-2832J-916D01*
G01X406956Y849664D01*
G03X406884Y849782I-2576J-1491D01*
G02X406987Y850323I337J216D01*
G03X407530Y851380I-757J1057D01*
G03X406229Y852681I-1301J0D01*
G03X404934Y851509I0J-1301D01*
G02X404518Y851149I-398J39D01*
G03X404378Y851152I-134J-2973D01*
G03X404240Y851149I-4J-2976D01*
G02X403824Y851509I-18J400D01*
G03X402529Y852681I-1295J-129D01*
G03X401228Y851380I0J-1301D01*
G03X401769Y850324I1301J0D01*
G02X401873Y849783I-233J-325D01*
G03X401402Y848176I2506J-1607D01*
G03X401434Y847739I2976J-2D01*
G03X401015Y847535I1089J-2770D01*
G02X400743Y847602I-102J172D01*
G03X400425Y848027I-2533J-1563D01*
G03X400172Y848597I-2832J-916D01*
G01X399556Y849664D01*
G03X399484Y849782I-2576J-1491D01*
G02X399587Y850323I337J216D01*
G03X400130Y851380I-757J1057D01*
G03X398993Y852671I-1301J0D01*
G01X398818Y852693D01*
Y855506D01*
G02X399191Y855606I200J0D01*
G01X399481Y855103D01*
X399451Y855016D01*
G03X399377Y854584I1227J-433D01*
G03X401979I1301J0D01*
G03X400918Y855863I-1301J0D01*
G01X400828Y855880D01*
X400026Y857270D01*
X400056Y857357D01*
G03X400130Y857789I-1227J433D01*
G03X398993Y859080I-1301J0D01*
G01X398818Y859102D01*
Y862884D01*
X398993Y862906D01*
G03X400130Y864186I-164J1291D01*
G02X400530Y864582I400J-4D01*
G01X400595D01*
G02X401229Y864243I234J-324D01*
G03X401228Y864197I1300J-51D01*
G03X402529Y865498I1301J0D01*
G03X402483Y865497I5J-1301D01*
G02X402186Y866180I-15J400D01*
G01X402708Y866702D01*
G02X403317Y866650I283J-283D01*
G03X404379Y866100I1062J750D01*
G03X405680Y867401I0J1301D01*
G03X405130Y868463I-1300J0D01*
G02X405078Y869072I231J326D01*
G01X405515Y869509D01*
X405644Y869444D01*
G03X405989Y869327I586J1162D01*
G01X406079Y869310D01*
X406881Y867920D01*
X406851Y867833D01*
G03X406777Y867401I1227J-433D01*
G03X409379I1301J0D01*
G03X408318Y868680I-1301J0D01*
G01X408228Y868697D01*
X407426Y870087D01*
X407456Y870174D01*
G03X407530Y870606I-1227J433D01*
G03X407391Y871191I-1301J0D01*
G01X407326Y871320D01*
X408644Y872638D01*
X408672Y872653D01*
G03X409235Y873216I-594J1157D01*
G01X409250Y873244D01*
X409818Y873812D01*
G02X410495Y873595I283J-283D01*
G03X411538Y872531I1283J215D01*
G01X411628Y872514D01*
X412431Y871122D01*
X412401Y871036D01*
G03X412328Y870606I1228J-430D01*
G03X414930I1301J0D01*
G03X413867Y871885I-1301J0D01*
G01X413776Y871902D01*
X412975Y873291D01*
X413005Y873378D01*
G03X413079Y873810I-1227J433D01*
G03X412834Y874570I-1301J0D01*
G02X413158Y875204I324J234D01*
G01X417798D01*
G02X418122Y874570I0J-400D01*
G03X417877Y873810I1056J-760D01*
G03X418938Y872531I1301J0D01*
G01X419028Y872514D01*
X419831Y871122D01*
X419801Y871036D01*
G03X419728Y870606I1228J-430D01*
G03X422330I1301J0D01*
G03X421267Y871885I-1301J0D01*
G01X421176Y871902D01*
X420375Y873291D01*
X420405Y873378D01*
G03X420479Y873810I-1227J433D01*
G03X420234Y874570I-1301J0D01*
G02X420558Y875204I324J234D01*
G01X425198D01*
G02X425522Y874570I0J-400D01*
G03X425277Y873810I1056J-760D01*
G03X426338Y872531I1301J0D01*
G01X426428Y872514D01*
X427231Y871122D01*
X427201Y871036D01*
G03X427128Y870606I1228J-430D01*
G03X429730I1301J0D01*
G03X428667Y871885I-1301J0D01*
G01X428576Y871902D01*
X427775Y873291D01*
X427805Y873378D01*
G03X427879Y873810I-1227J433D01*
G03X427634Y874570I-1301J0D01*
G02X427958Y875204I324J234D01*
G01X428898D01*
G02X429222Y874570I0J-400D01*
G03X428977Y873810I1056J-760D01*
G03X431579I1301J0D01*
G03X431334Y874570I-1301J0D01*
G02X431658Y875204I324J234D01*
G37*
G36*
G01X402421Y1028455D02*
X403827D01*
G02X404103Y1027765I0J-400D01*
G03X403697Y1026821I894J-944D01*
G03X406299I1301J0D01*
G01Y1026834D01*
G02X406982Y1027120I400J3D01*
G01X407607Y1026495D01*
Y1016237D01*
G02X407178Y1015838I-400J0D01*
G03X407085Y1015841I-88J-1298D01*
G03Y1013239I0J-1301D01*
G03X407178Y1013242I5J1301D01*
G02X407607Y1012843I29J-399D01*
G01Y985285D01*
X412967Y979925D01*
Y964635D01*
X406657Y958325D01*
Y949826D01*
G02X405996Y949523I-400J0D01*
G03X405145Y949840I-851J-984D01*
G03X403844Y948539I0J-1301D01*
G03X404186Y947659I1301J-1D01*
G02Y947119I-294J-270D01*
G03X403844Y946239I959J-879D01*
G03X405145Y944938I1301J0D01*
G03X405996Y945255I0J1301D01*
G02X406657Y944952I261J-303D01*
G01Y944535D01*
X405747Y943625D01*
X402357D01*
G02X401962Y944091I0J400D01*
G03X401980Y944304I-1283J216D01*
G03X399378I-1301J0D01*
G03X399396Y944091I1301J3D01*
G02X399001Y943625I-395J-66D01*
G01X398656D01*
G02X398261Y944091I0J400D01*
G03X398279Y944304I-1283J216D01*
G03X396978Y945605I-1301J0D01*
G03X395780Y944811I0J-1301D01*
G02X395128Y944684I-369J155D01*
G01X394497Y945315D01*
Y945824D01*
G02X394952Y946220I400J0D01*
G03X395129Y946208I176J1289D01*
G03Y948810I0J1301D01*
G03X394952Y948798I-1J-1301D01*
G02X394497Y949194I-55J396D01*
G01Y950257D01*
X394508Y950289D01*
G03Y951137I-1231J424D01*
G01X394497Y951169D01*
Y952232D01*
G02X394952Y952628I400J0D01*
G03X395129Y952616I176J1289D01*
G03Y955218I0J1301D01*
G03X394952Y955206I-1J-1301D01*
G02X394497Y955602I-55J396D01*
G01Y956666D01*
X394508Y956698D01*
G03Y957546I-1231J424D01*
G01X394497Y957578D01*
Y958641D01*
G02X394952Y959037I400J0D01*
G03X395129Y959025I176J1289D01*
G03Y961627I0J1301D01*
G03X394952Y961615I-1J-1301D01*
G02X394497Y962011I-55J396D01*
G01Y962845D01*
X395046Y963394D01*
G02X395717Y963210I283J-282D01*
G03X396978Y962229I1261J320D01*
G03X398279Y963530I0J1301D01*
G03X397298Y964791I-1301J0D01*
G02X397114Y965462I98J388D01*
G01X397407Y965755D01*
G02X397958Y965769I283J-283D01*
G03X398829Y965434I871J965D01*
G03X400130Y966735I0J1301D01*
G03X399795Y967606I-1300J0D01*
G02X399809Y968157I297J268D01*
G01X400332Y968680D01*
X400436Y968661D01*
G03X400678Y968638I244J1278D01*
G03X401979Y969939I0J1301D01*
G03X401956Y970181I-1301J-2D01*
G01X401937Y970285D01*
X403897Y972245D01*
Y977364D01*
G02X404430Y977742I400J1D01*
G03X404861Y977668I432J1227D01*
G03X406162Y978969I0J1301D01*
G03X405820Y979849I-1301J1D01*
G02Y980389I294J270D01*
G03X406162Y981269I-959J879D01*
G03X404861Y982570I-1301J0D01*
G03X403562Y981335I0J-1301D01*
G02X402879Y981073I-400J20D01*
G01X401825Y982127D01*
X401877Y982251D01*
G03X401979Y982756I-1199J505D01*
G03X400764Y984054I-1301J0D01*
G02X400577Y984254I13J200D01*
G01Y999197D01*
X400588Y999228D01*
G03X400664Y999684I-1326J455D01*
G03X400588Y1000140I-1402J1D01*
G01X400577Y1000171D01*
Y1000935D01*
X398712Y1002800D01*
Y1002884D01*
G03X397624Y1004171I-1301J4D01*
G01X397457Y1004199D01*
Y1007986D01*
X397624Y1008013D01*
G03Y1010581I-212J1284D01*
G01X397457Y1010608D01*
Y1014394D01*
X397624Y1014422D01*
G03Y1016988I-212J1283D01*
G01X397457Y1017016D01*
Y1020803D01*
X397624Y1020831D01*
G03Y1023397I-212J1283D01*
G01X397457Y1023425D01*
Y1026835D01*
X397970Y1027348D01*
X397998Y1027362D01*
G03X398572Y1027936I-587J1161D01*
G01X398586Y1027964D01*
X399077Y1028455D01*
X399801D01*
X399831Y1028291D01*
G03X402391I1280J232D01*
G01X402421Y1028455D01*
G37*
G36*
G01X392095Y977151D02*
X391910Y976551D01*
X390880D01*
X390695Y977151D01*
Y977325D01*
X392095D01*
Y977151D01*
G37*
G36*
G01X388405D02*
X388220Y976551D01*
X387190D01*
X387005Y977151D01*
Y977326D01*
X388405D01*
Y977151D01*
G37*
G36*
G01X392095D02*
X391910Y976551D01*
X390880D01*
X390695Y977151D01*
Y977325D01*
X392095D01*
Y977151D01*
G37*
G36*
G01X388405D02*
X388220Y976551D01*
X387190D01*
X387005Y977151D01*
Y977326D01*
X388405D01*
Y977151D01*
G37*
G36*
G01X393164Y974937D02*
X393776Y975077D01*
X394291Y974185D01*
X393864Y973725D01*
X393713Y973638D01*
X393013Y974850D01*
X393164Y974937D01*
G37*
G36*
G01X396279Y972339D02*
X396464Y972939D01*
X397494D01*
X397679Y972339D01*
Y972164D01*
X396279D01*
Y972339D01*
G37*
G36*
G01X390695Y975543D02*
X390880Y976143D01*
X391910D01*
X392095Y975543D01*
Y975369D01*
X390695D01*
Y975543D01*
G37*
G36*
G01X387052D02*
X387237Y976143D01*
X388267D01*
X388452Y975543D01*
Y975368D01*
X387052D01*
Y975543D01*
G37*
G36*
G01X393164Y974937D02*
X393776Y975077D01*
X394291Y974185D01*
X393864Y973725D01*
X393713Y973638D01*
X393013Y974850D01*
X393164Y974937D01*
G37*
G36*
G01X396279Y972339D02*
X396464Y972939D01*
X397494D01*
X397679Y972339D01*
Y972164D01*
X396279D01*
Y972339D01*
G37*
G36*
G01X390695Y975543D02*
X390880Y976143D01*
X391910D01*
X392095Y975543D01*
Y975369D01*
X390695D01*
Y975543D01*
G37*
G36*
G01X387052D02*
X387237Y976143D01*
X388267D01*
X388452Y975543D01*
Y975368D01*
X387052D01*
Y975543D01*
G37*
G36*
G01X392612Y978749D02*
X392797Y979349D01*
X393827D01*
X394012Y978749D01*
Y978574D01*
X392612D01*
Y978749D01*
G37*
G36*
G01X388912D02*
X389097Y979349D01*
X390127D01*
X390312Y978749D01*
Y978574D01*
X388912D01*
Y978749D01*
G37*
G36*
G01X392612D02*
X392797Y979349D01*
X393827D01*
X394012Y978749D01*
Y978574D01*
X392612D01*
Y978749D01*
G37*
G36*
G01X388912D02*
X389097Y979349D01*
X390127D01*
X390312Y978749D01*
Y978574D01*
X388912D01*
Y978749D01*
G37*
G36*
G01X393415Y971311D02*
X392803Y971171D01*
X392288Y972063D01*
X392715Y972523D01*
X392866Y972610D01*
X393566Y971398D01*
X393415Y971311D01*
G37*
G36*
G01X399505Y970743D02*
X399320Y970143D01*
X398290D01*
X398105Y970743D01*
Y970918D01*
X399505D01*
Y970743D01*
G37*
G36*
G01X395805D02*
X395620Y970143D01*
X394590D01*
X394405Y970743D01*
Y970917D01*
X395805D01*
Y970743D01*
G37*
G36*
G01X390302Y973947D02*
X390117Y973347D01*
X389087D01*
X388902Y973947D01*
Y974121D01*
X390302D01*
Y973947D01*
G37*
G36*
G01X401264Y972561D02*
X401691Y972101D01*
X401176Y971209D01*
X400564Y971349D01*
X400413Y971436D01*
X401113Y972648D01*
X401264Y972561D01*
G37*
G36*
G01X393415Y971311D02*
X392803Y971171D01*
X392288Y972063D01*
X392715Y972523D01*
X392866Y972610D01*
X393566Y971398D01*
X393415Y971311D01*
G37*
G36*
G01X399505Y970743D02*
X399320Y970143D01*
X398290D01*
X398105Y970743D01*
Y970918D01*
X399505D01*
Y970743D01*
G37*
G36*
G01X395805D02*
X395620Y970143D01*
X394590D01*
X394405Y970743D01*
Y970917D01*
X395805D01*
Y970743D01*
G37*
G36*
G01X390302Y973947D02*
X390117Y973347D01*
X389087D01*
X388902Y973947D01*
Y974121D01*
X390302D01*
Y973947D01*
G37*
G36*
G01X401264Y972561D02*
X401691Y972101D01*
X401176Y971209D01*
X400564Y971349D01*
X400413Y971436D01*
X401113Y972648D01*
X401264Y972561D01*
G37*
G36*
G01X486236Y930270D02*
X488339D01*
X490053Y928556D01*
X490040Y928458D01*
G03X490028Y928283I1289J-176D01*
G03X491329Y926982I1301J0D01*
G03X491504Y926994I-1J1301D01*
G01X491602Y927007D01*
X491954Y926655D01*
Y925518D01*
X491944Y925488D01*
G03Y924670I1234J-409D01*
G01X491954Y924640D01*
Y923561D01*
G02X491501Y923165I-400J0D01*
G03X491329Y923176I-169J-1290D01*
G03Y920574I0J-1301D01*
G03X491501Y920585I3J1301D01*
G02X491954Y920189I53J-396D01*
G01Y919112D01*
X491944Y919081D01*
G03X491877Y918670I1234J-412D01*
G03X491944Y918259I1301J1D01*
G01X491954Y918228D01*
Y917152D01*
G02X491501Y916756I-400J0D01*
G03X491329Y916767I-169J-1290D01*
G03Y914165I0J-1301D01*
G03X491501Y914176I3J1301D01*
G02X491954Y913780I53J-396D01*
G01Y912704D01*
X491944Y912673D01*
G03X491877Y912262I1234J-412D01*
G03X491944Y911851I1301J1D01*
G01X491954Y911820D01*
Y910743D01*
G02X491501Y910347I-400J0D01*
G03X491329Y910358I-169J-1290D01*
G03Y907756I0J-1301D01*
G03X491501Y907767I3J1301D01*
G02X491954Y907371I53J-396D01*
G01Y906435D01*
X491991Y906398D01*
X491950Y906280D01*
G03X491878Y905853I1230J-427D01*
G03X493179Y904552I1301J0D01*
G03X493606Y904624I0J1302D01*
G01X493724Y904665D01*
X494184Y904205D01*
G02X494166Y903623I-283J-283D01*
G03X493728Y902649I864J-974D01*
G03X495029Y901348I1301J0D01*
G03X496003Y901786I0J1302D01*
G02X496585Y901804I299J-265D01*
G01X496971Y901418D01*
G02X496733Y900738I-283J-283D01*
G03X495578Y899445I146J-1293D01*
G03X496879Y898144I1301J0D01*
G03X498172Y899299I0J1301D01*
G02X498852Y899537I397J-45D01*
G01X499337Y899052D01*
X499352Y899010D01*
G03X500143Y898219I1226J435D01*
G01X500185Y898204D01*
X501373Y897016D01*
X501297Y896884D01*
G03X501127Y896240I1131J-643D01*
G03X502428Y894939I1301J0D01*
G03X503072Y895109I1J1301D01*
G01X503204Y895185D01*
X503640Y894749D01*
G02X503574Y894130I-283J-283D01*
G03X502978Y893036I706J-1094D01*
G03X504279Y891735I1301J0D01*
G03X505373Y892331I0J1302D01*
G02X505992Y892397I336J-217D01*
G01X508526Y889863D01*
X508529Y889784D01*
G03X509829Y888531I1300J48D01*
G03X510737Y888900I0J1302D01*
G01X512621D01*
G03X514437I908J933D01*
G01X516321D01*
G03X518137I908J933D01*
G01X520021D01*
G03X521837I908J933D01*
G01X523721D01*
G03X524629Y888531I908J933D01*
G03X524893Y888558I0J1301D01*
G01X524999Y888580D01*
X525514Y888065D01*
G02X525524Y887511I-283J-282D01*
G03X525178Y886627I956J-884D01*
G03X526479Y885326I1301J0D01*
G03X527363Y885672I0J1302D01*
G02X527917Y885662I272J-293D01*
G01X528429Y885150D01*
X528181Y884719D01*
X528090Y884702D01*
G03X527028Y883423I239J-1279D01*
G03X528329Y882122I1301J0D01*
G03X528482Y882131I0J1301D01*
G02X528929Y881734I47J-397D01*
G01Y880581D01*
X528922Y880555D01*
G03X528878Y880219I1257J-335D01*
G03X528922Y879883I1301J-1D01*
G01X528929Y879857D01*
Y878703D01*
G02X528482Y878306I-400J0D01*
G03X528329Y878315I-153J-1292D01*
G03Y875713I0J-1301D01*
G03X528482Y875722I0J1301D01*
G02X528929Y875325I47J-397D01*
G01Y874175D01*
X528922Y874149D01*
G03X528877Y873810I1256J-339D01*
G03X528922Y873471I1301J0D01*
G01X528929Y873445D01*
Y872295D01*
G02X528482Y871898I-400J0D01*
G03X528329Y871907I-153J-1292D01*
G03X527028Y870606I0J-1301D01*
G03X527102Y870174I1301J1D01*
G01X527132Y870087D01*
X526330Y868697D01*
X526240Y868680D01*
G03X525178Y867401I239J-1279D01*
G03X527780I1301J0D01*
G03X527706Y867833I-1301J-1D01*
G01X527676Y867919D01*
X528479Y869310D01*
X528569Y869327D01*
G03X528676Y869352I-242J1278D01*
G01X528702Y869359D01*
X528929D01*
Y867766D01*
X528922Y867740D01*
G03X528877Y867401I1256J-339D01*
G03X528922Y867062I1301J0D01*
G01X528929Y867036D01*
Y865886D01*
G02X528482Y865489I-400J0D01*
G03X528329Y865498I-153J-1292D01*
G03Y862896I0J-1301D01*
G03X528482Y862905I0J1301D01*
G02X528929Y862508I47J-397D01*
G01Y861355D01*
X528922Y861329D01*
G03X528878Y860993I1257J-335D01*
G03X528922Y860657I1301J-1D01*
G01X528929Y860631D01*
Y859478D01*
G02X528482Y859081I-400J0D01*
G03X528329Y859090I-153J-1292D01*
G03X527028Y857789I0J-1301D01*
G03X527102Y857357I1301J1D01*
G01X527132Y857270D01*
X526330Y855880D01*
X526239Y855863D01*
G03X525180Y854671I239J-1279D01*
G01X525175Y854596D01*
X524758Y854179D01*
G02X524077Y854491I-282J283D01*
G03X524080Y854584I-1298J88D01*
G03X522779Y853283I-1301J0D01*
G03X522872Y853286I5J1301D01*
G02X523184Y852605I29J-399D01*
G01X522624Y852045D01*
G02X522009Y852105I-283J283D01*
G03X520929Y852681I-1080J-724D01*
G03X519628Y851380I0J-1301D01*
G03X519690Y850982I1301J-1D01*
G02X519309Y850460I-381J-122D01*
G01X518849D01*
G02X518468Y850982I0J400D01*
G03X518530Y851380I-1239J397D01*
G03X517229Y852681I-1301J0D01*
G03X515934Y851509I0J-1301D01*
G02X515518Y851149I-398J39D01*
G03X515378Y851152I-134J-2973D01*
G03X515240Y851149I-4J-2976D01*
G02X514824Y851509I-18J400D01*
G03X513529Y852681I-1295J-129D01*
G03X512228Y851380I0J-1301D01*
G03X512290Y850982I1301J-1D01*
G02X511909Y850460I-381J-122D01*
G01X511449D01*
G02X511068Y850982I0J400D01*
G03X511130Y851380I-1239J397D01*
G03X509829Y852681I-1301J0D01*
G03X508534Y851509I0J-1301D01*
G02X508118Y851149I-398J39D01*
G03X507978Y851152I-134J-2973D01*
G03X507840Y851149I-4J-2976D01*
G02X507424Y851509I-18J400D01*
G03X506129Y852681I-1295J-129D01*
G03X504828Y851380I0J-1301D01*
G03X504890Y850982I1301J-1D01*
G02X504509Y850460I-381J-122D01*
G01X504049D01*
G02X503668Y850982I0J400D01*
G03X503730Y851380I-1239J397D01*
G03X502429Y852681I-1301J0D01*
G03X501134Y851509I0J-1301D01*
G02X500718Y851149I-398J39D01*
G03X500578Y851152I-134J-2973D01*
G03X500440Y851149I-4J-2976D01*
G02X500024Y851509I-18J400D01*
G03X498729Y852681I-1295J-129D01*
G03X497428Y851380I0J-1301D01*
G03X497969Y850324I1301J0D01*
G02X498073Y849783I-233J-325D01*
G03X497602Y848176I2506J-1607D01*
G03X497634Y847739I2976J-2D01*
G03X497215Y847535I1089J-2770D01*
G02X496943Y847602I-102J172D01*
G03X496625Y848027I-2533J-1563D01*
G03X496372Y848597I-2832J-916D01*
G01X495756Y849664D01*
G03X495684Y849782I-2576J-1491D01*
G02X495787Y850323I337J216D01*
G03X496330Y851380I-757J1057D01*
G03X495029Y852681I-1301J0D01*
G03X493734Y851509I0J-1301D01*
G02X493318Y851149I-398J39D01*
G03X493178Y851152I-134J-2973D01*
G03X493040Y851149I-4J-2976D01*
G02X492624Y851509I-18J400D01*
G03X491329Y852681I-1295J-129D01*
G03X490028Y851380I0J-1301D01*
G03X490569Y850324I1301J0D01*
G02X490673Y849783I-233J-325D01*
G03X490202Y848176I2506J-1607D01*
G03X490234Y847739I2976J-2D01*
G03X489815Y847535I1089J-2770D01*
G02X489543Y847602I-102J172D01*
G03X489225Y848027I-2533J-1563D01*
G03X488972Y848597I-2832J-916D01*
G01X488356Y849664D01*
G03X488284Y849782I-2576J-1491D01*
G02X488387Y850323I337J216D01*
G03X488930Y851380I-757J1057D01*
G03X487629Y852681I-1301J0D01*
G03X486334Y851509I0J-1301D01*
G02X485918Y851149I-398J39D01*
G03X485778Y851152I-134J-2973D01*
G03X485640Y851149I-4J-2976D01*
G02X485224Y851509I-18J400D01*
G03X483929Y852681I-1295J-129D01*
G03X482628Y851380I0J-1301D01*
G03X483169Y850324I1301J0D01*
G02X483273Y849783I-233J-325D01*
G03X482802Y848176I2506J-1607D01*
G03X482834Y847739I2976J-2D01*
G03X482415Y847535I1089J-2770D01*
G02X482143Y847602I-102J172D01*
G03X481825Y848027I-2533J-1563D01*
G03X481572Y848597I-2832J-916D01*
G01X480956Y849664D01*
G03X480884Y849782I-2576J-1491D01*
G02X480987Y850323I337J216D01*
G03X481530Y851380I-757J1057D01*
G03X480229Y852681I-1301J0D01*
G03X478934Y851509I0J-1301D01*
G02X478518Y851149I-398J39D01*
G03X478378Y851152I-134J-2973D01*
G03X478240Y851149I-4J-2976D01*
G02X477824Y851509I-18J400D01*
G03X476529Y852681I-1295J-129D01*
G03X475228Y851380I0J-1301D01*
G03X475769Y850324I1301J0D01*
G02X475873Y849783I-233J-325D01*
G03X475402Y848176I2506J-1607D01*
G03X475434Y847739I2976J-2D01*
G03X475015Y847535I1089J-2770D01*
G02X474743Y847602I-102J172D01*
G03X474425Y848027I-2533J-1563D01*
G03X474172Y848597I-2832J-916D01*
G01X473556Y849664D01*
G03X473484Y849782I-2576J-1491D01*
G02X473587Y850323I337J216D01*
G03X474130Y851380I-757J1057D01*
G03X472829Y852681I-1301J0D01*
G03X471534Y851509I0J-1301D01*
G02X471118Y851149I-398J39D01*
G03X470978Y851152I-134J-2973D01*
G03X470840Y851149I-4J-2976D01*
G02X470424Y851509I-18J400D01*
G03X469129Y852681I-1295J-129D01*
G03X467828Y851380I0J-1301D01*
G03X468369Y850324I1301J0D01*
G02X468473Y849783I-233J-325D01*
G03X468002Y848176I2506J-1607D01*
G03X468034Y847739I2976J-2D01*
G03X467615Y847535I1089J-2770D01*
G02X467343Y847602I-102J172D01*
G03X467025Y848027I-2533J-1563D01*
G03X466772Y848597I-2832J-916D01*
G01X466156Y849664D01*
G03X466084Y849782I-2576J-1491D01*
G02X466187Y850323I337J216D01*
G03X466730Y851380I-757J1057D01*
G03X465429Y852681I-1301J0D01*
G03X464134Y851509I0J-1301D01*
G02X463718Y851149I-398J39D01*
G03X463578Y851152I-134J-2973D01*
G03X463440Y851149I-4J-2976D01*
G02X463024Y851509I-18J400D01*
G03X461729Y852681I-1295J-129D01*
G03X460428Y851380I0J-1301D01*
G03X460969Y850324I1301J0D01*
G02X461073Y849783I-233J-325D01*
G03X460602Y848176I2506J-1607D01*
G03X460634Y847739I2976J-2D01*
G03X460215Y847535I1089J-2770D01*
G02X459943Y847602I-102J172D01*
G03X459625Y848027I-2533J-1563D01*
G03X459372Y848597I-2832J-916D01*
G01X458756Y849664D01*
G03X458684Y849782I-2576J-1491D01*
G02X458787Y850323I337J216D01*
G03X459330Y851380I-757J1057D01*
G03X458029Y852681I-1301J0D01*
G03X456734Y851509I0J-1301D01*
G02X456318Y851149I-398J39D01*
G03X456178Y851152I-134J-2973D01*
G03X456039Y851149I-5J-2976D01*
G02X455623Y851509I-18J400D01*
G03X454328Y852681I-1295J-129D01*
G03X453027Y851380I0J-1301D01*
G03X453569Y850323I1302J0D01*
G02X453672Y849783I-234J-324D01*
G03X453534Y849542I2511J-1598D01*
G02X453014Y849362I-355J184D01*
G03X452478Y849477I-535J-1186D01*
G03X451945Y849363I0J-1301D01*
G02X451435Y849528I-164J365D01*
G01X451356Y849664D01*
G03X451284Y849782I-2576J-1491D01*
G02X451387Y850323I337J216D01*
G03X451930Y851380I-757J1057D01*
G03X450629Y852681I-1301J0D01*
G03X449334Y851509I0J-1301D01*
G02X448918Y851149I-398J39D01*
G03X448778Y851152I-134J-2973D01*
G03X448640Y851149I-4J-2976D01*
G02X448224Y851509I-18J400D01*
G03X446929Y852681I-1295J-129D01*
G03X445628Y851380I0J-1301D01*
G03X446169Y850324I1301J0D01*
G02X446273Y849783I-233J-325D01*
G03X446134Y849542I2506J-1606D01*
G02X445614Y849362I-355J184D01*
G03X445078Y849477I-535J-1186D01*
G03X443777Y848176I0J-1301D01*
G03X443781Y848078I1301J4D01*
G02X443382Y847648I-399J-30D01*
G01X443227D01*
G03X443092Y847644I21J-2976D01*
G02X442675Y848075I-18J400D01*
G03X442679Y848176I-1297J102D01*
G03X441378Y849477I-1301J0D01*
G03X440842Y849362I-1J-1301D01*
G02X440322Y849542I-165J364D01*
G03X440184Y849782I-2646J-1362D01*
G02X440287Y850323I337J216D01*
G03X440830Y851380I-757J1057D01*
G03X439529Y852681I-1301J0D01*
G01X439520D01*
G02X439319Y852881I-1J200D01*
G01Y856288D01*
G02X439520Y856488I200J0D01*
G01X439528D01*
G03Y859090I0J1301D01*
G01X439520D01*
G02X439319Y859290I-1J200D01*
G01Y862696D01*
G02X439520Y862896I200J0D01*
G01X439529D01*
G03Y865498I0J1301D01*
G01X439520D01*
G02X439319Y865698I-1J200D01*
G01Y868687D01*
X439679Y869310D01*
X439769Y869327D01*
G03X440830Y870606I-240J1279D01*
G03X439529Y871907I-1301J0D01*
G01X439520D01*
G02X439319Y872107I-1J200D01*
G01Y875513D01*
G02X439520Y875713I200J0D01*
G01X439529D01*
G03Y878315I0J1301D01*
G01X439520D01*
G02X439319Y878515I-1J200D01*
G01Y881922D01*
G02X439520Y882122I200J0D01*
G01X439529D01*
G03X440830Y883423I0J1301D01*
G03X440756Y883855I-1301J-1D01*
G01X440726Y883942D01*
X441528Y885331D01*
X441618Y885348D01*
G03X442679Y886627I-240J1279D01*
G03X440077I-1301J0D01*
G03X440151Y886195I1301J1D01*
G01X440181Y886108D01*
X440065Y885907D01*
G02X439319Y886107I-346J200D01*
G01Y888331D01*
G02X439520Y888531I200J0D01*
G01X439529D01*
G03Y891133I0J1301D01*
G01X439520D01*
G02X439319Y891333I-1J200D01*
G01Y894739D01*
G02X439520Y894939I200J0D01*
G01X439529D01*
G03Y897541I0J1301D01*
G01X439520D01*
G02X439319Y897741I-1J200D01*
G01Y901148D01*
G02X439520Y901348I200J0D01*
G01X439528D01*
G03Y903950I0J1301D01*
G01X439520D01*
G02X439319Y904150I-1J200D01*
G01Y907556D01*
G02X439520Y907756I200J0D01*
G01X439529D01*
G03Y910358I0J1301D01*
G01X439520D01*
G02X439319Y910558I-1J200D01*
G01Y913965D01*
G02X439520Y914165I200J0D01*
G01X439529D01*
G03Y916767I0J1301D01*
G01X439520D01*
G02X439319Y916967I-1J200D01*
G01Y920374D01*
G02X439520Y920574I200J0D01*
G01X439529D01*
G03Y923176I0J1301D01*
G03X438381Y922487I0J-1301D01*
G02X437745Y922392I-353J188D01*
G01X435267Y924870D01*
X435276Y924963D01*
G03X435281Y925079I-1296J114D01*
G03X434084Y926376I-1301J0D01*
G02X433716Y926775I32J399D01*
G01Y929332D01*
X434654Y930270D01*
X437218D01*
X437250Y930259D01*
G03X437679Y930186I430J1228D01*
G03X438108Y930259I-1J1301D01*
G01X438140Y930270D01*
X440918D01*
X440950Y930259D01*
G03X441379Y930186I430J1228D01*
G03X441808Y930259I-1J1301D01*
G01X441840Y930270D01*
X444618D01*
X444650Y930259D01*
G03X445079Y930186I430J1228D01*
G03X445508Y930259I-1J1301D01*
G01X445540Y930270D01*
X448319D01*
X448351Y930259D01*
G03X448780Y930186I430J1228D01*
G03X449209Y930259I-1J1301D01*
G01X449241Y930270D01*
X453391D01*
G03X454815I712J1090D01*
G01X474978D01*
X474985Y930077D01*
G03X477585I1300J49D01*
G01X477592Y930270D01*
X477920D01*
X477951Y930259D01*
G03X478805I427J1230D01*
G01X478836Y930270D01*
X481621D01*
X481652Y930259D01*
G03X482506I427J1230D01*
G01X482537Y930270D01*
X485320D01*
X485351Y930259D01*
G03X486205I427J1230D01*
G01X486236Y930270D01*
G37*
G36*
G01X478167Y1029945D02*
X480877D01*
X481484Y1029338D01*
X481402Y1029203D01*
G03X481210Y1028523I1108J-680D01*
G03X483812I1301J0D01*
G03X483742Y1028945I-1301J1D01*
G02X484120Y1029475I378J130D01*
G01X484602D01*
G02X484980Y1028945I0J-400D01*
G03X484910Y1028523I1231J-421D01*
G03X486211Y1027222I1301J0D01*
G03X486483Y1027251I-1J1301D01*
G02X486967Y1026860I84J-391D01*
G01Y1026021D01*
G03X486761Y1025318I1095J-703D01*
G03X486967Y1024615I1301J0D01*
G01Y1023777D01*
G02X486483Y1023386I-400J0D01*
G03X486211Y1023415I-273J-1272D01*
G03Y1020813I0J-1301D01*
G03X486483Y1020842I-1J1301D01*
G02X486967Y1020451I84J-391D01*
G01Y1019613D01*
G03X486817Y1019289I1095J-704D01*
G01X486803Y1019241D01*
X486338Y1018776D01*
G02X485657Y1019024I-283J283D01*
G03X484361Y1020211I-1296J-114D01*
G03X483060Y1018910I0J-1301D01*
G03X484247Y1017614I1301J0D01*
G02X484495Y1016933I-35J-398D01*
G01X484088Y1016526D01*
G02X483501Y1016549I-283J283D01*
G03X482511Y1017006I-990J-844D01*
G03X481210Y1015705I0J-1301D01*
G03X481667Y1014715I1301J0D01*
G02X481690Y1014128I-260J-304D01*
G01X481237Y1013675D01*
X481117Y1013720D01*
G03X480662Y1013802I-455J-1219D01*
G03X479361Y1012501I0J-1301D01*
G03X479443Y1012046I1301J0D01*
G01X479488Y1011926D01*
X478009Y1010447D01*
G03X477922Y1010381I803J-1149D01*
G02X477596Y1010531I-126J155D01*
G03X477203Y1011432I-1301J-31D01*
G02X477201Y1012002I279J286D01*
G03X477586Y1012926I-916J924D01*
G03X474984I-1301J0D01*
G03X475377Y1011994I1302J0D01*
G02X475379Y1011424I-279J-286D01*
G03X474994Y1010500I916J-924D01*
G03X476295Y1009199I1301J0D01*
G03X476864Y1009330I0J1301D01*
G02X477432Y1009043I175J-360D01*
G03X477574Y1008638I1378J256D01*
G01X477597Y1008594D01*
Y1008285D01*
X481550Y1004332D01*
G02X481560Y1003776I-282J-283D01*
G03X481210Y1002888I951J-888D01*
G03X482511Y1001587I1301J0D01*
G03X483399Y1001937I0J1301D01*
G02X483955Y1001927I273J-292D01*
G01X484037Y1001845D01*
Y1000952D01*
X483907Y1000903D01*
G03Y998465I454J-1219D01*
G01X484037Y998416D01*
Y981050D01*
G02X483849Y980851I-200J0D01*
G03Y978253I79J-1299D01*
G02X484037Y978054I-12J-199D01*
G01Y976215D01*
X486481Y973771D01*
X486429Y973647D01*
G03X486328Y973143I1200J-503D01*
G03X486607Y972338I1301J0D01*
G01Y971585D01*
G02X486106Y971198I-400J0D01*
G03X485778Y971240I-328J-1260D01*
G03Y968638I0J-1301D01*
G03X486106Y968680I0J1302D01*
G02X486607Y968293I101J-387D01*
G01Y967540D01*
G03Y965930I1022J-805D01*
G01Y965176D01*
G02X486106Y964789I-400J0D01*
G03X485778Y964831I-328J-1260D01*
G03Y962229I0J-1301D01*
G03X486106Y962271I0J1302D01*
G02X486607Y961884I101J-387D01*
G01Y961131D01*
G03Y959521I1022J-805D01*
G01Y958768D01*
G02X486106Y958381I-400J0D01*
G03X485778Y958423I-328J-1260D01*
G03Y955821I0J-1301D01*
G03X486106Y955863I0J1302D01*
G02X486607Y955476I101J-387D01*
G01Y954722D01*
G03Y953112I1022J-805D01*
G01Y952359D01*
G02X486106Y951972I-400J0D01*
G03X485778Y952014I-328J-1260D01*
G03Y949412I0J-1301D01*
G03X486106Y949454I0J1302D01*
G02X486607Y949067I101J-387D01*
G01Y948314D01*
G03X486463Y948086I1022J-805D01*
G01X486448Y948056D01*
X485890Y947498D01*
G02X485212Y947717I-283J283D01*
G03X483928Y948810I-1284J-208D01*
G03X482627Y947509I0J-1301D01*
G03X483720Y946225I1301J0D01*
G02X483939Y945547I-64J-395D01*
G01X483767Y945375D01*
X482818D01*
G03X481340I-739J-1072D01*
G01X479117D01*
G03X478378Y945605I-739J-1072D01*
G03X477929Y945525I0J-1300D01*
G02X477412Y945772I-138J376D01*
G03X477139Y946235I-1233J-415D01*
G02Y946775I294J270D01*
G03X477481Y947655I-959J879D01*
G03X474879I-1301J0D01*
G03X475221Y946775I1301J-1D01*
G02Y946235I-294J-270D01*
G03X474893Y945546I959J-879D01*
G01X474868Y945375D01*
X474607D01*
X473827Y946155D01*
Y961645D01*
X466757Y968715D01*
Y969887D01*
X466866Y969942D01*
G03Y972258I-595J1158D01*
G01X466757Y972313D01*
Y976885D01*
X472947Y983075D01*
Y1018795D01*
X475643Y1021491D01*
X475767Y1021438D01*
G03X476275Y1021335I507J1198D01*
G03X477576Y1022636I0J1301D01*
G03X477473Y1023144I-1301J1D01*
G01X477420Y1023268D01*
X477857Y1023705D01*
Y1029005D01*
X477847Y1029015D01*
Y1029625D01*
X478167Y1029945D01*
G37*
G36*
G01X491838Y1066821D02*
X492999Y1065660D01*
Y1065251D01*
G02X492402Y1064903I-400J0D01*
G03X491762Y1065071I-639J-1133D01*
G03Y1062469I0J-1301D01*
G03X492402Y1062637I1J1301D01*
G02X492999Y1062289I197J-348D01*
G01Y1061713D01*
G03Y1059417I612J-1148D01*
G01Y1058842D01*
G02X492402Y1058494I-400J0D01*
G03X491762Y1058662I-639J-1133D01*
G03Y1056060I0J-1301D01*
G03X492402Y1056228I1J1301D01*
G02X492999Y1055880I197J-348D01*
G01Y1055305D01*
G03Y1053009I612J-1148D01*
G01Y1052433D01*
G02X492402Y1052085I-400J0D01*
G03X491762Y1052253I-639J-1133D01*
G03Y1049651I0J-1301D01*
G03X492402Y1049819I1J1301D01*
G02X492999Y1049471I197J-348D01*
G01Y1048897D01*
G03Y1046601I612J-1148D01*
G01Y1046025D01*
G02X492402Y1045677I-400J0D01*
G03X491762Y1045845I-639J-1133D01*
G03Y1043243I0J-1301D01*
G03X492402Y1043411I1J1301D01*
G02X492999Y1043063I197J-348D01*
G01Y1042488D01*
G03Y1040192I612J-1148D01*
G01Y1039617D01*
G02X492402Y1039269I-400J0D01*
G03X491762Y1039437I-639J-1133D01*
G03Y1036835I0J-1301D01*
G03X492402Y1037003I1J1301D01*
G02X492999Y1036655I197J-348D01*
G01Y1036079D01*
G03Y1033783I614J-1148D01*
G01Y1033208D01*
G02X492402Y1032860I-400J0D01*
G03X491762Y1033028I-639J-1133D01*
G03Y1030426I0J-1301D01*
G03X492661Y1030786I1J1301D01*
G01X492719Y1030842D01*
X492999D01*
Y1030427D01*
X492507Y1029935D01*
X482367D01*
X481675Y1030627D01*
G02X481663Y1030896I142J141D01*
G03X481963Y1031727I-1001J831D01*
G03X479361I-1301J0D01*
G03X479421Y1031335I1301J-1D01*
G02X479040Y1030815I-381J-120D01*
G01X477767D01*
X477237Y1030285D01*
Y1026459D01*
X475720Y1024942D01*
X470290D01*
X468870Y1026362D01*
Y1040119D01*
X468736Y1040253D01*
G02X468722Y1040521I141J142D01*
G03X469012Y1041340I-1011J819D01*
G03X467711Y1042641I-1301J0D01*
G03X466892Y1042351I0J-1301D01*
G01X466752Y1042237D01*
X466278Y1042711D01*
G02X466397Y1043358I283J282D01*
G03X467162Y1044544I-537J1186D01*
G03X465911Y1045844I-1301J0D01*
G02X465719Y1046044I8J200D01*
G01Y1049452D01*
G02X465911Y1049652I200J0D01*
G03Y1052252I-51J1300D01*
G02X465719Y1052452I8J200D01*
G01Y1055861D01*
G02X465911Y1056061I200J0D01*
G03Y1058661I-49J1300D01*
G02X465719Y1058861I8J200D01*
G01Y1062270D01*
G02X465911Y1062470I200J0D01*
G03X467163Y1063770I-49J1300D01*
G03X466435Y1064938I-1301J0D01*
G02X466329Y1065580I177J359D01*
G01X466789Y1066040D01*
X466928Y1065935D01*
G03X467711Y1065673I783J1039D01*
G03X469012Y1066974I0J1301D01*
G03X469010Y1067047I-1301J1D01*
G02X469409Y1067470I399J23D01*
G01X469713D01*
G02X470112Y1067047I0J-400D01*
G03X470110Y1066974I1299J-72D01*
G03X472712I1301J0D01*
G03X472710Y1067047I-1301J1D01*
G02X473109Y1067470I399J23D01*
G01X473413D01*
G02X473812Y1067047I0J-400D01*
G03X473810Y1066974I1299J-72D01*
G03X476412I1301J0D01*
G03X476410Y1067047I-1301J1D01*
G02X476809Y1067470I399J23D01*
G01X477113D01*
G02X477512Y1067047I0J-400D01*
G03X477510Y1066974I1299J-72D01*
G03X480112I1301J0D01*
G03X480110Y1067047I-1301J1D01*
G02X480509Y1067470I399J23D01*
G01X480814D01*
G02X481213Y1067047I0J-400D01*
G03X481211Y1066974I1299J-72D01*
G03X483813I1301J0D01*
G03X483811Y1067047I-1301J1D01*
G02X484210Y1067470I399J23D01*
G01X484513D01*
G02X484912Y1067047I0J-400D01*
G03X484910Y1066974I1299J-72D01*
G03X487512I1301J0D01*
G03X487510Y1067047I-1301J1D01*
G02X487909Y1067470I399J23D01*
G01X488213D01*
G02X488612Y1067047I0J-400D01*
G03X488610Y1066974I1299J-72D01*
G03X489911Y1065673I1301J0D01*
G03X491169Y1066641I0J1301D01*
G02X491838Y1066821I386J-103D01*
G37*
G36*
G01X875373Y127312D02*
X876879D01*
X877124Y127067D01*
Y54252D01*
G02X871260Y48388I-5864J0D01*
G01X774417D01*
G03X764533Y38504I0J-9884D01*
G01Y25740D01*
X764542D01*
Y24724D01*
G02X762606Y22788I-1936J0D01*
G01X500402D01*
G02X498466Y24724I0J1936D01*
G01Y25740D01*
X498475D01*
Y30489D01*
G02X498675Y30688I200J-1D01*
G01X498769Y30665D01*
G03X499475Y30489I706J1328D01*
G03X499978Y30576I-1J1503D01*
G02X500176Y30539I67J-189D01*
G03X500391Y30367I2356J2724D01*
G01X500472Y30208D01*
Y24787D01*
X762536D01*
Y30209D01*
X762617Y30368D01*
G03Y36166I-2138J2899D01*
G01X762536Y36325D01*
Y38504D01*
G02X762561Y39265I11881J-9D01*
G01Y39263D01*
X764405Y41107D01*
Y44900D01*
G02X764701Y45341I10010J-6399D01*
G02X764712Y45353I153J-129D01*
G01X767568Y48209D01*
G02X767580Y48220I141J-142D01*
G02X768628Y48879I6840J-9714D01*
G02X768640Y48884I83J-182D01*
G01X771155Y49928D01*
G02X774413Y50384I3260J-11424D01*
G01X871260D01*
G03X875128Y54252I0J3868D01*
G01Y127067D01*
X875373Y127312D01*
G37*
G36*
G01D02*
X876879D01*
X877124Y127067D01*
Y54252D01*
G02X871260Y48388I-5864J0D01*
G01X774417D01*
G03X764533Y38504I0J-9884D01*
G01Y25740D01*
X764542D01*
Y24724D01*
G02X762606Y22788I-1936J0D01*
G01X500402D01*
G02X498466Y24724I0J1936D01*
G01Y25740D01*
X498475D01*
Y30489D01*
G02X498675Y30688I200J-1D01*
G01X498769Y30665D01*
G03X499475Y30489I706J1328D01*
G03X499978Y30576I-1J1503D01*
G02X500176Y30539I67J-189D01*
G03X500391Y30367I2356J2724D01*
G01X500472Y30208D01*
Y24787D01*
X762536D01*
Y30209D01*
X762617Y30368D01*
G03Y36166I-2138J2899D01*
G01X762536Y36325D01*
Y38504D01*
G02X762561Y39265I11881J-9D01*
G01Y39263D01*
X764405Y41107D01*
Y44900D01*
G02X764701Y45341I10010J-6399D01*
G02X764712Y45353I153J-129D01*
G01X767568Y48209D01*
G02X767580Y48220I141J-142D01*
G02X768628Y48879I6840J-9714D01*
G02X768640Y48884I83J-182D01*
G01X771155Y49928D01*
G02X774413Y50384I3260J-11424D01*
G01X871260D01*
G03X875128Y54252I0J3868D01*
G01Y127067D01*
X875373Y127312D01*
G37*
G36*
G01X497995Y981953D02*
X498180Y982553D01*
X499210D01*
X499395Y981953D01*
Y981778D01*
X497995D01*
Y981953D01*
G37*
G36*
G01X494305Y981951D02*
X494490Y982551D01*
X495520D01*
X495705Y981951D01*
Y981777D01*
X494305D01*
Y981951D01*
G37*
G36*
G01X490605Y981953D02*
X490790Y982553D01*
X491820D01*
X492005Y981953D01*
Y981778D01*
X490605D01*
Y981953D01*
G37*
G36*
G01X497995D02*
X498180Y982553D01*
X499210D01*
X499395Y981953D01*
Y981778D01*
X497995D01*
Y981953D01*
G37*
G36*
G01X494305Y981951D02*
X494490Y982551D01*
X495520D01*
X495705Y981951D01*
Y981777D01*
X494305D01*
Y981951D01*
G37*
G36*
G01X490605Y981953D02*
X490790Y982553D01*
X491820D01*
X492005Y981953D01*
Y981778D01*
X490605D01*
Y981953D01*
G37*
G36*
G01X496179Y978747D02*
X496364Y979347D01*
X497394D01*
X497579Y978747D01*
Y978573D01*
X496179D01*
Y978747D01*
G37*
G36*
G01X492512Y978749D02*
X492697Y979349D01*
X493727D01*
X493912Y978749D01*
Y978574D01*
X492512D01*
Y978749D01*
G37*
G36*
G01X499912D02*
X500097Y979349D01*
X501127D01*
X501312Y978749D01*
Y978574D01*
X499912D01*
Y978749D01*
G37*
G36*
G01X496179Y978747D02*
X496364Y979347D01*
X497394D01*
X497579Y978747D01*
Y978573D01*
X496179D01*
Y978747D01*
G37*
G36*
G01X492512Y978749D02*
X492697Y979349D01*
X493727D01*
X493912Y978749D01*
Y978574D01*
X492512D01*
Y978749D01*
G37*
G36*
G01X499912D02*
X500097Y979349D01*
X501127D01*
X501312Y978749D01*
Y978574D01*
X499912D01*
Y978749D01*
G37*
G36*
G01X497612Y980355D02*
X497427Y979755D01*
X496397D01*
X496212Y980355D01*
Y980530D01*
X497612D01*
Y980355D01*
G37*
G36*
G01X501312D02*
X501127Y979755D01*
X500097D01*
X499912Y980355D01*
Y980530D01*
X501312D01*
Y980355D01*
G37*
G36*
G01X497612D02*
X497427Y979755D01*
X496397D01*
X496212Y980355D01*
Y980530D01*
X497612D01*
Y980355D01*
G37*
G36*
G01X501312D02*
X501127Y979755D01*
X500097D01*
X499912Y980355D01*
Y980530D01*
X501312D01*
Y980355D01*
G37*
G36*
G01X499405Y977151D02*
X499220Y976551D01*
X498190D01*
X498005Y977151D01*
Y977326D01*
X499405D01*
Y977151D01*
G37*
G36*
G01D02*
X499220Y976551D01*
X498190D01*
X498005Y977151D01*
Y977326D01*
X499405D01*
Y977151D01*
G37*
G36*
G01X509696Y901267D02*
X510308Y901407D01*
X510823Y900515D01*
X510396Y900055D01*
X510245Y899968D01*
X509545Y901180D01*
X509696Y901267D01*
G37*
G36*
G01X512795Y898641D02*
X512980Y899241D01*
X514010D01*
X514195Y898641D01*
Y898467D01*
X512795D01*
Y898641D01*
G37*
G36*
G01X516495D02*
X516680Y899241D01*
X517710D01*
X517895Y898641D01*
Y898467D01*
X516495D01*
Y898641D01*
G37*
G36*
G01X509696Y901267D02*
X510308Y901407D01*
X510823Y900515D01*
X510396Y900055D01*
X510245Y899968D01*
X509545Y901180D01*
X509696Y901267D01*
G37*
G36*
G01X512795Y898641D02*
X512980Y899241D01*
X514010D01*
X514195Y898641D01*
Y898467D01*
X512795D01*
Y898641D01*
G37*
G36*
G01X516495D02*
X516680Y899241D01*
X517710D01*
X517895Y898641D01*
Y898467D01*
X516495D01*
Y898641D01*
G37*
G36*
G01X507849Y898059D02*
X508461Y898199D01*
X508976Y897307D01*
X508549Y896847D01*
X508398Y896760D01*
X507698Y897972D01*
X507849Y898059D01*
G37*
G36*
G01X511012Y895437D02*
X511197Y896037D01*
X512227D01*
X512412Y895437D01*
Y895262D01*
X511012D01*
Y895437D01*
G37*
G36*
G01X514679Y895435D02*
X514864Y896035D01*
X515894D01*
X516079Y895435D01*
Y895261D01*
X514679D01*
Y895435D01*
G37*
G36*
G01X507849Y898059D02*
X508461Y898199D01*
X508976Y897307D01*
X508549Y896847D01*
X508398Y896760D01*
X507698Y897972D01*
X507849Y898059D01*
G37*
G36*
G01X511012Y895437D02*
X511197Y896037D01*
X512227D01*
X512412Y895437D01*
Y895262D01*
X511012D01*
Y895437D01*
G37*
G36*
G01X514679Y895435D02*
X514864Y896035D01*
X515894D01*
X516079Y895435D01*
Y895261D01*
X514679D01*
Y895435D01*
G37*
G36*
G01X512412Y897043D02*
X512227Y896443D01*
X511197D01*
X511012Y897043D01*
Y897218D01*
X512412D01*
Y897043D01*
G37*
G36*
G01X509964Y897615D02*
X509352Y897475D01*
X508837Y898367D01*
X509264Y898827D01*
X509415Y898914D01*
X510115Y897702D01*
X509964Y897615D01*
G37*
G36*
G01X516112Y897043D02*
X515927Y896443D01*
X514897D01*
X514712Y897043D01*
Y897218D01*
X516112D01*
Y897043D01*
G37*
G36*
G01X512412D02*
X512227Y896443D01*
X511197D01*
X511012Y897043D01*
Y897218D01*
X512412D01*
Y897043D01*
G37*
G36*
G01X509964Y897615D02*
X509352Y897475D01*
X508837Y898367D01*
X509264Y898827D01*
X509415Y898914D01*
X510115Y897702D01*
X509964Y897615D01*
G37*
G36*
G01X516112Y897043D02*
X515927Y896443D01*
X514897D01*
X514712Y897043D01*
Y897218D01*
X516112D01*
Y897043D01*
G37*
G36*
G01X508093Y894447D02*
X507481Y894307D01*
X506966Y895199D01*
X507393Y895659D01*
X507544Y895746D01*
X508244Y894534D01*
X508093Y894447D01*
G37*
G36*
G01X514205Y893839D02*
X514020Y893239D01*
X512990D01*
X512805Y893839D01*
Y894014D01*
X514205D01*
Y893839D01*
G37*
G36*
G01X517905Y893841D02*
X517720Y893241D01*
X516690D01*
X516505Y893841D01*
Y894015D01*
X517905D01*
Y893841D01*
G37*
G36*
G01X510495Y893839D02*
X510310Y893239D01*
X509280D01*
X509095Y893839D01*
Y894014D01*
X510495D01*
Y893839D01*
G37*
G36*
G01X508093Y894447D02*
X507481Y894307D01*
X506966Y895199D01*
X507393Y895659D01*
X507544Y895746D01*
X508244Y894534D01*
X508093Y894447D01*
G37*
G36*
G01X514205Y893839D02*
X514020Y893239D01*
X512990D01*
X512805Y893839D01*
Y894014D01*
X514205D01*
Y893839D01*
G37*
G36*
G01X517905Y893841D02*
X517720Y893241D01*
X516690D01*
X516505Y893841D01*
Y894015D01*
X517905D01*
Y893841D01*
G37*
G36*
G01X510495Y893839D02*
X510310Y893239D01*
X509280D01*
X509095Y893839D01*
Y894014D01*
X510495D01*
Y893839D01*
G37*
G36*
G01X514195Y900249D02*
X514010Y899649D01*
X512980D01*
X512795Y900249D01*
Y900423D01*
X514195D01*
Y900249D01*
G37*
G36*
G01X517895D02*
X517710Y899649D01*
X516680D01*
X516495Y900249D01*
Y900423D01*
X517895D01*
Y900249D01*
G37*
G36*
G01X514195D02*
X514010Y899649D01*
X512980D01*
X512795Y900249D01*
Y900423D01*
X514195D01*
Y900249D01*
G37*
G36*
G01X517895D02*
X517710Y899649D01*
X516680D01*
X516495Y900249D01*
Y900423D01*
X517895D01*
Y900249D01*
G37*
G36*
G01X508712Y916269D02*
X508527Y915669D01*
X507497D01*
X507312Y916269D01*
Y916444D01*
X508712D01*
Y916269D01*
G37*
G36*
G01X512412D02*
X512227Y915669D01*
X511197D01*
X511012Y916269D01*
Y916444D01*
X512412D01*
Y916269D01*
G37*
G36*
G01X516112D02*
X515927Y915669D01*
X514897D01*
X514712Y916269D01*
Y916444D01*
X516112D01*
Y916269D01*
G37*
G36*
G01X505012D02*
X504827Y915669D01*
X503797D01*
X503612Y916269D01*
Y916444D01*
X505012D01*
Y916269D01*
G37*
G36*
G01X508712D02*
X508527Y915669D01*
X507497D01*
X507312Y916269D01*
Y916444D01*
X508712D01*
Y916269D01*
G37*
G36*
G01X512412D02*
X512227Y915669D01*
X511197D01*
X511012Y916269D01*
Y916444D01*
X512412D01*
Y916269D01*
G37*
G36*
G01X516112D02*
X515927Y915669D01*
X514897D01*
X514712Y916269D01*
Y916444D01*
X516112D01*
Y916269D01*
G37*
G36*
G01X505012D02*
X504827Y915669D01*
X503797D01*
X503612Y916269D01*
Y916444D01*
X505012D01*
Y916269D01*
G37*
G36*
G01X507279Y914661D02*
X507464Y915261D01*
X508494D01*
X508679Y914661D01*
Y914487D01*
X507279D01*
Y914661D01*
G37*
G36*
G01X511012Y914663D02*
X511197Y915263D01*
X512227D01*
X512412Y914663D01*
Y914488D01*
X511012D01*
Y914663D01*
G37*
G36*
G01X514712D02*
X514897Y915263D01*
X515927D01*
X516112Y914663D01*
Y914488D01*
X514712D01*
Y914663D01*
G37*
G36*
G01X507279Y914661D02*
X507464Y915261D01*
X508494D01*
X508679Y914661D01*
Y914487D01*
X507279D01*
Y914661D01*
G37*
G36*
G01X511012Y914663D02*
X511197Y915263D01*
X512227D01*
X512412Y914663D01*
Y914488D01*
X511012D01*
Y914663D01*
G37*
G36*
G01X514712D02*
X514897Y915263D01*
X515927D01*
X516112Y914663D01*
Y914488D01*
X514712D01*
Y914663D01*
G37*
G36*
G01X509105Y911457D02*
X509290Y912057D01*
X510320D01*
X510505Y911457D01*
Y911283D01*
X509105D01*
Y911457D01*
G37*
G36*
G01X512795Y911459D02*
X512980Y912059D01*
X514010D01*
X514195Y911459D01*
Y911284D01*
X512795D01*
Y911459D01*
G37*
G36*
G01X515243Y910887D02*
X515855Y911027D01*
X516370Y910135D01*
X515943Y909675D01*
X515792Y909588D01*
X515092Y910800D01*
X515243Y910887D01*
G37*
G36*
G01X509105Y911457D02*
X509290Y912057D01*
X510320D01*
X510505Y911457D01*
Y911283D01*
X509105D01*
Y911457D01*
G37*
G36*
G01X512795Y911459D02*
X512980Y912059D01*
X514010D01*
X514195Y911459D01*
Y911284D01*
X512795D01*
Y911459D01*
G37*
G36*
G01X515243Y910887D02*
X515855Y911027D01*
X516370Y910135D01*
X515943Y909675D01*
X515792Y909588D01*
X515092Y910800D01*
X515243Y910887D01*
G37*
G36*
G01X510505Y913067D02*
X510320Y912467D01*
X509290D01*
X509105Y913067D01*
Y913241D01*
X510505D01*
Y913067D01*
G37*
G36*
G01X514195Y913065D02*
X514010Y912465D01*
X512980D01*
X512795Y913065D01*
Y913240D01*
X514195D01*
Y913065D01*
G37*
G36*
G01X517364Y910432D02*
X516752Y910292D01*
X516237Y911184D01*
X516664Y911644D01*
X516815Y911731D01*
X517515Y910519D01*
X517364Y910432D01*
G37*
G36*
G01X510505Y913067D02*
X510320Y912467D01*
X509290D01*
X509105Y913067D01*
Y913241D01*
X510505D01*
Y913067D01*
G37*
G36*
G01X514195Y913065D02*
X514010Y912465D01*
X512980D01*
X512795Y913065D01*
Y913240D01*
X514195D01*
Y913065D01*
G37*
G36*
G01X517364Y910432D02*
X516752Y910292D01*
X516237Y911184D01*
X516664Y911644D01*
X516815Y911731D01*
X517515Y910519D01*
X517364Y910432D01*
G37*
G36*
G01X515515Y907225D02*
X514903Y907085D01*
X514388Y907977D01*
X514815Y908437D01*
X514966Y908524D01*
X515666Y907312D01*
X515515Y907225D01*
G37*
G36*
G01X517905Y906657D02*
X517720Y906057D01*
X516690D01*
X516505Y906657D01*
Y906831D01*
X517905D01*
Y906657D01*
G37*
G36*
G01X512412Y909861D02*
X512227Y909261D01*
X511197D01*
X511012Y909861D01*
Y910035D01*
X512412D01*
Y909861D01*
G37*
G36*
G01X515515Y907225D02*
X514903Y907085D01*
X514388Y907977D01*
X514815Y908437D01*
X514966Y908524D01*
X515666Y907312D01*
X515515Y907225D01*
G37*
G36*
G01X517905Y906657D02*
X517720Y906057D01*
X516690D01*
X516505Y906657D01*
Y906831D01*
X517905D01*
Y906657D01*
G37*
G36*
G01X512412Y909861D02*
X512227Y909261D01*
X511197D01*
X511012Y909861D01*
Y910035D01*
X512412D01*
Y909861D01*
G37*
G36*
G01X516112Y903453D02*
X515927Y902853D01*
X514897D01*
X514712Y903453D01*
Y903627D01*
X516112D01*
Y903453D01*
G37*
G36*
G01X510495Y906657D02*
X510310Y906057D01*
X509280D01*
X509095Y906657D01*
Y906831D01*
X510495D01*
Y906657D01*
G37*
G36*
G01X513643Y904059D02*
X513031Y903919D01*
X512516Y904811D01*
X512943Y905271D01*
X513094Y905358D01*
X513794Y904146D01*
X513643Y904059D01*
G37*
G36*
G01X516112Y903453D02*
X515927Y902853D01*
X514897D01*
X514712Y903453D01*
Y903627D01*
X516112D01*
Y903453D01*
G37*
G36*
G01X510495Y906657D02*
X510310Y906057D01*
X509280D01*
X509095Y906657D01*
Y906831D01*
X510495D01*
Y906657D01*
G37*
G36*
G01X513643Y904059D02*
X513031Y903919D01*
X512516Y904811D01*
X512943Y905271D01*
X513094Y905358D01*
X513794Y904146D01*
X513643Y904059D01*
G37*
G36*
G01X511571Y904431D02*
X512183Y904571D01*
X512698Y903679D01*
X512271Y903219D01*
X512120Y903132D01*
X511420Y904344D01*
X511571Y904431D01*
G37*
G36*
G01X514712Y901845D02*
X514897Y902445D01*
X515927D01*
X516112Y901845D01*
Y901671D01*
X514712D01*
Y901845D01*
G37*
G36*
G01X511571Y904431D02*
X512183Y904571D01*
X512698Y903679D01*
X512271Y903219D01*
X512120Y903132D01*
X511420Y904344D01*
X511571Y904431D01*
G37*
G36*
G01X514712Y901845D02*
X514897Y902445D01*
X515927D01*
X516112Y901845D01*
Y901671D01*
X514712D01*
Y901845D01*
G37*
G36*
G01X513392Y907685D02*
X514004Y907825D01*
X514519Y906933D01*
X514092Y906473D01*
X513941Y906386D01*
X513241Y907598D01*
X513392Y907685D01*
G37*
G36*
G01X516505Y905049D02*
X516690Y905649D01*
X517720D01*
X517905Y905049D01*
Y904875D01*
X516505D01*
Y905049D01*
G37*
G36*
G01X507312Y908253D02*
X507497Y908853D01*
X508527D01*
X508712Y908253D01*
Y908079D01*
X507312D01*
Y908253D01*
G37*
G36*
G01X511012D02*
X511197Y908853D01*
X512227D01*
X512412Y908253D01*
Y908079D01*
X511012D01*
Y908253D01*
G37*
G36*
G01X513392Y907685D02*
X514004Y907825D01*
X514519Y906933D01*
X514092Y906473D01*
X513941Y906386D01*
X513241Y907598D01*
X513392Y907685D01*
G37*
G36*
G01X516505Y905049D02*
X516690Y905649D01*
X517720D01*
X517905Y905049D01*
Y904875D01*
X516505D01*
Y905049D01*
G37*
G36*
G01X507312Y908253D02*
X507497Y908853D01*
X508527D01*
X508712Y908253D01*
Y908079D01*
X507312D01*
Y908253D01*
G37*
G36*
G01X511012D02*
X511197Y908853D01*
X512227D01*
X512412Y908253D01*
Y908079D01*
X511012D01*
Y908253D01*
G37*
G36*
G01X511787Y900871D02*
X511175Y900731D01*
X510660Y901623D01*
X511087Y902083D01*
X511238Y902170D01*
X511938Y900958D01*
X511787Y900871D01*
G37*
G36*
G01D02*
X511175Y900731D01*
X510660Y901623D01*
X511087Y902083D01*
X511238Y902170D01*
X511938Y900958D01*
X511787Y900871D01*
G37*
G36*
G01X510505Y932291D02*
X510320Y931691D01*
X509290D01*
X509105Y932291D01*
Y932466D01*
X510505D01*
Y932291D01*
G37*
G36*
G01X514195D02*
X514010Y931691D01*
X512980D01*
X512795Y932291D01*
Y932465D01*
X514195D01*
Y932291D01*
G37*
G36*
G01X517895D02*
X517710Y931691D01*
X516680D01*
X516495Y932291D01*
Y932465D01*
X517895D01*
Y932291D01*
G37*
G36*
G01X510505D02*
X510320Y931691D01*
X509290D01*
X509105Y932291D01*
Y932466D01*
X510505D01*
Y932291D01*
G37*
G36*
G01X514195D02*
X514010Y931691D01*
X512980D01*
X512795Y932291D01*
Y932465D01*
X514195D01*
Y932291D01*
G37*
G36*
G01X517895D02*
X517710Y931691D01*
X516680D01*
X516495Y932291D01*
Y932465D01*
X517895D01*
Y932291D01*
G37*
G36*
G01X509105Y930683D02*
X509290Y931283D01*
X510320D01*
X510505Y930683D01*
Y930509D01*
X509105D01*
Y930683D01*
G37*
G36*
G01X512795Y930685D02*
X512980Y931285D01*
X514010D01*
X514195Y930685D01*
Y930510D01*
X512795D01*
Y930685D01*
G37*
G36*
G01X516495D02*
X516680Y931285D01*
X517710D01*
X517895Y930685D01*
Y930510D01*
X516495D01*
Y930685D01*
G37*
G36*
G01X509105Y930683D02*
X509290Y931283D01*
X510320D01*
X510505Y930683D01*
Y930509D01*
X509105D01*
Y930683D01*
G37*
G36*
G01X512795Y930685D02*
X512980Y931285D01*
X514010D01*
X514195Y930685D01*
Y930510D01*
X512795D01*
Y930685D01*
G37*
G36*
G01X516495D02*
X516680Y931285D01*
X517710D01*
X517895Y930685D01*
Y930510D01*
X516495D01*
Y930685D01*
G37*
G36*
G01X506795Y919473D02*
X506610Y918873D01*
X505580D01*
X505395Y919473D01*
Y919648D01*
X506795D01*
Y919473D01*
G37*
G36*
G01X510528Y919475D02*
X510343Y918875D01*
X509313D01*
X509128Y919475D01*
Y919649D01*
X510528D01*
Y919475D01*
G37*
G36*
G01X514195Y919473D02*
X514010Y918873D01*
X512980D01*
X512795Y919473D01*
Y919648D01*
X514195D01*
Y919473D01*
G37*
G36*
G01X517895D02*
X517710Y918873D01*
X516680D01*
X516495Y919473D01*
Y919648D01*
X517895D01*
Y919473D01*
G37*
G36*
G01X506795D02*
X506610Y918873D01*
X505580D01*
X505395Y919473D01*
Y919648D01*
X506795D01*
Y919473D01*
G37*
G36*
G01X510528Y919475D02*
X510343Y918875D01*
X509313D01*
X509128Y919475D01*
Y919649D01*
X510528D01*
Y919475D01*
G37*
G36*
G01X514195Y919473D02*
X514010Y918873D01*
X512980D01*
X512795Y919473D01*
Y919648D01*
X514195D01*
Y919473D01*
G37*
G36*
G01X517895D02*
X517710Y918873D01*
X516680D01*
X516495Y919473D01*
Y919648D01*
X517895D01*
Y919473D01*
G37*
G36*
G01X510962Y921069D02*
X511147Y921669D01*
X512177D01*
X512362Y921069D01*
Y920895D01*
X510962D01*
Y921069D01*
G37*
G36*
G01X514662D02*
X514847Y921669D01*
X515877D01*
X516062Y921069D01*
Y920895D01*
X514662D01*
Y921069D01*
G37*
G36*
G01X510962D02*
X511147Y921669D01*
X512177D01*
X512362Y921069D01*
Y920895D01*
X510962D01*
Y921069D01*
G37*
G36*
G01X514662D02*
X514847Y921669D01*
X515877D01*
X516062Y921069D01*
Y920895D01*
X514662D01*
Y921069D01*
G37*
G36*
G01X505395Y917867D02*
X505580Y918467D01*
X506610D01*
X506795Y917867D01*
Y917692D01*
X505395D01*
Y917867D01*
G37*
G36*
G01X509095D02*
X509280Y918467D01*
X510310D01*
X510495Y917867D01*
Y917692D01*
X509095D01*
Y917867D01*
G37*
G36*
G01X512795D02*
X512980Y918467D01*
X514010D01*
X514195Y917867D01*
Y917692D01*
X512795D01*
Y917867D01*
G37*
G36*
G01X516495D02*
X516680Y918467D01*
X517710D01*
X517895Y917867D01*
Y917692D01*
X516495D01*
Y917867D01*
G37*
G36*
G01X505395D02*
X505580Y918467D01*
X506610D01*
X506795Y917867D01*
Y917692D01*
X505395D01*
Y917867D01*
G37*
G36*
G01X509095D02*
X509280Y918467D01*
X510310D01*
X510495Y917867D01*
Y917692D01*
X509095D01*
Y917867D01*
G37*
G36*
G01X512795D02*
X512980Y918467D01*
X514010D01*
X514195Y917867D01*
Y917692D01*
X512795D01*
Y917867D01*
G37*
G36*
G01X516495D02*
X516680Y918467D01*
X517710D01*
X517895Y917867D01*
Y917692D01*
X516495D01*
Y917867D01*
G37*
G36*
G01X512412Y929087D02*
X512227Y928487D01*
X511197D01*
X511012Y929087D01*
Y929261D01*
X512412D01*
Y929087D01*
G37*
G36*
G01X516112D02*
X515927Y928487D01*
X514897D01*
X514712Y929087D01*
Y929261D01*
X516112D01*
Y929087D01*
G37*
G36*
G01X512412D02*
X512227Y928487D01*
X511197D01*
X511012Y929087D01*
Y929261D01*
X512412D01*
Y929087D01*
G37*
G36*
G01X516112D02*
X515927Y928487D01*
X514897D01*
X514712Y929087D01*
Y929261D01*
X516112D01*
Y929087D01*
G37*
G36*
G01X512402Y922679D02*
X512217Y922079D01*
X511187D01*
X511002Y922679D01*
Y922853D01*
X512402D01*
Y922679D01*
G37*
G36*
G01X516112D02*
X515927Y922079D01*
X514897D01*
X514712Y922679D01*
Y922853D01*
X516112D01*
Y922679D01*
G37*
G36*
G01X512402D02*
X512217Y922079D01*
X511187D01*
X511002Y922679D01*
Y922853D01*
X512402D01*
Y922679D01*
G37*
G36*
G01X516112D02*
X515927Y922079D01*
X514897D01*
X514712Y922679D01*
Y922853D01*
X516112D01*
Y922679D01*
G37*
G36*
G01X510941Y927477D02*
X511126Y928077D01*
X512156D01*
X512341Y927477D01*
Y927302D01*
X510941D01*
Y927477D01*
G37*
G36*
G01X514665Y927479D02*
X514850Y928079D01*
X515880D01*
X516065Y927479D01*
Y927304D01*
X514665D01*
Y927479D01*
G37*
G36*
G01X510941Y927477D02*
X511126Y928077D01*
X512156D01*
X512341Y927477D01*
Y927302D01*
X510941D01*
Y927477D01*
G37*
G36*
G01X514665Y927479D02*
X514850Y928079D01*
X515880D01*
X516065Y927479D01*
Y927304D01*
X514665D01*
Y927479D01*
G37*
G36*
G01X509128Y924275D02*
X509313Y924875D01*
X510343D01*
X510528Y924275D01*
Y924100D01*
X509128D01*
Y924275D01*
G37*
G36*
G01X512795D02*
X512980Y924875D01*
X514010D01*
X514195Y924275D01*
Y924101D01*
X512795D01*
Y924275D01*
G37*
G36*
G01X516505D02*
X516690Y924875D01*
X517720D01*
X517905Y924275D01*
Y924101D01*
X516505D01*
Y924275D01*
G37*
G36*
G01X509128D02*
X509313Y924875D01*
X510343D01*
X510528Y924275D01*
Y924100D01*
X509128D01*
Y924275D01*
G37*
G36*
G01X512795D02*
X512980Y924875D01*
X514010D01*
X514195Y924275D01*
Y924101D01*
X512795D01*
Y924275D01*
G37*
G36*
G01X516505D02*
X516690Y924875D01*
X517720D01*
X517905Y924275D01*
Y924101D01*
X516505D01*
Y924275D01*
G37*
G36*
G01X514242Y925883D02*
X514057Y925283D01*
X513027D01*
X512842Y925883D01*
Y926058D01*
X514242D01*
Y925883D01*
G37*
G36*
G01X517942D02*
X517757Y925283D01*
X516727D01*
X516542Y925883D01*
Y926058D01*
X517942D01*
Y925883D01*
G37*
G36*
G01X514242D02*
X514057Y925283D01*
X513027D01*
X512842Y925883D01*
Y926058D01*
X514242D01*
Y925883D01*
G37*
G36*
G01X517942D02*
X517757Y925283D01*
X516727D01*
X516542Y925883D01*
Y926058D01*
X517942D01*
Y925883D01*
G37*
G36*
G01X508679Y948313D02*
X508494Y947713D01*
X507464D01*
X507279Y948313D01*
Y948488D01*
X508679D01*
Y948313D01*
G37*
G36*
G01X512412D02*
X512227Y947713D01*
X511197D01*
X511012Y948313D01*
Y948487D01*
X512412D01*
Y948313D01*
G37*
G36*
G01X516112D02*
X515927Y947713D01*
X514897D01*
X514712Y948313D01*
Y948487D01*
X516112D01*
Y948313D01*
G37*
G36*
G01X508679D02*
X508494Y947713D01*
X507464D01*
X507279Y948313D01*
Y948488D01*
X508679D01*
Y948313D01*
G37*
G36*
G01X512412D02*
X512227Y947713D01*
X511197D01*
X511012Y948313D01*
Y948487D01*
X512412D01*
Y948313D01*
G37*
G36*
G01X516112D02*
X515927Y947713D01*
X514897D01*
X514712Y948313D01*
Y948487D01*
X516112D01*
Y948313D01*
G37*
G36*
G01X510962Y940295D02*
X511147Y940895D01*
X512177D01*
X512362Y940295D01*
Y940121D01*
X510962D01*
Y940295D01*
G37*
G36*
G01X514662D02*
X514847Y940895D01*
X515877D01*
X516062Y940295D01*
Y940121D01*
X514662D01*
Y940295D01*
G37*
G36*
G01X510962D02*
X511147Y940895D01*
X512177D01*
X512362Y940295D01*
Y940121D01*
X510962D01*
Y940295D01*
G37*
G36*
G01X514662D02*
X514847Y940895D01*
X515877D01*
X516062Y940295D01*
Y940121D01*
X514662D01*
Y940295D01*
G37*
G36*
G01X509142Y937091D02*
X509327Y937691D01*
X510357D01*
X510542Y937091D01*
Y936916D01*
X509142D01*
Y937091D01*
G37*
G36*
G01X512842D02*
X513027Y937691D01*
X514057D01*
X514242Y937091D01*
Y936916D01*
X512842D01*
Y937091D01*
G37*
G36*
G01X516542D02*
X516727Y937691D01*
X517757D01*
X517942Y937091D01*
Y936916D01*
X516542D01*
Y937091D01*
G37*
G36*
G01X509142D02*
X509327Y937691D01*
X510357D01*
X510542Y937091D01*
Y936916D01*
X509142D01*
Y937091D01*
G37*
G36*
G01X512842D02*
X513027Y937691D01*
X514057D01*
X514242Y937091D01*
Y936916D01*
X512842D01*
Y937091D01*
G37*
G36*
G01X516542D02*
X516727Y937691D01*
X517757D01*
X517942Y937091D01*
Y936916D01*
X516542D01*
Y937091D01*
G37*
G36*
G01X510545Y938701D02*
X510360Y938101D01*
X509330D01*
X509145Y938701D01*
Y938875D01*
X510545D01*
Y938701D01*
G37*
G36*
G01X514245D02*
X514060Y938101D01*
X513030D01*
X512845Y938701D01*
Y938875D01*
X514245D01*
Y938701D01*
G37*
G36*
G01X517945D02*
X517760Y938101D01*
X516730D01*
X516545Y938701D01*
Y938875D01*
X517945D01*
Y938701D01*
G37*
G36*
G01X510545D02*
X510360Y938101D01*
X509330D01*
X509145Y938701D01*
Y938875D01*
X510545D01*
Y938701D01*
G37*
G36*
G01X514245D02*
X514060Y938101D01*
X513030D01*
X512845Y938701D01*
Y938875D01*
X514245D01*
Y938701D01*
G37*
G36*
G01X517945D02*
X517760Y938101D01*
X516730D01*
X516545Y938701D01*
Y938875D01*
X517945D01*
Y938701D01*
G37*
G36*
G01X512365Y935497D02*
X512180Y934897D01*
X511150D01*
X510965Y935497D01*
Y935671D01*
X512365D01*
Y935497D01*
G37*
G36*
G01X508665D02*
X508480Y934897D01*
X507450D01*
X507265Y935497D01*
Y935671D01*
X508665D01*
Y935497D01*
G37*
G36*
G01X516065D02*
X515880Y934897D01*
X514850D01*
X514665Y935497D01*
Y935671D01*
X516065D01*
Y935497D01*
G37*
G36*
G01X512365D02*
X512180Y934897D01*
X511150D01*
X510965Y935497D01*
Y935671D01*
X512365D01*
Y935497D01*
G37*
G36*
G01X508665D02*
X508480Y934897D01*
X507450D01*
X507265Y935497D01*
Y935671D01*
X508665D01*
Y935497D01*
G37*
G36*
G01X516065D02*
X515880Y934897D01*
X514850D01*
X514665Y935497D01*
Y935671D01*
X516065D01*
Y935497D01*
G37*
G36*
G01X507279Y933887D02*
X507464Y934487D01*
X508494D01*
X508679Y933887D01*
Y933713D01*
X507279D01*
Y933887D01*
G37*
G36*
G01X511012Y933889D02*
X511197Y934489D01*
X512227D01*
X512412Y933889D01*
Y933714D01*
X511012D01*
Y933889D01*
G37*
G36*
G01X514712D02*
X514897Y934489D01*
X515927D01*
X516112Y933889D01*
Y933714D01*
X514712D01*
Y933889D01*
G37*
G36*
G01X507279Y933887D02*
X507464Y934487D01*
X508494D01*
X508679Y933887D01*
Y933713D01*
X507279D01*
Y933887D01*
G37*
G36*
G01X511012Y933889D02*
X511197Y934489D01*
X512227D01*
X512412Y933889D01*
Y933714D01*
X511012D01*
Y933889D01*
G37*
G36*
G01X514712D02*
X514897Y934489D01*
X515927D01*
X516112Y933889D01*
Y933714D01*
X514712D01*
Y933889D01*
G37*
G36*
G01X510495Y945107D02*
X510310Y944507D01*
X509280D01*
X509095Y945107D01*
Y945282D01*
X510495D01*
Y945107D01*
G37*
G36*
G01X514195D02*
X514010Y944507D01*
X512980D01*
X512795Y945107D01*
Y945282D01*
X514195D01*
Y945107D01*
G37*
G36*
G01X517905D02*
X517720Y944507D01*
X516690D01*
X516505Y945107D01*
Y945282D01*
X517905D01*
Y945107D01*
G37*
G36*
G01X510495D02*
X510310Y944507D01*
X509280D01*
X509095Y945107D01*
Y945282D01*
X510495D01*
Y945107D01*
G37*
G36*
G01X514195D02*
X514010Y944507D01*
X512980D01*
X512795Y945107D01*
Y945282D01*
X514195D01*
Y945107D01*
G37*
G36*
G01X517905D02*
X517720Y944507D01*
X516690D01*
X516505Y945107D01*
Y945282D01*
X517905D01*
Y945107D01*
G37*
G36*
G01X512795Y943501D02*
X512980Y944101D01*
X514010D01*
X514195Y943501D01*
Y943326D01*
X512795D01*
Y943501D01*
G37*
G36*
G01X516505D02*
X516690Y944101D01*
X517720D01*
X517905Y943501D01*
Y943326D01*
X516505D01*
Y943501D01*
G37*
G36*
G01X512795D02*
X512980Y944101D01*
X514010D01*
X514195Y943501D01*
Y943326D01*
X512795D01*
Y943501D01*
G37*
G36*
G01X516505D02*
X516690Y944101D01*
X517720D01*
X517905Y943501D01*
Y943326D01*
X516505D01*
Y943501D01*
G37*
G36*
G01X507312Y946705D02*
X507497Y947305D01*
X508527D01*
X508712Y946705D01*
Y946531D01*
X507312D01*
Y946705D01*
G37*
G36*
G01X511012D02*
X511197Y947305D01*
X512227D01*
X512412Y946705D01*
Y946531D01*
X511012D01*
Y946705D01*
G37*
G36*
G01X514712D02*
X514897Y947305D01*
X515927D01*
X516112Y946705D01*
Y946531D01*
X514712D01*
Y946705D01*
G37*
G36*
G01X507312D02*
X507497Y947305D01*
X508527D01*
X508712Y946705D01*
Y946531D01*
X507312D01*
Y946705D01*
G37*
G36*
G01X511012D02*
X511197Y947305D01*
X512227D01*
X512412Y946705D01*
Y946531D01*
X511012D01*
Y946705D01*
G37*
G36*
G01X514712D02*
X514897Y947305D01*
X515927D01*
X516112Y946705D01*
Y946531D01*
X514712D01*
Y946705D01*
G37*
G36*
G01X516112Y941903D02*
X515927Y941303D01*
X514897D01*
X514712Y941903D01*
Y942078D01*
X516112D01*
Y941903D01*
G37*
G36*
G01X512378Y941905D02*
X512193Y941305D01*
X511163D01*
X510978Y941905D01*
Y942080D01*
X512378D01*
Y941905D01*
G37*
G36*
G01X516112Y941903D02*
X515927Y941303D01*
X514897D01*
X514712Y941903D01*
Y942078D01*
X516112D01*
Y941903D01*
G37*
G36*
G01X512378Y941905D02*
X512193Y941305D01*
X511163D01*
X510978Y941905D01*
Y942080D01*
X512378D01*
Y941905D01*
G37*
G36*
G01X503612Y953113D02*
X503797Y953713D01*
X504827D01*
X505012Y953113D01*
Y952939D01*
X503612D01*
Y953113D01*
G37*
G36*
G01X511012D02*
X511197Y953713D01*
X512227D01*
X512412Y953113D01*
Y952939D01*
X511012D01*
Y953113D01*
G37*
G36*
G01X507279D02*
X507464Y953713D01*
X508494D01*
X508679Y953113D01*
Y952938D01*
X507279D01*
Y953113D01*
G37*
G36*
G01X514712D02*
X514897Y953713D01*
X515927D01*
X516112Y953113D01*
Y952939D01*
X514712D01*
Y953113D01*
G37*
G36*
G01X503612D02*
X503797Y953713D01*
X504827D01*
X505012Y953113D01*
Y952939D01*
X503612D01*
Y953113D01*
G37*
G36*
G01X511012D02*
X511197Y953713D01*
X512227D01*
X512412Y953113D01*
Y952939D01*
X511012D01*
Y953113D01*
G37*
G36*
G01X507279D02*
X507464Y953713D01*
X508494D01*
X508679Y953113D01*
Y952938D01*
X507279D01*
Y953113D01*
G37*
G36*
G01X514712D02*
X514897Y953713D01*
X515927D01*
X516112Y953113D01*
Y952939D01*
X514712D01*
Y953113D01*
G37*
G36*
G01X509105Y949909D02*
X509290Y950509D01*
X510320D01*
X510505Y949909D01*
Y949734D01*
X509105D01*
Y949909D01*
G37*
G36*
G01X505405D02*
X505590Y950509D01*
X506620D01*
X506805Y949909D01*
Y949735D01*
X505405D01*
Y949909D01*
G37*
G36*
G01X512795D02*
X512980Y950509D01*
X514010D01*
X514195Y949909D01*
Y949735D01*
X512795D01*
Y949909D01*
G37*
G36*
G01X516495D02*
X516680Y950509D01*
X517710D01*
X517895Y949909D01*
Y949735D01*
X516495D01*
Y949909D01*
G37*
G36*
G01X509105D02*
X509290Y950509D01*
X510320D01*
X510505Y949909D01*
Y949734D01*
X509105D01*
Y949909D01*
G37*
G36*
G01X505405D02*
X505590Y950509D01*
X506620D01*
X506805Y949909D01*
Y949735D01*
X505405D01*
Y949909D01*
G37*
G36*
G01X512795D02*
X512980Y950509D01*
X514010D01*
X514195Y949909D01*
Y949735D01*
X512795D01*
Y949909D01*
G37*
G36*
G01X516495D02*
X516680Y950509D01*
X517710D01*
X517895Y949909D01*
Y949735D01*
X516495D01*
Y949909D01*
G37*
G36*
G01X506805Y951517D02*
X506620Y950917D01*
X505590D01*
X505405Y951517D01*
Y951691D01*
X506805D01*
Y951517D01*
G37*
G36*
G01X510505D02*
X510320Y950917D01*
X509290D01*
X509105Y951517D01*
Y951692D01*
X510505D01*
Y951517D01*
G37*
G36*
G01X514195D02*
X514010Y950917D01*
X512980D01*
X512795Y951517D01*
Y951691D01*
X514195D01*
Y951517D01*
G37*
G36*
G01X517895D02*
X517710Y950917D01*
X516680D01*
X516495Y951517D01*
Y951691D01*
X517895D01*
Y951517D01*
G37*
G36*
G01X506805D02*
X506620Y950917D01*
X505590D01*
X505405Y951517D01*
Y951691D01*
X506805D01*
Y951517D01*
G37*
G36*
G01X510505D02*
X510320Y950917D01*
X509290D01*
X509105Y951517D01*
Y951692D01*
X510505D01*
Y951517D01*
G37*
G36*
G01X514195D02*
X514010Y950917D01*
X512980D01*
X512795Y951517D01*
Y951691D01*
X514195D01*
Y951517D01*
G37*
G36*
G01X517895D02*
X517710Y950917D01*
X516680D01*
X516495Y951517D01*
Y951691D01*
X517895D01*
Y951517D01*
G37*
G36*
G01X503612Y959523D02*
X503797Y960123D01*
X504827D01*
X505012Y959523D01*
Y959348D01*
X503612D01*
Y959523D01*
G37*
G36*
G01X507302Y959521D02*
X507487Y960121D01*
X508517D01*
X508702Y959521D01*
Y959347D01*
X507302D01*
Y959521D01*
G37*
G36*
G01X511002Y959523D02*
X511187Y960123D01*
X512217D01*
X512402Y959523D01*
Y959348D01*
X511002D01*
Y959523D01*
G37*
G36*
G01X514712D02*
X514897Y960123D01*
X515927D01*
X516112Y959523D01*
Y959348D01*
X514712D01*
Y959523D01*
G37*
G36*
G01X503612D02*
X503797Y960123D01*
X504827D01*
X505012Y959523D01*
Y959348D01*
X503612D01*
Y959523D01*
G37*
G36*
G01X507302Y959521D02*
X507487Y960121D01*
X508517D01*
X508702Y959521D01*
Y959347D01*
X507302D01*
Y959521D01*
G37*
G36*
G01X511002Y959523D02*
X511187Y960123D01*
X512217D01*
X512402Y959523D01*
Y959348D01*
X511002D01*
Y959523D01*
G37*
G36*
G01X514712D02*
X514897Y960123D01*
X515927D01*
X516112Y959523D01*
Y959348D01*
X514712D01*
Y959523D01*
G37*
G36*
G01X506795Y957925D02*
X506610Y957325D01*
X505580D01*
X505395Y957925D01*
Y958100D01*
X506795D01*
Y957925D01*
G37*
G36*
G01X510528Y957927D02*
X510343Y957327D01*
X509313D01*
X509128Y957927D01*
Y958101D01*
X510528D01*
Y957927D01*
G37*
G36*
G01X514195Y957925D02*
X514010Y957325D01*
X512980D01*
X512795Y957925D01*
Y958100D01*
X514195D01*
Y957925D01*
G37*
G36*
G01X517895D02*
X517710Y957325D01*
X516680D01*
X516495Y957925D01*
Y958100D01*
X517895D01*
Y957925D01*
G37*
G36*
G01X506795D02*
X506610Y957325D01*
X505580D01*
X505395Y957925D01*
Y958100D01*
X506795D01*
Y957925D01*
G37*
G36*
G01X510528Y957927D02*
X510343Y957327D01*
X509313D01*
X509128Y957927D01*
Y958101D01*
X510528D01*
Y957927D01*
G37*
G36*
G01X514195Y957925D02*
X514010Y957325D01*
X512980D01*
X512795Y957925D01*
Y958100D01*
X514195D01*
Y957925D01*
G37*
G36*
G01X517895D02*
X517710Y957325D01*
X516680D01*
X516495Y957925D01*
Y958100D01*
X517895D01*
Y957925D01*
G37*
G36*
G01X509128Y962725D02*
X509313Y963325D01*
X510343D01*
X510528Y962725D01*
Y962551D01*
X509128D01*
Y962725D01*
G37*
G36*
G01X512795Y962727D02*
X512980Y963327D01*
X514010D01*
X514195Y962727D01*
Y962552D01*
X512795D01*
Y962727D01*
G37*
G36*
G01X516505D02*
X516690Y963327D01*
X517720D01*
X517905Y962727D01*
Y962552D01*
X516505D01*
Y962727D01*
G37*
G36*
G01X505395D02*
X505580Y963327D01*
X506610D01*
X506795Y962727D01*
Y962552D01*
X505395D01*
Y962727D01*
G37*
G36*
G01X501705Y962725D02*
X501890Y963325D01*
X502920D01*
X503105Y962725D01*
Y962551D01*
X501705D01*
Y962725D01*
G37*
G36*
G01X509128D02*
X509313Y963325D01*
X510343D01*
X510528Y962725D01*
Y962551D01*
X509128D01*
Y962725D01*
G37*
G36*
G01X512795Y962727D02*
X512980Y963327D01*
X514010D01*
X514195Y962727D01*
Y962552D01*
X512795D01*
Y962727D01*
G37*
G36*
G01X516505D02*
X516690Y963327D01*
X517720D01*
X517905Y962727D01*
Y962552D01*
X516505D01*
Y962727D01*
G37*
G36*
G01X505395D02*
X505580Y963327D01*
X506610D01*
X506795Y962727D01*
Y962552D01*
X505395D01*
Y962727D01*
G37*
G36*
G01X501705Y962725D02*
X501890Y963325D01*
X502920D01*
X503105Y962725D01*
Y962551D01*
X501705D01*
Y962725D01*
G37*
G36*
G01X512402Y961129D02*
X512217Y960529D01*
X511187D01*
X511002Y961129D01*
Y961304D01*
X512402D01*
Y961129D01*
G37*
G36*
G01X516112D02*
X515927Y960529D01*
X514897D01*
X514712Y961129D01*
Y961304D01*
X516112D01*
Y961129D01*
G37*
G36*
G01X512402D02*
X512217Y960529D01*
X511187D01*
X511002Y961129D01*
Y961304D01*
X512402D01*
Y961129D01*
G37*
G36*
G01X516112D02*
X515927Y960529D01*
X514897D01*
X514712Y961129D01*
Y961304D01*
X516112D01*
Y961129D01*
G37*
G36*
G01X505395Y981953D02*
X505580Y982553D01*
X506610D01*
X506795Y981953D01*
Y981778D01*
X505395D01*
Y981953D01*
G37*
G36*
G01X509128Y981951D02*
X509313Y982551D01*
X510343D01*
X510528Y981951D01*
Y981777D01*
X509128D01*
Y981951D01*
G37*
G36*
G01X512795Y981953D02*
X512980Y982553D01*
X514010D01*
X514195Y981953D01*
Y981778D01*
X512795D01*
Y981953D01*
G37*
G36*
G01X516505D02*
X516690Y982553D01*
X517720D01*
X517905Y981953D01*
Y981778D01*
X516505D01*
Y981953D01*
G37*
G36*
G01X501695D02*
X501880Y982553D01*
X502910D01*
X503095Y981953D01*
Y981778D01*
X501695D01*
Y981953D01*
G37*
G36*
G01X505395D02*
X505580Y982553D01*
X506610D01*
X506795Y981953D01*
Y981778D01*
X505395D01*
Y981953D01*
G37*
G36*
G01X509128Y981951D02*
X509313Y982551D01*
X510343D01*
X510528Y981951D01*
Y981777D01*
X509128D01*
Y981951D01*
G37*
G36*
G01X512795Y981953D02*
X512980Y982553D01*
X514010D01*
X514195Y981953D01*
Y981778D01*
X512795D01*
Y981953D01*
G37*
G36*
G01X516505D02*
X516690Y982553D01*
X517720D01*
X517905Y981953D01*
Y981778D01*
X516505D01*
Y981953D01*
G37*
G36*
G01X501695D02*
X501880Y982553D01*
X502910D01*
X503095Y981953D01*
Y981778D01*
X501695D01*
Y981953D01*
G37*
G36*
G01X503612Y978749D02*
X503797Y979349D01*
X504827D01*
X505012Y978749D01*
Y978574D01*
X503612D01*
Y978749D01*
G37*
G36*
G01X507302Y978747D02*
X507487Y979347D01*
X508517D01*
X508702Y978747D01*
Y978573D01*
X507302D01*
Y978747D01*
G37*
G36*
G01X511002Y978749D02*
X511187Y979349D01*
X512217D01*
X512402Y978749D01*
Y978574D01*
X511002D01*
Y978749D01*
G37*
G36*
G01X514679Y978747D02*
X514864Y979347D01*
X515894D01*
X516079Y978747D01*
Y978573D01*
X514679D01*
Y978747D01*
G37*
G36*
G01X503612Y978749D02*
X503797Y979349D01*
X504827D01*
X505012Y978749D01*
Y978574D01*
X503612D01*
Y978749D01*
G37*
G36*
G01X507302Y978747D02*
X507487Y979347D01*
X508517D01*
X508702Y978747D01*
Y978573D01*
X507302D01*
Y978747D01*
G37*
G36*
G01X511002Y978749D02*
X511187Y979349D01*
X512217D01*
X512402Y978749D01*
Y978574D01*
X511002D01*
Y978749D01*
G37*
G36*
G01X514679Y978747D02*
X514864Y979347D01*
X515894D01*
X516079Y978747D01*
Y978573D01*
X514679D01*
Y978747D01*
G37*
G36*
G01X505012Y980355D02*
X504827Y979755D01*
X503797D01*
X503612Y980355D01*
Y980530D01*
X505012D01*
Y980355D01*
G37*
G36*
G01X508702Y980357D02*
X508517Y979757D01*
X507487D01*
X507302Y980357D01*
Y980531D01*
X508702D01*
Y980357D01*
G37*
G36*
G01X512402Y980355D02*
X512217Y979755D01*
X511187D01*
X511002Y980355D01*
Y980530D01*
X512402D01*
Y980355D01*
G37*
G36*
G01X516112D02*
X515927Y979755D01*
X514897D01*
X514712Y980355D01*
Y980530D01*
X516112D01*
Y980355D01*
G37*
G36*
G01X505012D02*
X504827Y979755D01*
X503797D01*
X503612Y980355D01*
Y980530D01*
X505012D01*
Y980355D01*
G37*
G36*
G01X508702Y980357D02*
X508517Y979757D01*
X507487D01*
X507302Y980357D01*
Y980531D01*
X508702D01*
Y980357D01*
G37*
G36*
G01X512402Y980355D02*
X512217Y979755D01*
X511187D01*
X511002Y980355D01*
Y980530D01*
X512402D01*
Y980355D01*
G37*
G36*
G01X516112D02*
X515927Y979755D01*
X514897D01*
X514712Y980355D01*
Y980530D01*
X516112D01*
Y980355D01*
G37*
G36*
G01X506795Y977151D02*
X506610Y976551D01*
X505580D01*
X505395Y977151D01*
Y977325D01*
X506795D01*
Y977151D01*
G37*
G36*
G01X510528D02*
X510343Y976551D01*
X509313D01*
X509128Y977151D01*
Y977326D01*
X510528D01*
Y977151D01*
G37*
G36*
G01X514205D02*
X514020Y976551D01*
X512990D01*
X512805Y977151D01*
Y977325D01*
X514205D01*
Y977151D01*
G37*
G36*
G01X517905D02*
X517720Y976551D01*
X516690D01*
X516505Y977151D01*
Y977326D01*
X517905D01*
Y977151D01*
G37*
G36*
G01X503095D02*
X502910Y976551D01*
X501880D01*
X501695Y977151D01*
Y977325D01*
X503095D01*
Y977151D01*
G37*
G36*
G01X506795D02*
X506610Y976551D01*
X505580D01*
X505395Y977151D01*
Y977325D01*
X506795D01*
Y977151D01*
G37*
G36*
G01X510528D02*
X510343Y976551D01*
X509313D01*
X509128Y977151D01*
Y977326D01*
X510528D01*
Y977151D01*
G37*
G36*
G01X514205D02*
X514020Y976551D01*
X512990D01*
X512805Y977151D01*
Y977325D01*
X514205D01*
Y977151D01*
G37*
G36*
G01X517905D02*
X517720Y976551D01*
X516690D01*
X516505Y977151D01*
Y977326D01*
X517905D01*
Y977151D01*
G37*
G36*
G01X503095D02*
X502910Y976551D01*
X501880D01*
X501695Y977151D01*
Y977325D01*
X503095D01*
Y977151D01*
G37*
G36*
G01X509528Y1027719D02*
X509713Y1028319D01*
X510743D01*
X510928Y1027719D01*
Y1027545D01*
X509528D01*
Y1027719D01*
G37*
G36*
G01X513228D02*
X513413Y1028319D01*
X514443D01*
X514628Y1027719D01*
Y1027545D01*
X513228D01*
Y1027719D01*
G37*
G36*
G01X509528D02*
X509713Y1028319D01*
X510743D01*
X510928Y1027719D01*
Y1027545D01*
X509528D01*
Y1027719D01*
G37*
G36*
G01X513228D02*
X513413Y1028319D01*
X514443D01*
X514628Y1027719D01*
Y1027545D01*
X513228D01*
Y1027719D01*
G37*
G36*
G01X510928Y1029327D02*
X510743Y1028727D01*
X509713D01*
X509528Y1029327D01*
Y1029501D01*
X510928D01*
Y1029327D01*
G37*
G36*
G01X514628D02*
X514443Y1028727D01*
X513413D01*
X513228Y1029327D01*
Y1029501D01*
X514628D01*
Y1029327D01*
G37*
G36*
G01X510928D02*
X510743Y1028727D01*
X509713D01*
X509528Y1029327D01*
Y1029501D01*
X510928D01*
Y1029327D01*
G37*
G36*
G01X514628D02*
X514443Y1028727D01*
X513413D01*
X513228Y1029327D01*
Y1029501D01*
X514628D01*
Y1029327D01*
G37*
G36*
G01X512845Y1026121D02*
X512660Y1025521D01*
X511630D01*
X511445Y1026121D01*
Y1026296D01*
X512845D01*
Y1026121D01*
G37*
G36*
G01X509145D02*
X508960Y1025521D01*
X507930D01*
X507745Y1026121D01*
Y1026296D01*
X509145D01*
Y1026121D01*
G37*
G36*
G01X506697Y1026693D02*
X506085Y1026553D01*
X505570Y1027445D01*
X505997Y1027905D01*
X506148Y1027992D01*
X506848Y1026780D01*
X506697Y1026693D01*
G37*
G36*
G01X516545Y1026121D02*
X516360Y1025521D01*
X515330D01*
X515145Y1026121D01*
Y1026296D01*
X516545D01*
Y1026121D01*
G37*
G36*
G01X512845D02*
X512660Y1025521D01*
X511630D01*
X511445Y1026121D01*
Y1026296D01*
X512845D01*
Y1026121D01*
G37*
G36*
G01X509145D02*
X508960Y1025521D01*
X507930D01*
X507745Y1026121D01*
Y1026296D01*
X509145D01*
Y1026121D01*
G37*
G36*
G01X506697Y1026693D02*
X506085Y1026553D01*
X505570Y1027445D01*
X505997Y1027905D01*
X506148Y1027992D01*
X506848Y1026780D01*
X506697Y1026693D01*
G37*
G36*
G01X516545Y1026121D02*
X516360Y1025521D01*
X515330D01*
X515145Y1026121D01*
Y1026296D01*
X516545D01*
Y1026121D01*
G37*
G36*
G01X507695Y1043739D02*
X507880Y1044339D01*
X508910D01*
X509095Y1043739D01*
Y1043565D01*
X507695D01*
Y1043739D01*
G37*
G36*
G01X511395D02*
X511580Y1044339D01*
X512610D01*
X512795Y1043739D01*
Y1043565D01*
X511395D01*
Y1043739D01*
G37*
G36*
G01X515095D02*
X515280Y1044339D01*
X516310D01*
X516495Y1043739D01*
Y1043565D01*
X515095D01*
Y1043739D01*
G37*
G36*
G01X503995D02*
X504180Y1044339D01*
X505210D01*
X505395Y1043739D01*
Y1043565D01*
X503995D01*
Y1043739D01*
G37*
G36*
G01X507695D02*
X507880Y1044339D01*
X508910D01*
X509095Y1043739D01*
Y1043565D01*
X507695D01*
Y1043739D01*
G37*
G36*
G01X511395D02*
X511580Y1044339D01*
X512610D01*
X512795Y1043739D01*
Y1043565D01*
X511395D01*
Y1043739D01*
G37*
G36*
G01X515095D02*
X515280Y1044339D01*
X516310D01*
X516495Y1043739D01*
Y1043565D01*
X515095D01*
Y1043739D01*
G37*
G36*
G01X503995D02*
X504180Y1044339D01*
X505210D01*
X505395Y1043739D01*
Y1043565D01*
X503995D01*
Y1043739D01*
G37*
G36*
G01X509575Y1040535D02*
X509760Y1041135D01*
X510790D01*
X510975Y1040535D01*
Y1040360D01*
X509575D01*
Y1040535D01*
G37*
G36*
G01X505875D02*
X506060Y1041135D01*
X507090D01*
X507275Y1040535D01*
Y1040360D01*
X505875D01*
Y1040535D01*
G37*
G36*
G01X513275D02*
X513460Y1041135D01*
X514490D01*
X514675Y1040535D01*
Y1040360D01*
X513275D01*
Y1040535D01*
G37*
G36*
G01X509575D02*
X509760Y1041135D01*
X510790D01*
X510975Y1040535D01*
Y1040360D01*
X509575D01*
Y1040535D01*
G37*
G36*
G01X505875D02*
X506060Y1041135D01*
X507090D01*
X507275Y1040535D01*
Y1040360D01*
X505875D01*
Y1040535D01*
G37*
G36*
G01X513275D02*
X513460Y1041135D01*
X514490D01*
X514675Y1040535D01*
Y1040360D01*
X513275D01*
Y1040535D01*
G37*
G36*
G01X510978Y1042145D02*
X510793Y1041545D01*
X509763D01*
X509578Y1042145D01*
Y1042319D01*
X510978D01*
Y1042145D01*
G37*
G36*
G01X514678D02*
X514493Y1041545D01*
X513463D01*
X513278Y1042145D01*
Y1042319D01*
X514678D01*
Y1042145D01*
G37*
G36*
G01X510978D02*
X510793Y1041545D01*
X509763D01*
X509578Y1042145D01*
Y1042319D01*
X510978D01*
Y1042145D01*
G37*
G36*
G01X514678D02*
X514493Y1041545D01*
X513463D01*
X513278Y1042145D01*
Y1042319D01*
X514678D01*
Y1042145D01*
G37*
G36*
G01X512798Y1038941D02*
X512613Y1038341D01*
X511583D01*
X511398Y1038941D01*
Y1039115D01*
X512798D01*
Y1038941D01*
G37*
G36*
G01X516498D02*
X516313Y1038341D01*
X515283D01*
X515098Y1038941D01*
Y1039115D01*
X516498D01*
Y1038941D01*
G37*
G36*
G01X512798D02*
X512613Y1038341D01*
X511583D01*
X511398Y1038941D01*
Y1039115D01*
X512798D01*
Y1038941D01*
G37*
G36*
G01X516498D02*
X516313Y1038341D01*
X515283D01*
X515098Y1038941D01*
Y1039115D01*
X516498D01*
Y1038941D01*
G37*
G36*
G01X511445Y1030923D02*
X511630Y1031523D01*
X512660D01*
X512845Y1030923D01*
Y1030749D01*
X511445D01*
Y1030923D01*
G37*
G36*
G01X515145D02*
X515330Y1031523D01*
X516360D01*
X516545Y1030923D01*
Y1030749D01*
X515145D01*
Y1030923D01*
G37*
G36*
G01X511445D02*
X511630Y1031523D01*
X512660D01*
X512845Y1030923D01*
Y1030749D01*
X511445D01*
Y1030923D01*
G37*
G36*
G01X515145D02*
X515330Y1031523D01*
X516360D01*
X516545Y1030923D01*
Y1030749D01*
X515145D01*
Y1030923D01*
G37*
G36*
G01X509538Y1046943D02*
X509723Y1047543D01*
X510753D01*
X510938Y1046943D01*
Y1046769D01*
X509538D01*
Y1046943D01*
G37*
G36*
G01X513275D02*
X513460Y1047543D01*
X514490D01*
X514675Y1046943D01*
Y1046769D01*
X513275D01*
Y1046943D01*
G37*
G36*
G01X509538D02*
X509723Y1047543D01*
X510753D01*
X510938Y1046943D01*
Y1046769D01*
X509538D01*
Y1046943D01*
G37*
G36*
G01X513275D02*
X513460Y1047543D01*
X514490D01*
X514675Y1046943D01*
Y1046769D01*
X513275D01*
Y1046943D01*
G37*
G36*
G01X512798Y1045349D02*
X512613Y1044749D01*
X511583D01*
X511398Y1045349D01*
Y1045524D01*
X512798D01*
Y1045349D01*
G37*
G36*
G01X509098D02*
X508913Y1044749D01*
X507883D01*
X507698Y1045349D01*
Y1045524D01*
X509098D01*
Y1045349D01*
G37*
G36*
G01X516498D02*
X516313Y1044749D01*
X515283D01*
X515098Y1045349D01*
Y1045524D01*
X516498D01*
Y1045349D01*
G37*
G36*
G01X512798D02*
X512613Y1044749D01*
X511583D01*
X511398Y1045349D01*
Y1045524D01*
X512798D01*
Y1045349D01*
G37*
G36*
G01X509098D02*
X508913Y1044749D01*
X507883D01*
X507698Y1045349D01*
Y1045524D01*
X509098D01*
Y1045349D01*
G37*
G36*
G01X516498D02*
X516313Y1044749D01*
X515283D01*
X515098Y1045349D01*
Y1045524D01*
X516498D01*
Y1045349D01*
G37*
G36*
G01X510961Y1035735D02*
X510776Y1035135D01*
X509746D01*
X509561Y1035735D01*
Y1035910D01*
X510961D01*
Y1035735D01*
G37*
G36*
G01X514628D02*
X514443Y1035135D01*
X513413D01*
X513228Y1035735D01*
Y1035909D01*
X514628D01*
Y1035735D01*
G37*
G36*
G01X510961D02*
X510776Y1035135D01*
X509746D01*
X509561Y1035735D01*
Y1035910D01*
X510961D01*
Y1035735D01*
G37*
G36*
G01X514628D02*
X514443Y1035135D01*
X513413D01*
X513228Y1035735D01*
Y1035909D01*
X514628D01*
Y1035735D01*
G37*
G36*
G01X513228Y1034127D02*
X513413Y1034727D01*
X514443D01*
X514628Y1034127D01*
Y1033953D01*
X513228D01*
Y1034127D01*
G37*
G36*
G01D02*
X513413Y1034727D01*
X514443D01*
X514628Y1034127D01*
Y1033953D01*
X513228D01*
Y1034127D01*
G37*
G36*
G01X511435Y1037333D02*
X511620Y1037933D01*
X512650D01*
X512835Y1037333D01*
Y1037158D01*
X511435D01*
Y1037333D01*
G37*
G36*
G01X515145D02*
X515330Y1037933D01*
X516360D01*
X516545Y1037333D01*
Y1037158D01*
X515145D01*
Y1037333D01*
G37*
G36*
G01X511435D02*
X511620Y1037933D01*
X512650D01*
X512835Y1037333D01*
Y1037158D01*
X511435D01*
Y1037333D01*
G37*
G36*
G01X515145D02*
X515330Y1037933D01*
X516360D01*
X516545Y1037333D01*
Y1037158D01*
X515145D01*
Y1037333D01*
G37*
G36*
G01X512845Y1032531D02*
X512660Y1031931D01*
X511630D01*
X511445Y1032531D01*
Y1032705D01*
X512845D01*
Y1032531D01*
G37*
G36*
G01X516545D02*
X516360Y1031931D01*
X515330D01*
X515145Y1032531D01*
Y1032705D01*
X516545D01*
Y1032531D01*
G37*
G36*
G01X512845D02*
X512660Y1031931D01*
X511630D01*
X511445Y1032531D01*
Y1032705D01*
X512845D01*
Y1032531D01*
G37*
G36*
G01X516545D02*
X516360Y1031931D01*
X515330D01*
X515145Y1032531D01*
Y1032705D01*
X516545D01*
Y1032531D01*
G37*
G36*
G01X504045Y1062967D02*
X504230Y1063567D01*
X505260D01*
X505445Y1062967D01*
Y1062792D01*
X504045D01*
Y1062967D01*
G37*
G36*
G01X511445D02*
X511630Y1063567D01*
X512660D01*
X512845Y1062967D01*
Y1062792D01*
X511445D01*
Y1062967D01*
G37*
G36*
G01X507745D02*
X507930Y1063567D01*
X508960D01*
X509145Y1062967D01*
Y1062792D01*
X507745D01*
Y1062967D01*
G37*
G36*
G01X515145D02*
X515330Y1063567D01*
X516360D01*
X516545Y1062967D01*
Y1062792D01*
X515145D01*
Y1062967D01*
G37*
G36*
G01X504045D02*
X504230Y1063567D01*
X505260D01*
X505445Y1062967D01*
Y1062792D01*
X504045D01*
Y1062967D01*
G37*
G36*
G01X511445D02*
X511630Y1063567D01*
X512660D01*
X512845Y1062967D01*
Y1062792D01*
X511445D01*
Y1062967D01*
G37*
G36*
G01X507745D02*
X507930Y1063567D01*
X508960D01*
X509145Y1062967D01*
Y1062792D01*
X507745D01*
Y1062967D01*
G37*
G36*
G01X515145D02*
X515330Y1063567D01*
X516360D01*
X516545Y1062967D01*
Y1062792D01*
X515145D01*
Y1062967D01*
G37*
G36*
G01X509575Y1059761D02*
X509760Y1060361D01*
X510790D01*
X510975Y1059761D01*
Y1059586D01*
X509575D01*
Y1059761D01*
G37*
G36*
G01X505886Y1059757D02*
X506071Y1060357D01*
X507101D01*
X507286Y1059757D01*
Y1059583D01*
X505886D01*
Y1059757D01*
G37*
G36*
G01X513275Y1059761D02*
X513460Y1060361D01*
X514490D01*
X514675Y1059761D01*
Y1059586D01*
X513275D01*
Y1059761D01*
G37*
G36*
G01X509575D02*
X509760Y1060361D01*
X510790D01*
X510975Y1059761D01*
Y1059586D01*
X509575D01*
Y1059761D01*
G37*
G36*
G01X505886Y1059757D02*
X506071Y1060357D01*
X507101D01*
X507286Y1059757D01*
Y1059583D01*
X505886D01*
Y1059757D01*
G37*
G36*
G01X513275Y1059761D02*
X513460Y1060361D01*
X514490D01*
X514675Y1059761D01*
Y1059586D01*
X513275D01*
Y1059761D01*
G37*
G36*
G01X510928Y1061369D02*
X510743Y1060769D01*
X509713D01*
X509528Y1061369D01*
Y1061543D01*
X510928D01*
Y1061369D01*
G37*
G36*
G01X514628D02*
X514443Y1060769D01*
X513413D01*
X513228Y1061369D01*
Y1061543D01*
X514628D01*
Y1061369D01*
G37*
G36*
G01X510928D02*
X510743Y1060769D01*
X509713D01*
X509528Y1061369D01*
Y1061543D01*
X510928D01*
Y1061369D01*
G37*
G36*
G01X514628D02*
X514443Y1060769D01*
X513413D01*
X513228Y1061369D01*
Y1061543D01*
X514628D01*
Y1061369D01*
G37*
G36*
G01X512845Y1058165D02*
X512660Y1057565D01*
X511630D01*
X511445Y1058165D01*
Y1058339D01*
X512845D01*
Y1058165D01*
G37*
G36*
G01X516545D02*
X516360Y1057565D01*
X515330D01*
X515145Y1058165D01*
Y1058339D01*
X516545D01*
Y1058165D01*
G37*
G36*
G01X512845D02*
X512660Y1057565D01*
X511630D01*
X511445Y1058165D01*
Y1058339D01*
X512845D01*
Y1058165D01*
G37*
G36*
G01X516545D02*
X516360Y1057565D01*
X515330D01*
X515145Y1058165D01*
Y1058339D01*
X516545D01*
Y1058165D01*
G37*
G36*
G01X511398Y1050149D02*
X511583Y1050749D01*
X512613D01*
X512798Y1050149D01*
Y1049974D01*
X511398D01*
Y1050149D01*
G37*
G36*
G01X515098D02*
X515283Y1050749D01*
X516313D01*
X516498Y1050149D01*
Y1049974D01*
X515098D01*
Y1050149D01*
G37*
G36*
G01X511398D02*
X511583Y1050749D01*
X512613D01*
X512798Y1050149D01*
Y1049974D01*
X511398D01*
Y1050149D01*
G37*
G36*
G01X515098D02*
X515283Y1050749D01*
X516313D01*
X516498Y1050149D01*
Y1049974D01*
X515098D01*
Y1050149D01*
G37*
G36*
G01X510975Y1048553D02*
X510790Y1047953D01*
X509760D01*
X509575Y1048553D01*
Y1048727D01*
X510975D01*
Y1048553D01*
G37*
G36*
G01X514675D02*
X514490Y1047953D01*
X513460D01*
X513275Y1048553D01*
Y1048727D01*
X514675D01*
Y1048553D01*
G37*
G36*
G01X510975D02*
X510790Y1047953D01*
X509760D01*
X509575Y1048553D01*
Y1048727D01*
X510975D01*
Y1048553D01*
G37*
G36*
G01X514675D02*
X514490Y1047953D01*
X513460D01*
X513275Y1048553D01*
Y1048727D01*
X514675D01*
Y1048553D01*
G37*
G36*
G01X510928Y1054961D02*
X510743Y1054361D01*
X509713D01*
X509528Y1054961D01*
Y1055135D01*
X510928D01*
Y1054961D01*
G37*
G36*
G01X514628D02*
X514443Y1054361D01*
X513413D01*
X513228Y1054961D01*
Y1055135D01*
X514628D01*
Y1054961D01*
G37*
G36*
G01X510928D02*
X510743Y1054361D01*
X509713D01*
X509528Y1054961D01*
Y1055135D01*
X510928D01*
Y1054961D01*
G37*
G36*
G01X514628D02*
X514443Y1054361D01*
X513413D01*
X513228Y1054961D01*
Y1055135D01*
X514628D01*
Y1054961D01*
G37*
G36*
G01X513228Y1053353D02*
X513413Y1053953D01*
X514443D01*
X514628Y1053353D01*
Y1053179D01*
X513228D01*
Y1053353D01*
G37*
G36*
G01D02*
X513413Y1053953D01*
X514443D01*
X514628Y1053353D01*
Y1053179D01*
X513228D01*
Y1053353D01*
G37*
G36*
G01X511445Y1056557D02*
X511630Y1057157D01*
X512660D01*
X512845Y1056557D01*
Y1056383D01*
X511445D01*
Y1056557D01*
G37*
G36*
G01X507745D02*
X507930Y1057157D01*
X508960D01*
X509145Y1056557D01*
Y1056383D01*
X507745D01*
Y1056557D01*
G37*
G36*
G01X515145D02*
X515330Y1057157D01*
X516360D01*
X516545Y1056557D01*
Y1056383D01*
X515145D01*
Y1056557D01*
G37*
G36*
G01X511445D02*
X511630Y1057157D01*
X512660D01*
X512845Y1056557D01*
Y1056383D01*
X511445D01*
Y1056557D01*
G37*
G36*
G01X507745D02*
X507930Y1057157D01*
X508960D01*
X509145Y1056557D01*
Y1056383D01*
X507745D01*
Y1056557D01*
G37*
G36*
G01X515145D02*
X515330Y1057157D01*
X516360D01*
X516545Y1056557D01*
Y1056383D01*
X515145D01*
Y1056557D01*
G37*
G36*
G01X512817Y1051759D02*
X512632Y1051159D01*
X511602D01*
X511417Y1051759D01*
Y1051933D01*
X512817D01*
Y1051759D01*
G37*
G36*
G01X516545Y1051757D02*
X516360Y1051157D01*
X515330D01*
X515145Y1051757D01*
Y1051931D01*
X516545D01*
Y1051757D01*
G37*
G36*
G01X512817Y1051759D02*
X512632Y1051159D01*
X511602D01*
X511417Y1051759D01*
Y1051933D01*
X512817D01*
Y1051759D01*
G37*
G36*
G01X516545Y1051757D02*
X516360Y1051157D01*
X515330D01*
X515145Y1051757D01*
Y1051931D01*
X516545D01*
Y1051757D01*
G37*
G36*
G01Y1077391D02*
X516360Y1076791D01*
X515330D01*
X515145Y1077391D01*
Y1077565D01*
X516545D01*
Y1077391D01*
G37*
G36*
G01X512798D02*
X512613Y1076791D01*
X511583D01*
X511398Y1077391D01*
Y1077566D01*
X512798D01*
Y1077391D01*
G37*
G36*
G01X516545D02*
X516360Y1076791D01*
X515330D01*
X515145Y1077391D01*
Y1077565D01*
X516545D01*
Y1077391D01*
G37*
G36*
G01X512798D02*
X512613Y1076791D01*
X511583D01*
X511398Y1077391D01*
Y1077566D01*
X512798D01*
Y1077391D01*
G37*
G36*
G01X511398Y1069375D02*
X511583Y1069975D01*
X512613D01*
X512798Y1069375D01*
Y1069200D01*
X511398D01*
Y1069375D01*
G37*
G36*
G01X515098D02*
X515283Y1069975D01*
X516313D01*
X516498Y1069375D01*
Y1069200D01*
X515098D01*
Y1069375D01*
G37*
G36*
G01X511398D02*
X511583Y1069975D01*
X512613D01*
X512798Y1069375D01*
Y1069200D01*
X511398D01*
Y1069375D01*
G37*
G36*
G01X515098D02*
X515283Y1069975D01*
X516313D01*
X516498Y1069375D01*
Y1069200D01*
X515098D01*
Y1069375D01*
G37*
G36*
G01X509528Y1066171D02*
X509713Y1066771D01*
X510743D01*
X510928Y1066171D01*
Y1065996D01*
X509528D01*
Y1066171D01*
G37*
G36*
G01X513228D02*
X513413Y1066771D01*
X514443D01*
X514628Y1066171D01*
Y1065996D01*
X513228D01*
Y1066171D01*
G37*
G36*
G01X506425Y1068806D02*
X507037Y1068946D01*
X507552Y1068054D01*
X507125Y1067594D01*
X506974Y1067507D01*
X506274Y1068719D01*
X506425Y1068806D01*
G37*
G36*
G01X509528Y1066171D02*
X509713Y1066771D01*
X510743D01*
X510928Y1066171D01*
Y1065996D01*
X509528D01*
Y1066171D01*
G37*
G36*
G01X513228D02*
X513413Y1066771D01*
X514443D01*
X514628Y1066171D01*
Y1065996D01*
X513228D01*
Y1066171D01*
G37*
G36*
G01X506425Y1068806D02*
X507037Y1068946D01*
X507552Y1068054D01*
X507125Y1067594D01*
X506974Y1067507D01*
X506274Y1068719D01*
X506425Y1068806D01*
G37*
G36*
G01X510975Y1067779D02*
X510790Y1067179D01*
X509760D01*
X509575Y1067779D01*
Y1067953D01*
X510975D01*
Y1067779D01*
G37*
G36*
G01X514675D02*
X514490Y1067179D01*
X513460D01*
X513275Y1067779D01*
Y1067953D01*
X514675D01*
Y1067779D01*
G37*
G36*
G01X510975D02*
X510790Y1067179D01*
X509760D01*
X509575Y1067779D01*
Y1067953D01*
X510975D01*
Y1067779D01*
G37*
G36*
G01X514675D02*
X514490Y1067179D01*
X513460D01*
X513275Y1067779D01*
Y1067953D01*
X514675D01*
Y1067779D01*
G37*
G36*
G01X509145Y1064573D02*
X508960Y1063973D01*
X507930D01*
X507745Y1064573D01*
Y1064748D01*
X509145D01*
Y1064573D01*
G37*
G36*
G01X506676Y1065180D02*
X506064Y1065040D01*
X505549Y1065932D01*
X505976Y1066392D01*
X506127Y1066479D01*
X506827Y1065267D01*
X506676Y1065180D01*
G37*
G36*
G01X512845Y1064573D02*
X512660Y1063973D01*
X511630D01*
X511445Y1064573D01*
Y1064748D01*
X512845D01*
Y1064573D01*
G37*
G36*
G01X516545D02*
X516360Y1063973D01*
X515330D01*
X515145Y1064573D01*
Y1064748D01*
X516545D01*
Y1064573D01*
G37*
G36*
G01X509145D02*
X508960Y1063973D01*
X507930D01*
X507745Y1064573D01*
Y1064748D01*
X509145D01*
Y1064573D01*
G37*
G36*
G01X506676Y1065180D02*
X506064Y1065040D01*
X505549Y1065932D01*
X505976Y1066392D01*
X506127Y1066479D01*
X506827Y1065267D01*
X506676Y1065180D01*
G37*
G36*
G01X512845Y1064573D02*
X512660Y1063973D01*
X511630D01*
X511445Y1064573D01*
Y1064748D01*
X512845D01*
Y1064573D01*
G37*
G36*
G01X516545D02*
X516360Y1063973D01*
X515330D01*
X515145Y1064573D01*
Y1064748D01*
X516545D01*
Y1064573D01*
G37*
G36*
G01X509575Y1078987D02*
X509760Y1079587D01*
X510790D01*
X510975Y1078987D01*
Y1078812D01*
X509575D01*
Y1078987D01*
G37*
G36*
G01X513275D02*
X513460Y1079587D01*
X514490D01*
X514675Y1078987D01*
Y1078812D01*
X513275D01*
Y1078987D01*
G37*
G36*
G01X509575D02*
X509760Y1079587D01*
X510790D01*
X510975Y1078987D01*
Y1078812D01*
X509575D01*
Y1078987D01*
G37*
G36*
G01X513275D02*
X513460Y1079587D01*
X514490D01*
X514675Y1078987D01*
Y1078812D01*
X513275D01*
Y1078987D01*
G37*
G36*
G01X510928Y1074187D02*
X510743Y1073587D01*
X509713D01*
X509528Y1074187D01*
Y1074361D01*
X510928D01*
Y1074187D01*
G37*
G36*
G01X514628D02*
X514443Y1073587D01*
X513413D01*
X513228Y1074187D01*
Y1074361D01*
X514628D01*
Y1074187D01*
G37*
G36*
G01X510928D02*
X510743Y1073587D01*
X509713D01*
X509528Y1074187D01*
Y1074361D01*
X510928D01*
Y1074187D01*
G37*
G36*
G01X514628D02*
X514443Y1073587D01*
X513413D01*
X513228Y1074187D01*
Y1074361D01*
X514628D01*
Y1074187D01*
G37*
G36*
G01X513228Y1072579D02*
X513413Y1073179D01*
X514443D01*
X514628Y1072579D01*
Y1072405D01*
X513228D01*
Y1072579D01*
G37*
G36*
G01D02*
X513413Y1073179D01*
X514443D01*
X514628Y1072579D01*
Y1072405D01*
X513228D01*
Y1072579D01*
G37*
G36*
G01X515145Y1075783D02*
X515330Y1076383D01*
X516360D01*
X516545Y1075783D01*
Y1075609D01*
X515145D01*
Y1075783D01*
G37*
G36*
G01X511445D02*
X511630Y1076383D01*
X512660D01*
X512845Y1075783D01*
Y1075609D01*
X511445D01*
Y1075783D01*
G37*
G36*
G01X515145D02*
X515330Y1076383D01*
X516360D01*
X516545Y1075783D01*
Y1075609D01*
X515145D01*
Y1075783D01*
G37*
G36*
G01X511445D02*
X511630Y1076383D01*
X512660D01*
X512845Y1075783D01*
Y1075609D01*
X511445D01*
Y1075783D01*
G37*
G36*
G01X512811Y1070985D02*
X512626Y1070385D01*
X511596D01*
X511411Y1070985D01*
Y1071160D01*
X512811D01*
Y1070985D01*
G37*
G36*
G01X516545Y1070981D02*
X516360Y1070381D01*
X515330D01*
X515145Y1070981D01*
Y1071156D01*
X516545D01*
Y1070981D01*
G37*
G36*
G01X512811Y1070985D02*
X512626Y1070385D01*
X511596D01*
X511411Y1070985D01*
Y1071160D01*
X512811D01*
Y1070985D01*
G37*
G36*
G01X516545Y1070981D02*
X516360Y1070381D01*
X515330D01*
X515145Y1070981D01*
Y1071156D01*
X516545D01*
Y1070981D01*
G37*
G36*
G01X510928Y1080595D02*
X510743Y1079995D01*
X509713D01*
X509528Y1080595D01*
Y1080769D01*
X510928D01*
Y1080595D01*
G37*
G36*
G01X507228D02*
X507043Y1079995D01*
X506013D01*
X505828Y1080595D01*
Y1080769D01*
X507228D01*
Y1080595D01*
G37*
G36*
G01X514628D02*
X514443Y1079995D01*
X513413D01*
X513228Y1080595D01*
Y1080769D01*
X514628D01*
Y1080595D01*
G37*
G36*
G01X510928D02*
X510743Y1079995D01*
X509713D01*
X509528Y1080595D01*
Y1080769D01*
X510928D01*
Y1080595D01*
G37*
G36*
G01X507228D02*
X507043Y1079995D01*
X506013D01*
X505828Y1080595D01*
Y1080769D01*
X507228D01*
Y1080595D01*
G37*
G36*
G01X514628D02*
X514443Y1079995D01*
X513413D01*
X513228Y1080595D01*
Y1080769D01*
X514628D01*
Y1080595D01*
G37*
G36*
G01X515145Y1082191D02*
X515330Y1082791D01*
X516360D01*
X516545Y1082191D01*
Y1082017D01*
X515145D01*
Y1082191D01*
G37*
G36*
G01X504045D02*
X504230Y1082791D01*
X505260D01*
X505445Y1082191D01*
Y1082017D01*
X504045D01*
Y1082191D01*
G37*
G36*
G01X511445D02*
X511630Y1082791D01*
X512660D01*
X512845Y1082191D01*
Y1082017D01*
X511445D01*
Y1082191D01*
G37*
G36*
G01X507745D02*
X507930Y1082791D01*
X508960D01*
X509145Y1082191D01*
Y1082017D01*
X507745D01*
Y1082191D01*
G37*
G36*
G01X515145D02*
X515330Y1082791D01*
X516360D01*
X516545Y1082191D01*
Y1082017D01*
X515145D01*
Y1082191D01*
G37*
G36*
G01X504045D02*
X504230Y1082791D01*
X505260D01*
X505445Y1082191D01*
Y1082017D01*
X504045D01*
Y1082191D01*
G37*
G36*
G01X511445D02*
X511630Y1082791D01*
X512660D01*
X512845Y1082191D01*
Y1082017D01*
X511445D01*
Y1082191D01*
G37*
G36*
G01X507745D02*
X507930Y1082791D01*
X508960D01*
X509145Y1082191D01*
Y1082017D01*
X507745D01*
Y1082191D01*
G37*
G36*
G01X515145Y1088600D02*
X515330Y1089200D01*
X516360D01*
X516545Y1088600D01*
Y1088426D01*
X515145D01*
Y1088600D01*
G37*
G36*
G01X511445D02*
X511630Y1089200D01*
X512660D01*
X512845Y1088600D01*
Y1088426D01*
X511445D01*
Y1088600D01*
G37*
G36*
G01X515145D02*
X515330Y1089200D01*
X516360D01*
X516545Y1088600D01*
Y1088426D01*
X515145D01*
Y1088600D01*
G37*
G36*
G01X511445D02*
X511630Y1089200D01*
X512660D01*
X512845Y1088600D01*
Y1088426D01*
X511445D01*
Y1088600D01*
G37*
G36*
G01X509538Y1085396D02*
X509723Y1085996D01*
X510753D01*
X510938Y1085396D01*
Y1085221D01*
X509538D01*
Y1085396D01*
G37*
G36*
G01X513228D02*
X513413Y1085996D01*
X514443D01*
X514628Y1085396D01*
Y1085222D01*
X513228D01*
Y1085396D01*
G37*
G36*
G01X509538D02*
X509723Y1085996D01*
X510753D01*
X510938Y1085396D01*
Y1085221D01*
X509538D01*
Y1085396D01*
G37*
G36*
G01X513228D02*
X513413Y1085996D01*
X514443D01*
X514628Y1085396D01*
Y1085222D01*
X513228D01*
Y1085396D01*
G37*
G36*
G01X510938Y1087005D02*
X510753Y1086405D01*
X509723D01*
X509538Y1087005D01*
Y1087179D01*
X510938D01*
Y1087005D01*
G37*
G36*
G01X514628Y1087003D02*
X514443Y1086403D01*
X513413D01*
X513228Y1087003D01*
Y1087178D01*
X514628D01*
Y1087003D01*
G37*
G36*
G01X510938Y1087005D02*
X510753Y1086405D01*
X509723D01*
X509538Y1087005D01*
Y1087179D01*
X510938D01*
Y1087005D01*
G37*
G36*
G01X514628Y1087003D02*
X514443Y1086403D01*
X513413D01*
X513228Y1087003D01*
Y1087178D01*
X514628D01*
Y1087003D01*
G37*
G36*
G01X516545Y1083799D02*
X516360Y1083199D01*
X515330D01*
X515145Y1083799D01*
Y1083973D01*
X516545D01*
Y1083799D01*
G37*
G36*
G01X512845D02*
X512660Y1083199D01*
X511630D01*
X511445Y1083799D01*
Y1083973D01*
X512845D01*
Y1083799D01*
G37*
G36*
G01X509112D02*
X508927Y1083199D01*
X507897D01*
X507712Y1083799D01*
Y1083974D01*
X509112D01*
Y1083799D01*
G37*
G36*
G01X516545D02*
X516360Y1083199D01*
X515330D01*
X515145Y1083799D01*
Y1083973D01*
X516545D01*
Y1083799D01*
G37*
G36*
G01X512845D02*
X512660Y1083199D01*
X511630D01*
X511445Y1083799D01*
Y1083973D01*
X512845D01*
Y1083799D01*
G37*
G36*
G01X509112D02*
X508927Y1083199D01*
X507897D01*
X507712Y1083799D01*
Y1083974D01*
X509112D01*
Y1083799D01*
G37*
G36*
G01X510938Y1093411D02*
X510753Y1092811D01*
X509723D01*
X509538Y1093411D01*
Y1093586D01*
X510938D01*
Y1093411D01*
G37*
G36*
G01X514695D02*
X514510Y1092811D01*
X513480D01*
X513295Y1093411D01*
Y1093586D01*
X514695D01*
Y1093411D01*
G37*
G36*
G01X510938D02*
X510753Y1092811D01*
X509723D01*
X509538Y1093411D01*
Y1093586D01*
X510938D01*
Y1093411D01*
G37*
G36*
G01X514695D02*
X514510Y1092811D01*
X513480D01*
X513295Y1093411D01*
Y1093586D01*
X514695D01*
Y1093411D01*
G37*
G36*
G01X513263Y1091804D02*
X513448Y1092404D01*
X514478D01*
X514663Y1091804D01*
Y1091630D01*
X513263D01*
Y1091804D01*
G37*
G36*
G01D02*
X513448Y1092404D01*
X514478D01*
X514663Y1091804D01*
Y1091630D01*
X513263D01*
Y1091804D01*
G37*
G36*
G01X515088Y1095009D02*
X515273Y1095609D01*
X516303D01*
X516488Y1095009D01*
Y1094835D01*
X515088D01*
Y1095009D01*
G37*
G36*
G01D02*
X515273Y1095609D01*
X516303D01*
X516488Y1095009D01*
Y1094835D01*
X515088D01*
Y1095009D01*
G37*
G36*
G01X516512Y1090209D02*
X516327Y1089609D01*
X515297D01*
X515112Y1090209D01*
Y1090383D01*
X516512D01*
Y1090209D01*
G37*
G36*
G01D02*
X516327Y1089609D01*
X515297D01*
X515112Y1090209D01*
Y1090383D01*
X516512D01*
Y1090209D01*
G37*
G36*
G01X516535Y1096617D02*
X516350Y1096017D01*
X515320D01*
X515135Y1096617D01*
Y1096791D01*
X516535D01*
Y1096617D01*
G37*
G36*
G01D02*
X516350Y1096017D01*
X515320D01*
X515135Y1096617D01*
Y1096791D01*
X516535D01*
Y1096617D01*
G37*
G36*
G01X523929Y898641D02*
X524114Y899241D01*
X525144D01*
X525329Y898641D01*
Y898466D01*
X523929D01*
Y898641D01*
G37*
G36*
G01X520205D02*
X520390Y899241D01*
X521420D01*
X521605Y898641D01*
Y898467D01*
X520205D01*
Y898641D01*
G37*
G36*
G01X527605D02*
X527790Y899241D01*
X528820D01*
X529005Y898641D01*
Y898466D01*
X527605D01*
Y898641D01*
G37*
G36*
G01X531305D02*
X531490Y899241D01*
X532520D01*
X532705Y898641D01*
Y898467D01*
X531305D01*
Y898641D01*
G37*
G36*
G01X523929D02*
X524114Y899241D01*
X525144D01*
X525329Y898641D01*
Y898466D01*
X523929D01*
Y898641D01*
G37*
G36*
G01X520205D02*
X520390Y899241D01*
X521420D01*
X521605Y898641D01*
Y898467D01*
X520205D01*
Y898641D01*
G37*
G36*
G01X527605D02*
X527790Y899241D01*
X528820D01*
X529005Y898641D01*
Y898466D01*
X527605D01*
Y898641D01*
G37*
G36*
G01X531305D02*
X531490Y899241D01*
X532520D01*
X532705Y898641D01*
Y898467D01*
X531305D01*
Y898641D01*
G37*
G36*
G01X522112Y895437D02*
X522297Y896037D01*
X523327D01*
X523512Y895437D01*
Y895262D01*
X522112D01*
Y895437D01*
G37*
G36*
G01X525779Y895435D02*
X525964Y896035D01*
X526994D01*
X527179Y895435D01*
Y895261D01*
X525779D01*
Y895435D01*
G37*
G36*
G01X529512Y895437D02*
X529697Y896037D01*
X530727D01*
X530912Y895437D01*
Y895262D01*
X529512D01*
Y895437D01*
G37*
G36*
G01X522112D02*
X522297Y896037D01*
X523327D01*
X523512Y895437D01*
Y895262D01*
X522112D01*
Y895437D01*
G37*
G36*
G01X525779Y895435D02*
X525964Y896035D01*
X526994D01*
X527179Y895435D01*
Y895261D01*
X525779D01*
Y895435D01*
G37*
G36*
G01X529512Y895437D02*
X529697Y896037D01*
X530727D01*
X530912Y895437D01*
Y895262D01*
X529512D01*
Y895437D01*
G37*
G36*
G01X518412D02*
X518597Y896037D01*
X519627D01*
X519812Y895437D01*
Y895262D01*
X518412D01*
Y895437D01*
G37*
G36*
G01D02*
X518597Y896037D01*
X519627D01*
X519812Y895437D01*
Y895262D01*
X518412D01*
Y895437D01*
G37*
G36*
G01X523479Y897045D02*
X523294Y896445D01*
X522264D01*
X522079Y897045D01*
Y897219D01*
X523479D01*
Y897045D01*
G37*
G36*
G01X527179D02*
X526994Y896445D01*
X525964D01*
X525779Y897045D01*
Y897219D01*
X527179D01*
Y897045D01*
G37*
G36*
G01X530912Y897043D02*
X530727Y896443D01*
X529697D01*
X529512Y897043D01*
Y897218D01*
X530912D01*
Y897043D01*
G37*
G36*
G01X523479Y897045D02*
X523294Y896445D01*
X522264D01*
X522079Y897045D01*
Y897219D01*
X523479D01*
Y897045D01*
G37*
G36*
G01X527179D02*
X526994Y896445D01*
X525964D01*
X525779Y897045D01*
Y897219D01*
X527179D01*
Y897045D01*
G37*
G36*
G01X530912Y897043D02*
X530727Y896443D01*
X529697D01*
X529512Y897043D01*
Y897218D01*
X530912D01*
Y897043D01*
G37*
G36*
G01X519812D02*
X519627Y896443D01*
X518597D01*
X518412Y897043D01*
Y897218D01*
X519812D01*
Y897043D01*
G37*
G36*
G01D02*
X519627Y896443D01*
X518597D01*
X518412Y897043D01*
Y897218D01*
X519812D01*
Y897043D01*
G37*
G36*
G01X521595Y893839D02*
X521410Y893239D01*
X520380D01*
X520195Y893839D01*
Y894014D01*
X521595D01*
Y893839D01*
G37*
G36*
G01X525305D02*
X525120Y893239D01*
X524090D01*
X523905Y893839D01*
Y894014D01*
X525305D01*
Y893839D01*
G37*
G36*
G01X529005Y893841D02*
X528820Y893241D01*
X527790D01*
X527605Y893841D01*
Y894015D01*
X529005D01*
Y893841D01*
G37*
G36*
G01X532705Y893839D02*
X532520Y893239D01*
X531490D01*
X531305Y893839D01*
Y894014D01*
X532705D01*
Y893839D01*
G37*
G36*
G01X521595D02*
X521410Y893239D01*
X520380D01*
X520195Y893839D01*
Y894014D01*
X521595D01*
Y893839D01*
G37*
G36*
G01X525305D02*
X525120Y893239D01*
X524090D01*
X523905Y893839D01*
Y894014D01*
X525305D01*
Y893839D01*
G37*
G36*
G01X529005Y893841D02*
X528820Y893241D01*
X527790D01*
X527605Y893841D01*
Y894015D01*
X529005D01*
Y893841D01*
G37*
G36*
G01X532705Y893839D02*
X532520Y893239D01*
X531490D01*
X531305Y893839D01*
Y894014D01*
X532705D01*
Y893839D01*
G37*
G36*
G01X521605Y900249D02*
X521420Y899649D01*
X520390D01*
X520205Y900249D01*
Y900423D01*
X521605D01*
Y900249D01*
G37*
G36*
G01X529005D02*
X528820Y899649D01*
X527790D01*
X527605Y900249D01*
Y900424D01*
X529005D01*
Y900249D01*
G37*
G36*
G01X532705D02*
X532520Y899649D01*
X531490D01*
X531305Y900249D01*
Y900423D01*
X532705D01*
Y900249D01*
G37*
G36*
G01X525329D02*
X525144Y899649D01*
X524114D01*
X523929Y900249D01*
Y900424D01*
X525329D01*
Y900249D01*
G37*
G36*
G01X521605D02*
X521420Y899649D01*
X520390D01*
X520205Y900249D01*
Y900423D01*
X521605D01*
Y900249D01*
G37*
G36*
G01X529005D02*
X528820Y899649D01*
X527790D01*
X527605Y900249D01*
Y900424D01*
X529005D01*
Y900249D01*
G37*
G36*
G01X532705D02*
X532520Y899649D01*
X531490D01*
X531305Y900249D01*
Y900423D01*
X532705D01*
Y900249D01*
G37*
G36*
G01X525329D02*
X525144Y899649D01*
X524114D01*
X523929Y900249D01*
Y900424D01*
X525329D01*
Y900249D01*
G37*
G36*
G01X523455Y916271D02*
X523270Y915671D01*
X522240D01*
X522055Y916271D01*
Y916445D01*
X523455D01*
Y916271D01*
G37*
G36*
G01X527155Y916269D02*
X526970Y915669D01*
X525940D01*
X525755Y916269D01*
Y916444D01*
X527155D01*
Y916269D01*
G37*
G36*
G01X530879Y916271D02*
X530694Y915671D01*
X529664D01*
X529479Y916271D01*
Y916445D01*
X530879D01*
Y916271D01*
G37*
G36*
G01X523455D02*
X523270Y915671D01*
X522240D01*
X522055Y916271D01*
Y916445D01*
X523455D01*
Y916271D01*
G37*
G36*
G01X527155Y916269D02*
X526970Y915669D01*
X525940D01*
X525755Y916269D01*
Y916444D01*
X527155D01*
Y916269D01*
G37*
G36*
G01X530879Y916271D02*
X530694Y915671D01*
X529664D01*
X529479Y916271D01*
Y916445D01*
X530879D01*
Y916271D01*
G37*
G36*
G01X519812Y916269D02*
X519627Y915669D01*
X518597D01*
X518412Y916269D01*
Y916444D01*
X519812D01*
Y916269D01*
G37*
G36*
G01D02*
X519627Y915669D01*
X518597D01*
X518412Y916269D01*
Y916444D01*
X519812D01*
Y916269D01*
G37*
G36*
G01X523905Y911459D02*
X524090Y912059D01*
X525120D01*
X525305Y911459D01*
Y911284D01*
X523905D01*
Y911459D01*
G37*
G36*
G01X520228Y911457D02*
X520413Y912057D01*
X521443D01*
X521628Y911457D01*
Y911283D01*
X520228D01*
Y911457D01*
G37*
G36*
G01X527629D02*
X527814Y912057D01*
X528844D01*
X529029Y911457D01*
Y911283D01*
X527629D01*
Y911457D01*
G37*
G36*
G01X531329D02*
X531514Y912057D01*
X532544D01*
X532729Y911457D01*
Y911283D01*
X531329D01*
Y911457D01*
G37*
G36*
G01X523905Y911459D02*
X524090Y912059D01*
X525120D01*
X525305Y911459D01*
Y911284D01*
X523905D01*
Y911459D01*
G37*
G36*
G01X520228Y911457D02*
X520413Y912057D01*
X521443D01*
X521628Y911457D01*
Y911283D01*
X520228D01*
Y911457D01*
G37*
G36*
G01X527629D02*
X527814Y912057D01*
X528844D01*
X529029Y911457D01*
Y911283D01*
X527629D01*
Y911457D01*
G37*
G36*
G01X531329D02*
X531514Y912057D01*
X532544D01*
X532729Y911457D01*
Y911283D01*
X531329D01*
Y911457D01*
G37*
G36*
G01X517092Y914094D02*
X517704Y914234D01*
X518219Y913342D01*
X517792Y912882D01*
X517641Y912795D01*
X516941Y914007D01*
X517092Y914094D01*
G37*
G36*
G01D02*
X517704Y914234D01*
X518219Y913342D01*
X517792Y912882D01*
X517641Y912795D01*
X516941Y914007D01*
X517092Y914094D01*
G37*
G36*
G01X522102Y908253D02*
X522287Y908853D01*
X523317D01*
X523502Y908253D01*
Y908079D01*
X522102D01*
Y908253D01*
G37*
G36*
G01X525779D02*
X525964Y908853D01*
X526994D01*
X527179Y908253D01*
Y908078D01*
X525779D01*
Y908253D01*
G37*
G36*
G01X529479D02*
X529664Y908853D01*
X530694D01*
X530879Y908253D01*
Y908078D01*
X529479D01*
Y908253D01*
G37*
G36*
G01X522102D02*
X522287Y908853D01*
X523317D01*
X523502Y908253D01*
Y908079D01*
X522102D01*
Y908253D01*
G37*
G36*
G01X525779D02*
X525964Y908853D01*
X526994D01*
X527179Y908253D01*
Y908078D01*
X525779D01*
Y908253D01*
G37*
G36*
G01X529479D02*
X529664Y908853D01*
X530694D01*
X530879Y908253D01*
Y908078D01*
X529479D01*
Y908253D01*
G37*
G36*
G01X518355D02*
X518540Y908853D01*
X519570D01*
X519755Y908253D01*
Y908078D01*
X518355D01*
Y908253D01*
G37*
G36*
G01D02*
X518540Y908853D01*
X519570D01*
X519755Y908253D01*
Y908078D01*
X518355D01*
Y908253D01*
G37*
G36*
G01X523502Y909861D02*
X523317Y909261D01*
X522287D01*
X522102Y909861D01*
Y910035D01*
X523502D01*
Y909861D01*
G37*
G36*
G01X527179D02*
X526994Y909261D01*
X525964D01*
X525779Y909861D01*
Y910036D01*
X527179D01*
Y909861D01*
G37*
G36*
G01X530879D02*
X530694Y909261D01*
X529664D01*
X529479Y909861D01*
Y910036D01*
X530879D01*
Y909861D01*
G37*
G36*
G01X523502D02*
X523317Y909261D01*
X522287D01*
X522102Y909861D01*
Y910035D01*
X523502D01*
Y909861D01*
G37*
G36*
G01X527179D02*
X526994Y909261D01*
X525964D01*
X525779Y909861D01*
Y910036D01*
X527179D01*
Y909861D01*
G37*
G36*
G01X530879D02*
X530694Y909261D01*
X529664D01*
X529479Y909861D01*
Y910036D01*
X530879D01*
Y909861D01*
G37*
G36*
G01X519802D02*
X519617Y909261D01*
X518587D01*
X518402Y909861D01*
Y910036D01*
X519802D01*
Y909861D01*
G37*
G36*
G01D02*
X519617Y909261D01*
X518587D01*
X518402Y909861D01*
Y910036D01*
X519802D01*
Y909861D01*
G37*
G36*
G01X525305Y906657D02*
X525120Y906057D01*
X524090D01*
X523905Y906657D01*
Y906831D01*
X525305D01*
Y906657D01*
G37*
G36*
G01X521652D02*
X521467Y906057D01*
X520437D01*
X520252Y906657D01*
Y906832D01*
X521652D01*
Y906657D01*
G37*
G36*
G01X529029D02*
X528844Y906057D01*
X527814D01*
X527629Y906657D01*
Y906832D01*
X529029D01*
Y906657D01*
G37*
G36*
G01X532729D02*
X532544Y906057D01*
X531514D01*
X531329Y906657D01*
Y906832D01*
X532729D01*
Y906657D01*
G37*
G36*
G01X525305D02*
X525120Y906057D01*
X524090D01*
X523905Y906657D01*
Y906831D01*
X525305D01*
Y906657D01*
G37*
G36*
G01X521652D02*
X521467Y906057D01*
X520437D01*
X520252Y906657D01*
Y906832D01*
X521652D01*
Y906657D01*
G37*
G36*
G01X529029D02*
X528844Y906057D01*
X527814D01*
X527629Y906657D01*
Y906832D01*
X529029D01*
Y906657D01*
G37*
G36*
G01X532729D02*
X532544Y906057D01*
X531514D01*
X531329Y906657D01*
Y906832D01*
X532729D01*
Y906657D01*
G37*
G36*
G01X523512Y903453D02*
X523327Y902853D01*
X522297D01*
X522112Y903453D01*
Y903627D01*
X523512D01*
Y903453D01*
G37*
G36*
G01X527179D02*
X526994Y902853D01*
X525964D01*
X525779Y903453D01*
Y903628D01*
X527179D01*
Y903453D01*
G37*
G36*
G01X530879D02*
X530694Y902853D01*
X529664D01*
X529479Y903453D01*
Y903628D01*
X530879D01*
Y903453D01*
G37*
G36*
G01X523512D02*
X523327Y902853D01*
X522297D01*
X522112Y903453D01*
Y903627D01*
X523512D01*
Y903453D01*
G37*
G36*
G01X527179D02*
X526994Y902853D01*
X525964D01*
X525779Y903453D01*
Y903628D01*
X527179D01*
Y903453D01*
G37*
G36*
G01X530879D02*
X530694Y902853D01*
X529664D01*
X529479Y903453D01*
Y903628D01*
X530879D01*
Y903453D01*
G37*
G36*
G01X519779D02*
X519594Y902853D01*
X518564D01*
X518379Y903453D01*
Y903628D01*
X519779D01*
Y903453D01*
G37*
G36*
G01D02*
X519594Y902853D01*
X518564D01*
X518379Y903453D01*
Y903628D01*
X519779D01*
Y903453D01*
G37*
G36*
G01X522079Y901845D02*
X522264Y902445D01*
X523294D01*
X523479Y901845D01*
Y901670D01*
X522079D01*
Y901845D01*
G37*
G36*
G01X525779D02*
X525964Y902445D01*
X526994D01*
X527179Y901845D01*
Y901670D01*
X525779D01*
Y901845D01*
G37*
G36*
G01X529512D02*
X529697Y902445D01*
X530727D01*
X530912Y901845D01*
Y901671D01*
X529512D01*
Y901845D01*
G37*
G36*
G01X522079D02*
X522264Y902445D01*
X523294D01*
X523479Y901845D01*
Y901670D01*
X522079D01*
Y901845D01*
G37*
G36*
G01X525779D02*
X525964Y902445D01*
X526994D01*
X527179Y901845D01*
Y901670D01*
X525779D01*
Y901845D01*
G37*
G36*
G01X529512D02*
X529697Y902445D01*
X530727D01*
X530912Y901845D01*
Y901671D01*
X529512D01*
Y901845D01*
G37*
G36*
G01X518412D02*
X518597Y902445D01*
X519627D01*
X519812Y901845D01*
Y901671D01*
X518412D01*
Y901845D01*
G37*
G36*
G01D02*
X518597Y902445D01*
X519627D01*
X519812Y901845D01*
Y901671D01*
X518412D01*
Y901845D01*
G37*
G36*
G01X523905Y905049D02*
X524090Y905649D01*
X525120D01*
X525305Y905049D01*
Y904875D01*
X523905D01*
Y905049D01*
G37*
G36*
G01X520205D02*
X520390Y905649D01*
X521420D01*
X521605Y905049D01*
Y904874D01*
X520205D01*
Y905049D01*
G37*
G36*
G01X527629D02*
X527814Y905649D01*
X528844D01*
X529029Y905049D01*
Y904874D01*
X527629D01*
Y905049D01*
G37*
G36*
G01X531329D02*
X531514Y905649D01*
X532544D01*
X532729Y905049D01*
Y904874D01*
X531329D01*
Y905049D01*
G37*
G36*
G01X523905D02*
X524090Y905649D01*
X525120D01*
X525305Y905049D01*
Y904875D01*
X523905D01*
Y905049D01*
G37*
G36*
G01X520205D02*
X520390Y905649D01*
X521420D01*
X521605Y905049D01*
Y904874D01*
X520205D01*
Y905049D01*
G37*
G36*
G01X527629D02*
X527814Y905649D01*
X528844D01*
X529029Y905049D01*
Y904874D01*
X527629D01*
Y905049D01*
G37*
G36*
G01X531329D02*
X531514Y905649D01*
X532544D01*
X532729Y905049D01*
Y904874D01*
X531329D01*
Y905049D01*
G37*
G36*
G01X521595Y932291D02*
X521410Y931691D01*
X520380D01*
X520195Y932291D01*
Y932465D01*
X521595D01*
Y932291D01*
G37*
G36*
G01X525352D02*
X525167Y931691D01*
X524137D01*
X523952Y932291D01*
Y932465D01*
X525352D01*
Y932291D01*
G37*
G36*
G01X529029D02*
X528844Y931691D01*
X527814D01*
X527629Y932291D01*
Y932466D01*
X529029D01*
Y932291D01*
G37*
G36*
G01X532705D02*
X532520Y931691D01*
X531490D01*
X531305Y932291D01*
Y932466D01*
X532705D01*
Y932291D01*
G37*
G36*
G01X521595D02*
X521410Y931691D01*
X520380D01*
X520195Y932291D01*
Y932465D01*
X521595D01*
Y932291D01*
G37*
G36*
G01X525352D02*
X525167Y931691D01*
X524137D01*
X523952Y932291D01*
Y932465D01*
X525352D01*
Y932291D01*
G37*
G36*
G01X529029D02*
X528844Y931691D01*
X527814D01*
X527629Y932291D01*
Y932466D01*
X529029D01*
Y932291D01*
G37*
G36*
G01X532705D02*
X532520Y931691D01*
X531490D01*
X531305Y932291D01*
Y932466D01*
X532705D01*
Y932291D01*
G37*
G36*
G01X520228Y930683D02*
X520413Y931283D01*
X521443D01*
X521628Y930683D01*
Y930509D01*
X520228D01*
Y930683D01*
G37*
G36*
G01X523905Y930685D02*
X524090Y931285D01*
X525120D01*
X525305Y930685D01*
Y930510D01*
X523905D01*
Y930685D01*
G37*
G36*
G01X527629Y930683D02*
X527814Y931283D01*
X528844D01*
X529029Y930683D01*
Y930509D01*
X527629D01*
Y930683D01*
G37*
G36*
G01X531305D02*
X531490Y931283D01*
X532520D01*
X532705Y930683D01*
Y930509D01*
X531305D01*
Y930683D01*
G37*
G36*
G01X520228D02*
X520413Y931283D01*
X521443D01*
X521628Y930683D01*
Y930509D01*
X520228D01*
Y930683D01*
G37*
G36*
G01X523905Y930685D02*
X524090Y931285D01*
X525120D01*
X525305Y930685D01*
Y930510D01*
X523905D01*
Y930685D01*
G37*
G36*
G01X527629Y930683D02*
X527814Y931283D01*
X528844D01*
X529029Y930683D01*
Y930509D01*
X527629D01*
Y930683D01*
G37*
G36*
G01X531305D02*
X531490Y931283D01*
X532520D01*
X532705Y930683D01*
Y930509D01*
X531305D01*
Y930683D01*
G37*
G36*
G01X525329Y919475D02*
X525144Y918875D01*
X524114D01*
X523929Y919475D01*
Y919649D01*
X525329D01*
Y919475D01*
G37*
G36*
G01X521605Y919473D02*
X521420Y918873D01*
X520390D01*
X520205Y919473D01*
Y919648D01*
X521605D01*
Y919473D01*
G37*
G36*
G01X529029Y919475D02*
X528844Y918875D01*
X527814D01*
X527629Y919475D01*
Y919649D01*
X529029D01*
Y919475D01*
G37*
G36*
G01X532729D02*
X532544Y918875D01*
X531514D01*
X531329Y919475D01*
Y919649D01*
X532729D01*
Y919475D01*
G37*
G36*
G01X525329D02*
X525144Y918875D01*
X524114D01*
X523929Y919475D01*
Y919649D01*
X525329D01*
Y919475D01*
G37*
G36*
G01X521605Y919473D02*
X521420Y918873D01*
X520390D01*
X520205Y919473D01*
Y919648D01*
X521605D01*
Y919473D01*
G37*
G36*
G01X529029Y919475D02*
X528844Y918875D01*
X527814D01*
X527629Y919475D01*
Y919649D01*
X529029D01*
Y919475D01*
G37*
G36*
G01X532729D02*
X532544Y918875D01*
X531514D01*
X531329Y919475D01*
Y919649D01*
X532729D01*
Y919475D01*
G37*
G36*
G01X522079Y921071D02*
X522264Y921671D01*
X523294D01*
X523479Y921071D01*
Y920896D01*
X522079D01*
Y921071D01*
G37*
G36*
G01X525779D02*
X525964Y921671D01*
X526994D01*
X527179Y921071D01*
Y920896D01*
X525779D01*
Y921071D01*
G37*
G36*
G01X529479D02*
X529664Y921671D01*
X530694D01*
X530879Y921071D01*
Y920896D01*
X529479D01*
Y921071D01*
G37*
G36*
G01X522079D02*
X522264Y921671D01*
X523294D01*
X523479Y921071D01*
Y920896D01*
X522079D01*
Y921071D01*
G37*
G36*
G01X525779D02*
X525964Y921671D01*
X526994D01*
X527179Y921071D01*
Y920896D01*
X525779D01*
Y921071D01*
G37*
G36*
G01X529479D02*
X529664Y921671D01*
X530694D01*
X530879Y921071D01*
Y920896D01*
X529479D01*
Y921071D01*
G37*
G36*
G01X518362Y921069D02*
X518547Y921669D01*
X519577D01*
X519762Y921069D01*
Y920895D01*
X518362D01*
Y921069D01*
G37*
G36*
G01D02*
X518547Y921669D01*
X519577D01*
X519762Y921069D01*
Y920895D01*
X518362D01*
Y921069D01*
G37*
G36*
G01X523962Y917867D02*
X524147Y918467D01*
X525177D01*
X525362Y917867D01*
Y917692D01*
X523962D01*
Y917867D01*
G37*
G36*
G01X520205D02*
X520390Y918467D01*
X521420D01*
X521605Y917867D01*
Y917692D01*
X520205D01*
Y917867D01*
G37*
G36*
G01X527629Y917865D02*
X527814Y918465D01*
X528844D01*
X529029Y917865D01*
Y917691D01*
X527629D01*
Y917865D01*
G37*
G36*
G01X531329D02*
X531514Y918465D01*
X532544D01*
X532729Y917865D01*
Y917691D01*
X531329D01*
Y917865D01*
G37*
G36*
G01X523962Y917867D02*
X524147Y918467D01*
X525177D01*
X525362Y917867D01*
Y917692D01*
X523962D01*
Y917867D01*
G37*
G36*
G01X520205D02*
X520390Y918467D01*
X521420D01*
X521605Y917867D01*
Y917692D01*
X520205D01*
Y917867D01*
G37*
G36*
G01X527629Y917865D02*
X527814Y918465D01*
X528844D01*
X529029Y917865D01*
Y917691D01*
X527629D01*
Y917865D01*
G37*
G36*
G01X531329D02*
X531514Y918465D01*
X532544D01*
X532729Y917865D01*
Y917691D01*
X531329D01*
Y917865D01*
G37*
G36*
G01X523502Y929087D02*
X523317Y928487D01*
X522287D01*
X522102Y929087D01*
Y929261D01*
X523502D01*
Y929087D01*
G37*
G36*
G01X527179D02*
X526994Y928487D01*
X525964D01*
X525779Y929087D01*
Y929262D01*
X527179D01*
Y929087D01*
G37*
G36*
G01X530879D02*
X530694Y928487D01*
X529664D01*
X529479Y929087D01*
Y929262D01*
X530879D01*
Y929087D01*
G37*
G36*
G01X523502D02*
X523317Y928487D01*
X522287D01*
X522102Y929087D01*
Y929261D01*
X523502D01*
Y929087D01*
G37*
G36*
G01X527179D02*
X526994Y928487D01*
X525964D01*
X525779Y929087D01*
Y929262D01*
X527179D01*
Y929087D01*
G37*
G36*
G01X530879D02*
X530694Y928487D01*
X529664D01*
X529479Y929087D01*
Y929262D01*
X530879D01*
Y929087D01*
G37*
G36*
G01X519802D02*
X519617Y928487D01*
X518587D01*
X518402Y929087D01*
Y929262D01*
X519802D01*
Y929087D01*
G37*
G36*
G01D02*
X519617Y928487D01*
X518587D01*
X518402Y929087D01*
Y929262D01*
X519802D01*
Y929087D01*
G37*
G36*
G01X523512Y922679D02*
X523327Y922079D01*
X522297D01*
X522112Y922679D01*
Y922853D01*
X523512D01*
Y922679D01*
G37*
G36*
G01X527179D02*
X526994Y922079D01*
X525964D01*
X525779Y922679D01*
Y922854D01*
X527179D01*
Y922679D01*
G37*
G36*
G01X530879D02*
X530694Y922079D01*
X529664D01*
X529479Y922679D01*
Y922854D01*
X530879D01*
Y922679D01*
G37*
G36*
G01X523512D02*
X523327Y922079D01*
X522297D01*
X522112Y922679D01*
Y922853D01*
X523512D01*
Y922679D01*
G37*
G36*
G01X527179D02*
X526994Y922079D01*
X525964D01*
X525779Y922679D01*
Y922854D01*
X527179D01*
Y922679D01*
G37*
G36*
G01X530879D02*
X530694Y922079D01*
X529664D01*
X529479Y922679D01*
Y922854D01*
X530879D01*
Y922679D01*
G37*
G36*
G01X519779D02*
X519594Y922079D01*
X518564D01*
X518379Y922679D01*
Y922854D01*
X519779D01*
Y922679D01*
G37*
G36*
G01D02*
X519594Y922079D01*
X518564D01*
X518379Y922679D01*
Y922854D01*
X519779D01*
Y922679D01*
G37*
G36*
G01X522102Y927479D02*
X522287Y928079D01*
X523317D01*
X523502Y927479D01*
Y927305D01*
X522102D01*
Y927479D01*
G37*
G36*
G01X525779D02*
X525964Y928079D01*
X526994D01*
X527179Y927479D01*
Y927304D01*
X525779D01*
Y927479D01*
G37*
G36*
G01X529479D02*
X529664Y928079D01*
X530694D01*
X530879Y927479D01*
Y927304D01*
X529479D01*
Y927479D01*
G37*
G36*
G01X522102D02*
X522287Y928079D01*
X523317D01*
X523502Y927479D01*
Y927305D01*
X522102D01*
Y927479D01*
G37*
G36*
G01X525779D02*
X525964Y928079D01*
X526994D01*
X527179Y927479D01*
Y927304D01*
X525779D01*
Y927479D01*
G37*
G36*
G01X529479D02*
X529664Y928079D01*
X530694D01*
X530879Y927479D01*
Y927304D01*
X529479D01*
Y927479D01*
G37*
G36*
G01X518365D02*
X518550Y928079D01*
X519580D01*
X519765Y927479D01*
Y927304D01*
X518365D01*
Y927479D01*
G37*
G36*
G01D02*
X518550Y928079D01*
X519580D01*
X519765Y927479D01*
Y927304D01*
X518365D01*
Y927479D01*
G37*
G36*
G01X523905Y924275D02*
X524090Y924875D01*
X525120D01*
X525305Y924275D01*
Y924101D01*
X523905D01*
Y924275D01*
G37*
G36*
G01X520205D02*
X520390Y924875D01*
X521420D01*
X521605Y924275D01*
Y924100D01*
X520205D01*
Y924275D01*
G37*
G36*
G01X527629D02*
X527814Y924875D01*
X528844D01*
X529029Y924275D01*
Y924100D01*
X527629D01*
Y924275D01*
G37*
G36*
G01X531329D02*
X531514Y924875D01*
X532544D01*
X532729Y924275D01*
Y924100D01*
X531329D01*
Y924275D01*
G37*
G36*
G01X523905D02*
X524090Y924875D01*
X525120D01*
X525305Y924275D01*
Y924101D01*
X523905D01*
Y924275D01*
G37*
G36*
G01X520205D02*
X520390Y924875D01*
X521420D01*
X521605Y924275D01*
Y924100D01*
X520205D01*
Y924275D01*
G37*
G36*
G01X527629D02*
X527814Y924875D01*
X528844D01*
X529029Y924275D01*
Y924100D01*
X527629D01*
Y924275D01*
G37*
G36*
G01X531329D02*
X531514Y924875D01*
X532544D01*
X532729Y924275D01*
Y924100D01*
X531329D01*
Y924275D01*
G37*
G36*
G01X525305Y925883D02*
X525120Y925283D01*
X524090D01*
X523905Y925883D01*
Y926057D01*
X525305D01*
Y925883D01*
G37*
G36*
G01X521642D02*
X521457Y925283D01*
X520427D01*
X520242Y925883D01*
Y926058D01*
X521642D01*
Y925883D01*
G37*
G36*
G01X529029D02*
X528844Y925283D01*
X527814D01*
X527629Y925883D01*
Y926058D01*
X529029D01*
Y925883D01*
G37*
G36*
G01X532729D02*
X532544Y925283D01*
X531514D01*
X531329Y925883D01*
Y926058D01*
X532729D01*
Y925883D01*
G37*
G36*
G01X525305D02*
X525120Y925283D01*
X524090D01*
X523905Y925883D01*
Y926057D01*
X525305D01*
Y925883D01*
G37*
G36*
G01X521642D02*
X521457Y925283D01*
X520427D01*
X520242Y925883D01*
Y926058D01*
X521642D01*
Y925883D01*
G37*
G36*
G01X529029D02*
X528844Y925283D01*
X527814D01*
X527629Y925883D01*
Y926058D01*
X529029D01*
Y925883D01*
G37*
G36*
G01X532729D02*
X532544Y925283D01*
X531514D01*
X531329Y925883D01*
Y926058D01*
X532729D01*
Y925883D01*
G37*
G36*
G01X523502Y948313D02*
X523317Y947713D01*
X522287D01*
X522102Y948313D01*
Y948487D01*
X523502D01*
Y948313D01*
G37*
G36*
G01X527179D02*
X526994Y947713D01*
X525964D01*
X525779Y948313D01*
Y948488D01*
X527179D01*
Y948313D01*
G37*
G36*
G01X530912D02*
X530727Y947713D01*
X529697D01*
X529512Y948313D01*
Y948487D01*
X530912D01*
Y948313D01*
G37*
G36*
G01X523502D02*
X523317Y947713D01*
X522287D01*
X522102Y948313D01*
Y948487D01*
X523502D01*
Y948313D01*
G37*
G36*
G01X527179D02*
X526994Y947713D01*
X525964D01*
X525779Y948313D01*
Y948488D01*
X527179D01*
Y948313D01*
G37*
G36*
G01X530912D02*
X530727Y947713D01*
X529697D01*
X529512Y948313D01*
Y948487D01*
X530912D01*
Y948313D01*
G37*
G36*
G01X519802D02*
X519617Y947713D01*
X518587D01*
X518402Y948313D01*
Y948488D01*
X519802D01*
Y948313D01*
G37*
G36*
G01D02*
X519617Y947713D01*
X518587D01*
X518402Y948313D01*
Y948488D01*
X519802D01*
Y948313D01*
G37*
G36*
G01X529479Y940295D02*
X529664Y940895D01*
X530694D01*
X530879Y940295D01*
Y940121D01*
X529479D01*
Y940295D01*
G37*
G36*
G01X525766D02*
X525951Y940895D01*
X526981D01*
X527166Y940295D01*
Y940121D01*
X525766D01*
Y940295D01*
G37*
G36*
G01X522062D02*
X522247Y940895D01*
X523277D01*
X523462Y940295D01*
Y940121D01*
X522062D01*
Y940295D01*
G37*
G36*
G01X529479D02*
X529664Y940895D01*
X530694D01*
X530879Y940295D01*
Y940121D01*
X529479D01*
Y940295D01*
G37*
G36*
G01X525766D02*
X525951Y940895D01*
X526981D01*
X527166Y940295D01*
Y940121D01*
X525766D01*
Y940295D01*
G37*
G36*
G01X522062D02*
X522247Y940895D01*
X523277D01*
X523462Y940295D01*
Y940121D01*
X522062D01*
Y940295D01*
G37*
G36*
G01X518362D02*
X518547Y940895D01*
X519577D01*
X519762Y940295D01*
Y940121D01*
X518362D01*
Y940295D01*
G37*
G36*
G01D02*
X518547Y940895D01*
X519577D01*
X519762Y940295D01*
Y940121D01*
X518362D01*
Y940295D01*
G37*
G36*
G01X531329Y937091D02*
X531514Y937691D01*
X532544D01*
X532729Y937091D01*
Y936917D01*
X531329D01*
Y937091D01*
G37*
G36*
G01X520242D02*
X520427Y937691D01*
X521457D01*
X521642Y937091D01*
Y936916D01*
X520242D01*
Y937091D01*
G37*
G36*
G01X527628D02*
X527813Y937691D01*
X528843D01*
X529028Y937091D01*
Y936916D01*
X527628D01*
Y937091D01*
G37*
G36*
G01X523942D02*
X524127Y937691D01*
X525157D01*
X525342Y937091D01*
Y936916D01*
X523942D01*
Y937091D01*
G37*
G36*
G01X531329D02*
X531514Y937691D01*
X532544D01*
X532729Y937091D01*
Y936917D01*
X531329D01*
Y937091D01*
G37*
G36*
G01X520242D02*
X520427Y937691D01*
X521457D01*
X521642Y937091D01*
Y936916D01*
X520242D01*
Y937091D01*
G37*
G36*
G01X527628D02*
X527813Y937691D01*
X528843D01*
X529028Y937091D01*
Y936916D01*
X527628D01*
Y937091D01*
G37*
G36*
G01X523942D02*
X524127Y937691D01*
X525157D01*
X525342Y937091D01*
Y936916D01*
X523942D01*
Y937091D01*
G37*
G36*
G01X521645Y938701D02*
X521460Y938101D01*
X520430D01*
X520245Y938701D01*
Y938875D01*
X521645D01*
Y938701D01*
G37*
G36*
G01X525345D02*
X525160Y938101D01*
X524130D01*
X523945Y938701D01*
Y938875D01*
X525345D01*
Y938701D01*
G37*
G36*
G01X529028D02*
X528843Y938101D01*
X527813D01*
X527628Y938701D01*
Y938875D01*
X529028D01*
Y938701D01*
G37*
G36*
G01X532729D02*
X532544Y938101D01*
X531514D01*
X531329Y938701D01*
Y938875D01*
X532729D01*
Y938701D01*
G37*
G36*
G01X521645D02*
X521460Y938101D01*
X520430D01*
X520245Y938701D01*
Y938875D01*
X521645D01*
Y938701D01*
G37*
G36*
G01X525345D02*
X525160Y938101D01*
X524130D01*
X523945Y938701D01*
Y938875D01*
X525345D01*
Y938701D01*
G37*
G36*
G01X529028D02*
X528843Y938101D01*
X527813D01*
X527628Y938701D01*
Y938875D01*
X529028D01*
Y938701D01*
G37*
G36*
G01X532729D02*
X532544Y938101D01*
X531514D01*
X531329Y938701D01*
Y938875D01*
X532729D01*
Y938701D01*
G37*
G36*
G01X527170Y935495D02*
X526985Y934895D01*
X525955D01*
X525770Y935495D01*
Y935670D01*
X527170D01*
Y935495D01*
G37*
G36*
G01X523465Y935497D02*
X523280Y934897D01*
X522250D01*
X522065Y935497D01*
Y935671D01*
X523465D01*
Y935497D01*
G37*
G36*
G01X530879Y935495D02*
X530694Y934895D01*
X529664D01*
X529479Y935495D01*
Y935670D01*
X530879D01*
Y935495D01*
G37*
G36*
G01X527170D02*
X526985Y934895D01*
X525955D01*
X525770Y935495D01*
Y935670D01*
X527170D01*
Y935495D01*
G37*
G36*
G01X523465Y935497D02*
X523280Y934897D01*
X522250D01*
X522065Y935497D01*
Y935671D01*
X523465D01*
Y935497D01*
G37*
G36*
G01X530879Y935495D02*
X530694Y934895D01*
X529664D01*
X529479Y935495D01*
Y935670D01*
X530879D01*
Y935495D01*
G37*
G36*
G01X519765Y935497D02*
X519580Y934897D01*
X518550D01*
X518365Y935497D01*
Y935671D01*
X519765D01*
Y935497D01*
G37*
G36*
G01D02*
X519580Y934897D01*
X518550D01*
X518365Y935497D01*
Y935671D01*
X519765D01*
Y935497D01*
G37*
G36*
G01X522102Y933887D02*
X522287Y934487D01*
X523317D01*
X523502Y933887D01*
Y933713D01*
X522102D01*
Y933887D01*
G37*
G36*
G01X525755Y933889D02*
X525940Y934489D01*
X526970D01*
X527155Y933889D01*
Y933714D01*
X525755D01*
Y933889D01*
G37*
G36*
G01X529479Y933887D02*
X529664Y934487D01*
X530694D01*
X530879Y933887D01*
Y933713D01*
X529479D01*
Y933887D01*
G37*
G36*
G01X522102D02*
X522287Y934487D01*
X523317D01*
X523502Y933887D01*
Y933713D01*
X522102D01*
Y933887D01*
G37*
G36*
G01X525755Y933889D02*
X525940Y934489D01*
X526970D01*
X527155Y933889D01*
Y933714D01*
X525755D01*
Y933889D01*
G37*
G36*
G01X529479Y933887D02*
X529664Y934487D01*
X530694D01*
X530879Y933887D01*
Y933713D01*
X529479D01*
Y933887D01*
G37*
G36*
G01X518412Y933889D02*
X518597Y934489D01*
X519627D01*
X519812Y933889D01*
Y933714D01*
X518412D01*
Y933889D01*
G37*
G36*
G01D02*
X518597Y934489D01*
X519627D01*
X519812Y933889D01*
Y933714D01*
X518412D01*
Y933889D01*
G37*
G36*
G01X521652Y945109D02*
X521467Y944509D01*
X520437D01*
X520252Y945109D01*
Y945283D01*
X521652D01*
Y945109D01*
G37*
G36*
G01X525305Y945107D02*
X525120Y944507D01*
X524090D01*
X523905Y945107D01*
Y945282D01*
X525305D01*
Y945107D01*
G37*
G36*
G01X529005Y945109D02*
X528820Y944509D01*
X527790D01*
X527605Y945109D01*
Y945283D01*
X529005D01*
Y945109D01*
G37*
G36*
G01X532729D02*
X532544Y944509D01*
X531514D01*
X531329Y945109D01*
Y945284D01*
X532729D01*
Y945109D01*
G37*
G36*
G01X521652D02*
X521467Y944509D01*
X520437D01*
X520252Y945109D01*
Y945283D01*
X521652D01*
Y945109D01*
G37*
G36*
G01X525305Y945107D02*
X525120Y944507D01*
X524090D01*
X523905Y945107D01*
Y945282D01*
X525305D01*
Y945107D01*
G37*
G36*
G01X529005Y945109D02*
X528820Y944509D01*
X527790D01*
X527605Y945109D01*
Y945283D01*
X529005D01*
Y945109D01*
G37*
G36*
G01X532729D02*
X532544Y944509D01*
X531514D01*
X531329Y945109D01*
Y945284D01*
X532729D01*
Y945109D01*
G37*
G36*
G01X531305Y943501D02*
X531490Y944101D01*
X532520D01*
X532705Y943501D01*
Y943326D01*
X531305D01*
Y943501D01*
G37*
G36*
G01X527605Y943499D02*
X527790Y944099D01*
X528820D01*
X529005Y943499D01*
Y943325D01*
X527605D01*
Y943499D01*
G37*
G36*
G01X523905Y943501D02*
X524090Y944101D01*
X525120D01*
X525305Y943501D01*
Y943326D01*
X523905D01*
Y943501D01*
G37*
G36*
G01X520205Y943499D02*
X520390Y944099D01*
X521420D01*
X521605Y943499D01*
Y943325D01*
X520205D01*
Y943499D01*
G37*
G36*
G01X531305Y943501D02*
X531490Y944101D01*
X532520D01*
X532705Y943501D01*
Y943326D01*
X531305D01*
Y943501D01*
G37*
G36*
G01X527605Y943499D02*
X527790Y944099D01*
X528820D01*
X529005Y943499D01*
Y943325D01*
X527605D01*
Y943499D01*
G37*
G36*
G01X523905Y943501D02*
X524090Y944101D01*
X525120D01*
X525305Y943501D01*
Y943326D01*
X523905D01*
Y943501D01*
G37*
G36*
G01X520205Y943499D02*
X520390Y944099D01*
X521420D01*
X521605Y943499D01*
Y943325D01*
X520205D01*
Y943499D01*
G37*
G36*
G01X522102Y946705D02*
X522287Y947305D01*
X523317D01*
X523502Y946705D01*
Y946531D01*
X522102D01*
Y946705D01*
G37*
G36*
G01X525779D02*
X525964Y947305D01*
X526994D01*
X527179Y946705D01*
Y946530D01*
X525779D01*
Y946705D01*
G37*
G36*
G01X529512D02*
X529697Y947305D01*
X530727D01*
X530912Y946705D01*
Y946531D01*
X529512D01*
Y946705D01*
G37*
G36*
G01X522102D02*
X522287Y947305D01*
X523317D01*
X523502Y946705D01*
Y946531D01*
X522102D01*
Y946705D01*
G37*
G36*
G01X525779D02*
X525964Y947305D01*
X526994D01*
X527179Y946705D01*
Y946530D01*
X525779D01*
Y946705D01*
G37*
G36*
G01X529512D02*
X529697Y947305D01*
X530727D01*
X530912Y946705D01*
Y946531D01*
X529512D01*
Y946705D01*
G37*
G36*
G01X518355D02*
X518540Y947305D01*
X519570D01*
X519755Y946705D01*
Y946530D01*
X518355D01*
Y946705D01*
G37*
G36*
G01D02*
X518540Y947305D01*
X519570D01*
X519755Y946705D01*
Y946530D01*
X518355D01*
Y946705D01*
G37*
G36*
G01X527179Y941905D02*
X526994Y941305D01*
X525964D01*
X525779Y941905D01*
Y942079D01*
X527179D01*
Y941905D01*
G37*
G36*
G01X530912Y941903D02*
X530727Y941303D01*
X529697D01*
X529512Y941903D01*
Y942078D01*
X530912D01*
Y941903D01*
G37*
G36*
G01X523512D02*
X523327Y941303D01*
X522297D01*
X522112Y941903D01*
Y942078D01*
X523512D01*
Y941903D01*
G37*
G36*
G01X527179Y941905D02*
X526994Y941305D01*
X525964D01*
X525779Y941905D01*
Y942079D01*
X527179D01*
Y941905D01*
G37*
G36*
G01X530912Y941903D02*
X530727Y941303D01*
X529697D01*
X529512Y941903D01*
Y942078D01*
X530912D01*
Y941903D01*
G37*
G36*
G01X523512D02*
X523327Y941303D01*
X522297D01*
X522112Y941903D01*
Y942078D01*
X523512D01*
Y941903D01*
G37*
G36*
G01X519779Y941905D02*
X519594Y941305D01*
X518564D01*
X518379Y941905D01*
Y942079D01*
X519779D01*
Y941905D01*
G37*
G36*
G01D02*
X519594Y941305D01*
X518564D01*
X518379Y941905D01*
Y942079D01*
X519779D01*
Y941905D01*
G37*
G36*
G01X525779Y953113D02*
X525964Y953713D01*
X526994D01*
X527179Y953113D01*
Y952938D01*
X525779D01*
Y953113D01*
G37*
G36*
G01X522112D02*
X522297Y953713D01*
X523327D01*
X523512Y953113D01*
Y952939D01*
X522112D01*
Y953113D01*
G37*
G36*
G01X529512D02*
X529697Y953713D01*
X530727D01*
X530912Y953113D01*
Y952939D01*
X529512D01*
Y953113D01*
G37*
G36*
G01X525779D02*
X525964Y953713D01*
X526994D01*
X527179Y953113D01*
Y952938D01*
X525779D01*
Y953113D01*
G37*
G36*
G01X522112D02*
X522297Y953713D01*
X523327D01*
X523512Y953113D01*
Y952939D01*
X522112D01*
Y953113D01*
G37*
G36*
G01X529512D02*
X529697Y953713D01*
X530727D01*
X530912Y953113D01*
Y952939D01*
X529512D01*
Y953113D01*
G37*
G36*
G01X518412D02*
X518597Y953713D01*
X519627D01*
X519812Y953113D01*
Y952939D01*
X518412D01*
Y953113D01*
G37*
G36*
G01D02*
X518597Y953713D01*
X519627D01*
X519812Y953113D01*
Y952939D01*
X518412D01*
Y953113D01*
G37*
G36*
G01X520228Y949909D02*
X520413Y950509D01*
X521443D01*
X521628Y949909D01*
Y949734D01*
X520228D01*
Y949909D01*
G37*
G36*
G01X527605D02*
X527790Y950509D01*
X528820D01*
X529005Y949909D01*
Y949734D01*
X527605D01*
Y949909D01*
G37*
G36*
G01X523905D02*
X524090Y950509D01*
X525120D01*
X525305Y949909D01*
Y949735D01*
X523905D01*
Y949909D01*
G37*
G36*
G01X531305D02*
X531490Y950509D01*
X532520D01*
X532705Y949909D01*
Y949735D01*
X531305D01*
Y949909D01*
G37*
G36*
G01X520228D02*
X520413Y950509D01*
X521443D01*
X521628Y949909D01*
Y949734D01*
X520228D01*
Y949909D01*
G37*
G36*
G01X527605D02*
X527790Y950509D01*
X528820D01*
X529005Y949909D01*
Y949734D01*
X527605D01*
Y949909D01*
G37*
G36*
G01X523905D02*
X524090Y950509D01*
X525120D01*
X525305Y949909D01*
Y949735D01*
X523905D01*
Y949909D01*
G37*
G36*
G01X531305D02*
X531490Y950509D01*
X532520D01*
X532705Y949909D01*
Y949735D01*
X531305D01*
Y949909D01*
G37*
G36*
G01X521595Y951517D02*
X521410Y950917D01*
X520380D01*
X520195Y951517D01*
Y951691D01*
X521595D01*
Y951517D01*
G37*
G36*
G01X529005D02*
X528820Y950917D01*
X527790D01*
X527605Y951517D01*
Y951692D01*
X529005D01*
Y951517D01*
G37*
G36*
G01X525305D02*
X525120Y950917D01*
X524090D01*
X523905Y951517D01*
Y951691D01*
X525305D01*
Y951517D01*
G37*
G36*
G01X532705D02*
X532520Y950917D01*
X531490D01*
X531305Y951517D01*
Y951691D01*
X532705D01*
Y951517D01*
G37*
G36*
G01X521595D02*
X521410Y950917D01*
X520380D01*
X520195Y951517D01*
Y951691D01*
X521595D01*
Y951517D01*
G37*
G36*
G01X529005D02*
X528820Y950917D01*
X527790D01*
X527605Y951517D01*
Y951692D01*
X529005D01*
Y951517D01*
G37*
G36*
G01X525305D02*
X525120Y950917D01*
X524090D01*
X523905Y951517D01*
Y951691D01*
X525305D01*
Y951517D01*
G37*
G36*
G01X532705D02*
X532520Y950917D01*
X531490D01*
X531305Y951517D01*
Y951691D01*
X532705D01*
Y951517D01*
G37*
G36*
G01X522079Y959521D02*
X522264Y960121D01*
X523294D01*
X523479Y959521D01*
Y959347D01*
X522079D01*
Y959521D01*
G37*
G36*
G01X525779D02*
X525964Y960121D01*
X526994D01*
X527179Y959521D01*
Y959347D01*
X525779D01*
Y959521D01*
G37*
G36*
G01X529512Y959523D02*
X529697Y960123D01*
X530727D01*
X530912Y959523D01*
Y959348D01*
X529512D01*
Y959523D01*
G37*
G36*
G01X522079Y959521D02*
X522264Y960121D01*
X523294D01*
X523479Y959521D01*
Y959347D01*
X522079D01*
Y959521D01*
G37*
G36*
G01X525779D02*
X525964Y960121D01*
X526994D01*
X527179Y959521D01*
Y959347D01*
X525779D01*
Y959521D01*
G37*
G36*
G01X529512Y959523D02*
X529697Y960123D01*
X530727D01*
X530912Y959523D01*
Y959348D01*
X529512D01*
Y959523D01*
G37*
G36*
G01X518412D02*
X518597Y960123D01*
X519627D01*
X519812Y959523D01*
Y959348D01*
X518412D01*
Y959523D01*
G37*
G36*
G01D02*
X518597Y960123D01*
X519627D01*
X519812Y959523D01*
Y959348D01*
X518412D01*
Y959523D01*
G37*
G36*
G01X521605Y957925D02*
X521420Y957325D01*
X520390D01*
X520205Y957925D01*
Y958100D01*
X521605D01*
Y957925D01*
G37*
G36*
G01X525329Y957927D02*
X525144Y957327D01*
X524114D01*
X523929Y957927D01*
Y958101D01*
X525329D01*
Y957927D01*
G37*
G36*
G01X529005D02*
X528820Y957327D01*
X527790D01*
X527605Y957927D01*
Y958101D01*
X529005D01*
Y957927D01*
G37*
G36*
G01X532705Y957925D02*
X532520Y957325D01*
X531490D01*
X531305Y957925D01*
Y958100D01*
X532705D01*
Y957925D01*
G37*
G36*
G01X521605D02*
X521420Y957325D01*
X520390D01*
X520205Y957925D01*
Y958100D01*
X521605D01*
Y957925D01*
G37*
G36*
G01X525329Y957927D02*
X525144Y957327D01*
X524114D01*
X523929Y957927D01*
Y958101D01*
X525329D01*
Y957927D01*
G37*
G36*
G01X529005D02*
X528820Y957327D01*
X527790D01*
X527605Y957927D01*
Y958101D01*
X529005D01*
Y957927D01*
G37*
G36*
G01X532705Y957925D02*
X532520Y957325D01*
X531490D01*
X531305Y957925D01*
Y958100D01*
X532705D01*
Y957925D01*
G37*
G36*
G01X523905Y962727D02*
X524090Y963327D01*
X525120D01*
X525305Y962727D01*
Y962552D01*
X523905D01*
Y962727D01*
G37*
G36*
G01X527605Y962725D02*
X527790Y963325D01*
X528820D01*
X529005Y962725D01*
Y962551D01*
X527605D01*
Y962725D01*
G37*
G36*
G01X531305Y962727D02*
X531490Y963327D01*
X532520D01*
X532705Y962727D01*
Y962552D01*
X531305D01*
Y962727D01*
G37*
G36*
G01X520205Y962725D02*
X520390Y963325D01*
X521420D01*
X521605Y962725D01*
Y962551D01*
X520205D01*
Y962725D01*
G37*
G36*
G01X523905Y962727D02*
X524090Y963327D01*
X525120D01*
X525305Y962727D01*
Y962552D01*
X523905D01*
Y962727D01*
G37*
G36*
G01X527605Y962725D02*
X527790Y963325D01*
X528820D01*
X529005Y962725D01*
Y962551D01*
X527605D01*
Y962725D01*
G37*
G36*
G01X531305Y962727D02*
X531490Y963327D01*
X532520D01*
X532705Y962727D01*
Y962552D01*
X531305D01*
Y962727D01*
G37*
G36*
G01X520205Y962725D02*
X520390Y963325D01*
X521420D01*
X521605Y962725D01*
Y962551D01*
X520205D01*
Y962725D01*
G37*
G36*
G01X523512Y961129D02*
X523327Y960529D01*
X522297D01*
X522112Y961129D01*
Y961304D01*
X523512D01*
Y961129D01*
G37*
G36*
G01X527179Y961131D02*
X526994Y960531D01*
X525964D01*
X525779Y961131D01*
Y961305D01*
X527179D01*
Y961131D01*
G37*
G36*
G01X530912Y961129D02*
X530727Y960529D01*
X529697D01*
X529512Y961129D01*
Y961304D01*
X530912D01*
Y961129D01*
G37*
G36*
G01X523512D02*
X523327Y960529D01*
X522297D01*
X522112Y961129D01*
Y961304D01*
X523512D01*
Y961129D01*
G37*
G36*
G01X527179Y961131D02*
X526994Y960531D01*
X525964D01*
X525779Y961131D01*
Y961305D01*
X527179D01*
Y961131D01*
G37*
G36*
G01X530912Y961129D02*
X530727Y960529D01*
X529697D01*
X529512Y961129D01*
Y961304D01*
X530912D01*
Y961129D01*
G37*
G36*
G01X519779Y961131D02*
X519594Y960531D01*
X518564D01*
X518379Y961131D01*
Y961305D01*
X519779D01*
Y961131D01*
G37*
G36*
G01D02*
X519594Y960531D01*
X518564D01*
X518379Y961131D01*
Y961305D01*
X519779D01*
Y961131D01*
G37*
G36*
G01X520229Y981951D02*
X520414Y982551D01*
X521444D01*
X521629Y981951D01*
Y981777D01*
X520229D01*
Y981951D01*
G37*
G36*
G01X523929D02*
X524114Y982551D01*
X525144D01*
X525329Y981951D01*
Y981777D01*
X523929D01*
Y981951D01*
G37*
G36*
G01X527629D02*
X527814Y982551D01*
X528844D01*
X529029Y981951D01*
Y981777D01*
X527629D01*
Y981951D01*
G37*
G36*
G01X520229D02*
X520414Y982551D01*
X521444D01*
X521629Y981951D01*
Y981777D01*
X520229D01*
Y981951D01*
G37*
G36*
G01X523929D02*
X524114Y982551D01*
X525144D01*
X525329Y981951D01*
Y981777D01*
X523929D01*
Y981951D01*
G37*
G36*
G01X527629D02*
X527814Y982551D01*
X528844D01*
X529029Y981951D01*
Y981777D01*
X527629D01*
Y981951D01*
G37*
G36*
G01X522079Y978747D02*
X522264Y979347D01*
X523294D01*
X523479Y978747D01*
Y978573D01*
X522079D01*
Y978747D01*
G37*
G36*
G01X525779D02*
X525964Y979347D01*
X526994D01*
X527179Y978747D01*
Y978573D01*
X525779D01*
Y978747D01*
G37*
G36*
G01X529479D02*
X529664Y979347D01*
X530694D01*
X530879Y978747D01*
Y978573D01*
X529479D01*
Y978747D01*
G37*
G36*
G01X522079D02*
X522264Y979347D01*
X523294D01*
X523479Y978747D01*
Y978573D01*
X522079D01*
Y978747D01*
G37*
G36*
G01X525779D02*
X525964Y979347D01*
X526994D01*
X527179Y978747D01*
Y978573D01*
X525779D01*
Y978747D01*
G37*
G36*
G01X529479D02*
X529664Y979347D01*
X530694D01*
X530879Y978747D01*
Y978573D01*
X529479D01*
Y978747D01*
G37*
G36*
G01X518412Y978749D02*
X518597Y979349D01*
X519627D01*
X519812Y978749D01*
Y978574D01*
X518412D01*
Y978749D01*
G37*
G36*
G01D02*
X518597Y979349D01*
X519627D01*
X519812Y978749D01*
Y978574D01*
X518412D01*
Y978749D01*
G37*
G36*
G01X523479Y980357D02*
X523294Y979757D01*
X522264D01*
X522079Y980357D01*
Y980531D01*
X523479D01*
Y980357D01*
G37*
G36*
G01X527179D02*
X526994Y979757D01*
X525964D01*
X525779Y980357D01*
Y980531D01*
X527179D01*
Y980357D01*
G37*
G36*
G01X530879D02*
X530694Y979757D01*
X529664D01*
X529479Y980357D01*
Y980531D01*
X530879D01*
Y980357D01*
G37*
G36*
G01X523479D02*
X523294Y979757D01*
X522264D01*
X522079Y980357D01*
Y980531D01*
X523479D01*
Y980357D01*
G37*
G36*
G01X527179D02*
X526994Y979757D01*
X525964D01*
X525779Y980357D01*
Y980531D01*
X527179D01*
Y980357D01*
G37*
G36*
G01X530879D02*
X530694Y979757D01*
X529664D01*
X529479Y980357D01*
Y980531D01*
X530879D01*
Y980357D01*
G37*
G36*
G01X519779D02*
X519594Y979757D01*
X518564D01*
X518379Y980357D01*
Y980531D01*
X519779D01*
Y980357D01*
G37*
G36*
G01D02*
X519594Y979757D01*
X518564D01*
X518379Y980357D01*
Y980531D01*
X519779D01*
Y980357D01*
G37*
G36*
G01X521605Y977151D02*
X521420Y976551D01*
X520390D01*
X520205Y977151D01*
Y977325D01*
X521605D01*
Y977151D01*
G37*
G36*
G01X525329D02*
X525144Y976551D01*
X524114D01*
X523929Y977151D01*
Y977326D01*
X525329D01*
Y977151D01*
G37*
G36*
G01X529029D02*
X528844Y976551D01*
X527814D01*
X527629Y977151D01*
Y977326D01*
X529029D01*
Y977151D01*
G37*
G36*
G01X532729D02*
X532544Y976551D01*
X531514D01*
X531329Y977151D01*
Y977326D01*
X532729D01*
Y977151D01*
G37*
G36*
G01X521605D02*
X521420Y976551D01*
X520390D01*
X520205Y977151D01*
Y977325D01*
X521605D01*
Y977151D01*
G37*
G36*
G01X525329D02*
X525144Y976551D01*
X524114D01*
X523929Y977151D01*
Y977326D01*
X525329D01*
Y977151D01*
G37*
G36*
G01X529029D02*
X528844Y976551D01*
X527814D01*
X527629Y977151D01*
Y977326D01*
X529029D01*
Y977151D01*
G37*
G36*
G01X532729D02*
X532544Y976551D01*
X531514D01*
X531329Y977151D01*
Y977326D01*
X532729D01*
Y977151D01*
G37*
G36*
G01X531176Y1005475D02*
X531603Y1005015D01*
X531088Y1004123D01*
X530476Y1004263D01*
X530325Y1004350D01*
X531025Y1005562D01*
X531176Y1005475D01*
G37*
G36*
G01D02*
X531603Y1005015D01*
X531088Y1004123D01*
X530476Y1004263D01*
X530325Y1004350D01*
X531025Y1005562D01*
X531176Y1005475D01*
G37*
G36*
G01X530043Y1006703D02*
X529616Y1007163D01*
X530131Y1008055D01*
X530743Y1007915D01*
X530894Y1007828D01*
X530194Y1006616D01*
X530043Y1006703D01*
G37*
G36*
G01X531761Y1008493D02*
X531946Y1009093D01*
X532976D01*
X533161Y1008493D01*
Y1008318D01*
X531761D01*
Y1008493D01*
G37*
G36*
G01X530043Y1006703D02*
X529616Y1007163D01*
X530131Y1008055D01*
X530743Y1007915D01*
X530894Y1007828D01*
X530194Y1006616D01*
X530043Y1006703D01*
G37*
G36*
G01X531761Y1008493D02*
X531946Y1009093D01*
X532976D01*
X533161Y1008493D01*
Y1008318D01*
X531761D01*
Y1008493D01*
G37*
G36*
G01X531901Y1003514D02*
X531474Y1003974D01*
X531989Y1004866D01*
X532601Y1004726D01*
X532752Y1004639D01*
X532052Y1003427D01*
X531901Y1003514D01*
G37*
G36*
G01D02*
X531474Y1003974D01*
X531989Y1004866D01*
X532601Y1004726D01*
X532752Y1004639D01*
X532052Y1003427D01*
X531901Y1003514D01*
G37*
G36*
G01X528028Y1027719D02*
X528213Y1028319D01*
X529243D01*
X529428Y1027719D01*
Y1027545D01*
X528028D01*
Y1027719D01*
G37*
G36*
G01X524361D02*
X524546Y1028319D01*
X525576D01*
X525761Y1027719D01*
Y1027544D01*
X524361D01*
Y1027719D01*
G37*
G36*
G01X520628D02*
X520813Y1028319D01*
X521843D01*
X522028Y1027719D01*
Y1027545D01*
X520628D01*
Y1027719D01*
G37*
G36*
G01X531761D02*
X531946Y1028319D01*
X532976D01*
X533161Y1027719D01*
Y1027544D01*
X531761D01*
Y1027719D01*
G37*
G36*
G01X528028D02*
X528213Y1028319D01*
X529243D01*
X529428Y1027719D01*
Y1027545D01*
X528028D01*
Y1027719D01*
G37*
G36*
G01X524361D02*
X524546Y1028319D01*
X525576D01*
X525761Y1027719D01*
Y1027544D01*
X524361D01*
Y1027719D01*
G37*
G36*
G01X520628D02*
X520813Y1028319D01*
X521843D01*
X522028Y1027719D01*
Y1027545D01*
X520628D01*
Y1027719D01*
G37*
G36*
G01X531761D02*
X531946Y1028319D01*
X532976D01*
X533161Y1027719D01*
Y1027544D01*
X531761D01*
Y1027719D01*
G37*
G36*
G01X516928D02*
X517113Y1028319D01*
X518143D01*
X518328Y1027719D01*
Y1027545D01*
X516928D01*
Y1027719D01*
G37*
G36*
G01D02*
X517113Y1028319D01*
X518143D01*
X518328Y1027719D01*
Y1027545D01*
X516928D01*
Y1027719D01*
G37*
G36*
G01X522061Y1029327D02*
X521876Y1028727D01*
X520846D01*
X520661Y1029327D01*
Y1029502D01*
X522061D01*
Y1029327D01*
G37*
G36*
G01X525728D02*
X525543Y1028727D01*
X524513D01*
X524328Y1029327D01*
Y1029501D01*
X525728D01*
Y1029327D01*
G37*
G36*
G01X529428D02*
X529243Y1028727D01*
X528213D01*
X528028Y1029327D01*
Y1029501D01*
X529428D01*
Y1029327D01*
G37*
G36*
G01X533161D02*
X532976Y1028727D01*
X531946D01*
X531761Y1029327D01*
Y1029502D01*
X533161D01*
Y1029327D01*
G37*
G36*
G01X522061D02*
X521876Y1028727D01*
X520846D01*
X520661Y1029327D01*
Y1029502D01*
X522061D01*
Y1029327D01*
G37*
G36*
G01X525728D02*
X525543Y1028727D01*
X524513D01*
X524328Y1029327D01*
Y1029501D01*
X525728D01*
Y1029327D01*
G37*
G36*
G01X529428D02*
X529243Y1028727D01*
X528213D01*
X528028Y1029327D01*
Y1029501D01*
X529428D01*
Y1029327D01*
G37*
G36*
G01X533161D02*
X532976Y1028727D01*
X531946D01*
X531761Y1029327D01*
Y1029502D01*
X533161D01*
Y1029327D01*
G37*
G36*
G01X518328D02*
X518143Y1028727D01*
X517113D01*
X516928Y1029327D01*
Y1029501D01*
X518328D01*
Y1029327D01*
G37*
G36*
G01D02*
X518143Y1028727D01*
X517113D01*
X516928Y1029327D01*
Y1029501D01*
X518328D01*
Y1029327D01*
G37*
G36*
G01X527635Y1026121D02*
X527450Y1025521D01*
X526420D01*
X526235Y1026121D01*
Y1026296D01*
X527635D01*
Y1026121D01*
G37*
G36*
G01X523935Y1026123D02*
X523750Y1025523D01*
X522720D01*
X522535Y1026123D01*
Y1026297D01*
X523935D01*
Y1026123D01*
G37*
G36*
G01X531335D02*
X531150Y1025523D01*
X530120D01*
X529935Y1026123D01*
Y1026297D01*
X531335D01*
Y1026123D01*
G37*
G36*
G01X527635Y1026121D02*
X527450Y1025521D01*
X526420D01*
X526235Y1026121D01*
Y1026296D01*
X527635D01*
Y1026121D01*
G37*
G36*
G01X523935Y1026123D02*
X523750Y1025523D01*
X522720D01*
X522535Y1026123D01*
Y1026297D01*
X523935D01*
Y1026123D01*
G37*
G36*
G01X531335D02*
X531150Y1025523D01*
X530120D01*
X529935Y1026123D01*
Y1026297D01*
X531335D01*
Y1026123D01*
G37*
G36*
G01X520245Y1026121D02*
X520060Y1025521D01*
X519030D01*
X518845Y1026121D01*
Y1026296D01*
X520245D01*
Y1026121D01*
G37*
G36*
G01D02*
X520060Y1025521D01*
X519030D01*
X518845Y1026121D01*
Y1026296D01*
X520245D01*
Y1026121D01*
G37*
G36*
G01X526195Y1043739D02*
X526380Y1044339D01*
X527410D01*
X527595Y1043739D01*
Y1043565D01*
X526195D01*
Y1043739D01*
G37*
G36*
G01X522495D02*
X522680Y1044339D01*
X523710D01*
X523895Y1043739D01*
Y1043565D01*
X522495D01*
Y1043739D01*
G37*
G36*
G01X529945Y1043741D02*
X530130Y1044341D01*
X531160D01*
X531345Y1043741D01*
Y1043566D01*
X529945D01*
Y1043741D01*
G37*
G36*
G01X526195Y1043739D02*
X526380Y1044339D01*
X527410D01*
X527595Y1043739D01*
Y1043565D01*
X526195D01*
Y1043739D01*
G37*
G36*
G01X522495D02*
X522680Y1044339D01*
X523710D01*
X523895Y1043739D01*
Y1043565D01*
X522495D01*
Y1043739D01*
G37*
G36*
G01X529945Y1043741D02*
X530130Y1044341D01*
X531160D01*
X531345Y1043741D01*
Y1043566D01*
X529945D01*
Y1043741D01*
G37*
G36*
G01X518795Y1043739D02*
X518980Y1044339D01*
X520010D01*
X520195Y1043739D01*
Y1043565D01*
X518795D01*
Y1043739D01*
G37*
G36*
G01D02*
X518980Y1044339D01*
X520010D01*
X520195Y1043739D01*
Y1043565D01*
X518795D01*
Y1043739D01*
G37*
G36*
G01X528028Y1040537D02*
X528213Y1041137D01*
X529243D01*
X529428Y1040537D01*
Y1040362D01*
X528028D01*
Y1040537D01*
G37*
G36*
G01X524375Y1040535D02*
X524560Y1041135D01*
X525590D01*
X525775Y1040535D01*
Y1040360D01*
X524375D01*
Y1040535D01*
G37*
G36*
G01X520675D02*
X520860Y1041135D01*
X521890D01*
X522075Y1040535D01*
Y1040360D01*
X520675D01*
Y1040535D01*
G37*
G36*
G01X531761D02*
X531946Y1041135D01*
X532976D01*
X533161Y1040535D01*
Y1040361D01*
X531761D01*
Y1040535D01*
G37*
G36*
G01X528028Y1040537D02*
X528213Y1041137D01*
X529243D01*
X529428Y1040537D01*
Y1040362D01*
X528028D01*
Y1040537D01*
G37*
G36*
G01X524375Y1040535D02*
X524560Y1041135D01*
X525590D01*
X525775Y1040535D01*
Y1040360D01*
X524375D01*
Y1040535D01*
G37*
G36*
G01X520675D02*
X520860Y1041135D01*
X521890D01*
X522075Y1040535D01*
Y1040360D01*
X520675D01*
Y1040535D01*
G37*
G36*
G01X531761D02*
X531946Y1041135D01*
X532976D01*
X533161Y1040535D01*
Y1040361D01*
X531761D01*
Y1040535D01*
G37*
G36*
G01X516975D02*
X517160Y1041135D01*
X518190D01*
X518375Y1040535D01*
Y1040360D01*
X516975D01*
Y1040535D01*
G37*
G36*
G01D02*
X517160Y1041135D01*
X518190D01*
X518375Y1040535D01*
Y1040360D01*
X516975D01*
Y1040535D01*
G37*
G36*
G01X529478Y1042145D02*
X529293Y1041545D01*
X528263D01*
X528078Y1042145D01*
Y1042319D01*
X529478D01*
Y1042145D01*
G37*
G36*
G01X525778D02*
X525593Y1041545D01*
X524563D01*
X524378Y1042145D01*
Y1042319D01*
X525778D01*
Y1042145D01*
G37*
G36*
G01X522078D02*
X521893Y1041545D01*
X520863D01*
X520678Y1042145D01*
Y1042319D01*
X522078D01*
Y1042145D01*
G37*
G36*
G01X533128Y1042143D02*
X532943Y1041543D01*
X531913D01*
X531728Y1042143D01*
Y1042318D01*
X533128D01*
Y1042143D01*
G37*
G36*
G01X529478Y1042145D02*
X529293Y1041545D01*
X528263D01*
X528078Y1042145D01*
Y1042319D01*
X529478D01*
Y1042145D01*
G37*
G36*
G01X525778D02*
X525593Y1041545D01*
X524563D01*
X524378Y1042145D01*
Y1042319D01*
X525778D01*
Y1042145D01*
G37*
G36*
G01X522078D02*
X521893Y1041545D01*
X520863D01*
X520678Y1042145D01*
Y1042319D01*
X522078D01*
Y1042145D01*
G37*
G36*
G01X533128Y1042143D02*
X532943Y1041543D01*
X531913D01*
X531728Y1042143D01*
Y1042318D01*
X533128D01*
Y1042143D01*
G37*
G36*
G01X518378Y1042145D02*
X518193Y1041545D01*
X517163D01*
X516978Y1042145D01*
Y1042319D01*
X518378D01*
Y1042145D01*
G37*
G36*
G01D02*
X518193Y1041545D01*
X517163D01*
X516978Y1042145D01*
Y1042319D01*
X518378D01*
Y1042145D01*
G37*
G36*
G01X527645Y1038939D02*
X527460Y1038339D01*
X526430D01*
X526245Y1038939D01*
Y1039114D01*
X527645D01*
Y1038939D01*
G37*
G36*
G01X523898Y1038941D02*
X523713Y1038341D01*
X522683D01*
X522498Y1038941D01*
Y1039115D01*
X523898D01*
Y1038941D01*
G37*
G36*
G01X531335D02*
X531150Y1038341D01*
X530120D01*
X529935Y1038941D01*
Y1039115D01*
X531335D01*
Y1038941D01*
G37*
G36*
G01X527645Y1038939D02*
X527460Y1038339D01*
X526430D01*
X526245Y1038939D01*
Y1039114D01*
X527645D01*
Y1038939D01*
G37*
G36*
G01X523898Y1038941D02*
X523713Y1038341D01*
X522683D01*
X522498Y1038941D01*
Y1039115D01*
X523898D01*
Y1038941D01*
G37*
G36*
G01X531335D02*
X531150Y1038341D01*
X530120D01*
X529935Y1038941D01*
Y1039115D01*
X531335D01*
Y1038941D01*
G37*
G36*
G01X520198D02*
X520013Y1038341D01*
X518983D01*
X518798Y1038941D01*
Y1039115D01*
X520198D01*
Y1038941D01*
G37*
G36*
G01D02*
X520013Y1038341D01*
X518983D01*
X518798Y1038941D01*
Y1039115D01*
X520198D01*
Y1038941D01*
G37*
G36*
G01X526245Y1030923D02*
X526430Y1031523D01*
X527460D01*
X527645Y1030923D01*
Y1030749D01*
X526245D01*
Y1030923D01*
G37*
G36*
G01X522535D02*
X522720Y1031523D01*
X523750D01*
X523935Y1030923D01*
Y1030749D01*
X522535D01*
Y1030923D01*
G37*
G36*
G01X529935D02*
X530120Y1031523D01*
X531150D01*
X531335Y1030923D01*
Y1030748D01*
X529935D01*
Y1030923D01*
G37*
G36*
G01X526245D02*
X526430Y1031523D01*
X527460D01*
X527645Y1030923D01*
Y1030749D01*
X526245D01*
Y1030923D01*
G37*
G36*
G01X522535D02*
X522720Y1031523D01*
X523750D01*
X523935Y1030923D01*
Y1030749D01*
X522535D01*
Y1030923D01*
G37*
G36*
G01X529935D02*
X530120Y1031523D01*
X531150D01*
X531335Y1030923D01*
Y1030748D01*
X529935D01*
Y1030923D01*
G37*
G36*
G01X518835D02*
X519020Y1031523D01*
X520050D01*
X520235Y1030923D01*
Y1030748D01*
X518835D01*
Y1030923D01*
G37*
G36*
G01D02*
X519020Y1031523D01*
X520050D01*
X520235Y1030923D01*
Y1030748D01*
X518835D01*
Y1030923D01*
G37*
G36*
G01X531728Y1046945D02*
X531913Y1047545D01*
X532943D01*
X533128Y1046945D01*
Y1046771D01*
X531728D01*
Y1046945D01*
G37*
G36*
G01X528075Y1046943D02*
X528260Y1047543D01*
X529290D01*
X529475Y1046943D01*
Y1046769D01*
X528075D01*
Y1046943D01*
G37*
G36*
G01X524375D02*
X524560Y1047543D01*
X525590D01*
X525775Y1046943D01*
Y1046769D01*
X524375D01*
Y1046943D01*
G37*
G36*
G01X520675D02*
X520860Y1047543D01*
X521890D01*
X522075Y1046943D01*
Y1046769D01*
X520675D01*
Y1046943D01*
G37*
G36*
G01X531728Y1046945D02*
X531913Y1047545D01*
X532943D01*
X533128Y1046945D01*
Y1046771D01*
X531728D01*
Y1046945D01*
G37*
G36*
G01X528075Y1046943D02*
X528260Y1047543D01*
X529290D01*
X529475Y1046943D01*
Y1046769D01*
X528075D01*
Y1046943D01*
G37*
G36*
G01X524375D02*
X524560Y1047543D01*
X525590D01*
X525775Y1046943D01*
Y1046769D01*
X524375D01*
Y1046943D01*
G37*
G36*
G01X520675D02*
X520860Y1047543D01*
X521890D01*
X522075Y1046943D01*
Y1046769D01*
X520675D01*
Y1046943D01*
G37*
G36*
G01X516975D02*
X517160Y1047543D01*
X518190D01*
X518375Y1046943D01*
Y1046769D01*
X516975D01*
Y1046943D01*
G37*
G36*
G01D02*
X517160Y1047543D01*
X518190D01*
X518375Y1046943D01*
Y1046769D01*
X516975D01*
Y1046943D01*
G37*
G36*
G01X523898Y1045349D02*
X523713Y1044749D01*
X522683D01*
X522498Y1045349D01*
Y1045524D01*
X523898D01*
Y1045349D01*
G37*
G36*
G01X527598D02*
X527413Y1044749D01*
X526383D01*
X526198Y1045349D01*
Y1045524D01*
X527598D01*
Y1045349D01*
G37*
G36*
G01X531298D02*
X531113Y1044749D01*
X530083D01*
X529898Y1045349D01*
Y1045524D01*
X531298D01*
Y1045349D01*
G37*
G36*
G01X523898D02*
X523713Y1044749D01*
X522683D01*
X522498Y1045349D01*
Y1045524D01*
X523898D01*
Y1045349D01*
G37*
G36*
G01X527598D02*
X527413Y1044749D01*
X526383D01*
X526198Y1045349D01*
Y1045524D01*
X527598D01*
Y1045349D01*
G37*
G36*
G01X531298D02*
X531113Y1044749D01*
X530083D01*
X529898Y1045349D01*
Y1045524D01*
X531298D01*
Y1045349D01*
G37*
G36*
G01X520198D02*
X520013Y1044749D01*
X518983D01*
X518798Y1045349D01*
Y1045524D01*
X520198D01*
Y1045349D01*
G37*
G36*
G01D02*
X520013Y1044749D01*
X518983D01*
X518798Y1045349D01*
Y1045524D01*
X520198D01*
Y1045349D01*
G37*
G36*
G01X522038Y1035735D02*
X521853Y1035135D01*
X520823D01*
X520638Y1035735D01*
Y1035910D01*
X522038D01*
Y1035735D01*
G37*
G36*
G01X525728D02*
X525543Y1035135D01*
X524513D01*
X524328Y1035735D01*
Y1035909D01*
X525728D01*
Y1035735D01*
G37*
G36*
G01X529428D02*
X529243Y1035135D01*
X528213D01*
X528028Y1035735D01*
Y1035909D01*
X529428D01*
Y1035735D01*
G37*
G36*
G01X533161D02*
X532976Y1035135D01*
X531946D01*
X531761Y1035735D01*
Y1035910D01*
X533161D01*
Y1035735D01*
G37*
G36*
G01X522038D02*
X521853Y1035135D01*
X520823D01*
X520638Y1035735D01*
Y1035910D01*
X522038D01*
Y1035735D01*
G37*
G36*
G01X525728D02*
X525543Y1035135D01*
X524513D01*
X524328Y1035735D01*
Y1035909D01*
X525728D01*
Y1035735D01*
G37*
G36*
G01X529428D02*
X529243Y1035135D01*
X528213D01*
X528028Y1035735D01*
Y1035909D01*
X529428D01*
Y1035735D01*
G37*
G36*
G01X533161D02*
X532976Y1035135D01*
X531946D01*
X531761Y1035735D01*
Y1035910D01*
X533161D01*
Y1035735D01*
G37*
G36*
G01X518338D02*
X518153Y1035135D01*
X517123D01*
X516938Y1035735D01*
Y1035909D01*
X518338D01*
Y1035735D01*
G37*
G36*
G01D02*
X518153Y1035135D01*
X517123D01*
X516938Y1035735D01*
Y1035909D01*
X518338D01*
Y1035735D01*
G37*
G36*
G01X528028Y1034127D02*
X528213Y1034727D01*
X529243D01*
X529428Y1034127D01*
Y1033953D01*
X528028D01*
Y1034127D01*
G37*
G36*
G01X524328D02*
X524513Y1034727D01*
X525543D01*
X525728Y1034127D01*
Y1033953D01*
X524328D01*
Y1034127D01*
G37*
G36*
G01X520685D02*
X520870Y1034727D01*
X521900D01*
X522085Y1034127D01*
Y1033952D01*
X520685D01*
Y1034127D01*
G37*
G36*
G01X531761D02*
X531946Y1034727D01*
X532976D01*
X533161Y1034127D01*
Y1033952D01*
X531761D01*
Y1034127D01*
G37*
G36*
G01X528028D02*
X528213Y1034727D01*
X529243D01*
X529428Y1034127D01*
Y1033953D01*
X528028D01*
Y1034127D01*
G37*
G36*
G01X524328D02*
X524513Y1034727D01*
X525543D01*
X525728Y1034127D01*
Y1033953D01*
X524328D01*
Y1034127D01*
G37*
G36*
G01X520685D02*
X520870Y1034727D01*
X521900D01*
X522085Y1034127D01*
Y1033952D01*
X520685D01*
Y1034127D01*
G37*
G36*
G01X531761D02*
X531946Y1034727D01*
X532976D01*
X533161Y1034127D01*
Y1033952D01*
X531761D01*
Y1034127D01*
G37*
G36*
G01X516938D02*
X517123Y1034727D01*
X518153D01*
X518338Y1034127D01*
Y1033953D01*
X516938D01*
Y1034127D01*
G37*
G36*
G01D02*
X517123Y1034727D01*
X518153D01*
X518338Y1034127D01*
Y1033953D01*
X516938D01*
Y1034127D01*
G37*
G36*
G01X522545Y1037333D02*
X522730Y1037933D01*
X523760D01*
X523945Y1037333D01*
Y1037158D01*
X522545D01*
Y1037333D01*
G37*
G36*
G01X526245D02*
X526430Y1037933D01*
X527460D01*
X527645Y1037333D01*
Y1037158D01*
X526245D01*
Y1037333D01*
G37*
G36*
G01X529935Y1037331D02*
X530120Y1037931D01*
X531150D01*
X531335Y1037331D01*
Y1037157D01*
X529935D01*
Y1037331D01*
G37*
G36*
G01X522545Y1037333D02*
X522730Y1037933D01*
X523760D01*
X523945Y1037333D01*
Y1037158D01*
X522545D01*
Y1037333D01*
G37*
G36*
G01X526245D02*
X526430Y1037933D01*
X527460D01*
X527645Y1037333D01*
Y1037158D01*
X526245D01*
Y1037333D01*
G37*
G36*
G01X529935Y1037331D02*
X530120Y1037931D01*
X531150D01*
X531335Y1037331D01*
Y1037157D01*
X529935D01*
Y1037331D01*
G37*
G36*
G01X518812D02*
X518997Y1037931D01*
X520027D01*
X520212Y1037331D01*
Y1037157D01*
X518812D01*
Y1037331D01*
G37*
G36*
G01D02*
X518997Y1037931D01*
X520027D01*
X520212Y1037331D01*
Y1037157D01*
X518812D01*
Y1037331D01*
G37*
G36*
G01X523935Y1032531D02*
X523750Y1031931D01*
X522720D01*
X522535Y1032531D01*
Y1032705D01*
X523935D01*
Y1032531D01*
G37*
G36*
G01X527645D02*
X527460Y1031931D01*
X526430D01*
X526245Y1032531D01*
Y1032705D01*
X527645D01*
Y1032531D01*
G37*
G36*
G01X531335D02*
X531150Y1031931D01*
X530120D01*
X529935Y1032531D01*
Y1032706D01*
X531335D01*
Y1032531D01*
G37*
G36*
G01X523935D02*
X523750Y1031931D01*
X522720D01*
X522535Y1032531D01*
Y1032705D01*
X523935D01*
Y1032531D01*
G37*
G36*
G01X527645D02*
X527460Y1031931D01*
X526430D01*
X526245Y1032531D01*
Y1032705D01*
X527645D01*
Y1032531D01*
G37*
G36*
G01X531335D02*
X531150Y1031931D01*
X530120D01*
X529935Y1032531D01*
Y1032706D01*
X531335D01*
Y1032531D01*
G37*
G36*
G01X520188D02*
X520003Y1031931D01*
X518973D01*
X518788Y1032531D01*
Y1032706D01*
X520188D01*
Y1032531D01*
G37*
G36*
G01D02*
X520003Y1031931D01*
X518973D01*
X518788Y1032531D01*
Y1032706D01*
X520188D01*
Y1032531D01*
G37*
G36*
G01X526235Y1062967D02*
X526420Y1063567D01*
X527450D01*
X527635Y1062967D01*
Y1062792D01*
X526235D01*
Y1062967D01*
G37*
G36*
G01X522488Y1062965D02*
X522673Y1063565D01*
X523703D01*
X523888Y1062965D01*
Y1062791D01*
X522488D01*
Y1062965D01*
G37*
G36*
G01X529945Y1062967D02*
X530130Y1063567D01*
X531160D01*
X531345Y1062967D01*
Y1062792D01*
X529945D01*
Y1062967D01*
G37*
G36*
G01X526235D02*
X526420Y1063567D01*
X527450D01*
X527635Y1062967D01*
Y1062792D01*
X526235D01*
Y1062967D01*
G37*
G36*
G01X522488Y1062965D02*
X522673Y1063565D01*
X523703D01*
X523888Y1062965D01*
Y1062791D01*
X522488D01*
Y1062965D01*
G37*
G36*
G01X529945Y1062967D02*
X530130Y1063567D01*
X531160D01*
X531345Y1062967D01*
Y1062792D01*
X529945D01*
Y1062967D01*
G37*
G36*
G01X518845D02*
X519030Y1063567D01*
X520060D01*
X520245Y1062967D01*
Y1062792D01*
X518845D01*
Y1062967D01*
G37*
G36*
G01D02*
X519030Y1063567D01*
X520060D01*
X520245Y1062967D01*
Y1062792D01*
X518845D01*
Y1062967D01*
G37*
G36*
G01X528028Y1059761D02*
X528213Y1060361D01*
X529243D01*
X529428Y1059761D01*
Y1059587D01*
X528028D01*
Y1059761D01*
G37*
G36*
G01X524338D02*
X524523Y1060361D01*
X525553D01*
X525738Y1059761D01*
Y1059586D01*
X524338D01*
Y1059761D01*
G37*
G36*
G01X520675D02*
X520860Y1060361D01*
X521890D01*
X522075Y1059761D01*
Y1059586D01*
X520675D01*
Y1059761D01*
G37*
G36*
G01X531728D02*
X531913Y1060361D01*
X532943D01*
X533128Y1059761D01*
Y1059587D01*
X531728D01*
Y1059761D01*
G37*
G36*
G01X528028D02*
X528213Y1060361D01*
X529243D01*
X529428Y1059761D01*
Y1059587D01*
X528028D01*
Y1059761D01*
G37*
G36*
G01X524338D02*
X524523Y1060361D01*
X525553D01*
X525738Y1059761D01*
Y1059586D01*
X524338D01*
Y1059761D01*
G37*
G36*
G01X520675D02*
X520860Y1060361D01*
X521890D01*
X522075Y1059761D01*
Y1059586D01*
X520675D01*
Y1059761D01*
G37*
G36*
G01X531728D02*
X531913Y1060361D01*
X532943D01*
X533128Y1059761D01*
Y1059587D01*
X531728D01*
Y1059761D01*
G37*
G36*
G01X516975D02*
X517160Y1060361D01*
X518190D01*
X518375Y1059761D01*
Y1059586D01*
X516975D01*
Y1059761D01*
G37*
G36*
G01D02*
X517160Y1060361D01*
X518190D01*
X518375Y1059761D01*
Y1059586D01*
X516975D01*
Y1059761D01*
G37*
G36*
G01X522038Y1061369D02*
X521853Y1060769D01*
X520823D01*
X520638Y1061369D01*
Y1061543D01*
X522038D01*
Y1061369D01*
G37*
G36*
G01X525785D02*
X525600Y1060769D01*
X524570D01*
X524385Y1061369D01*
Y1061544D01*
X525785D01*
Y1061369D01*
G37*
G36*
G01X529428D02*
X529243Y1060769D01*
X528213D01*
X528028Y1061369D01*
Y1061543D01*
X529428D01*
Y1061369D01*
G37*
G36*
G01X533128D02*
X532943Y1060769D01*
X531913D01*
X531728Y1061369D01*
Y1061543D01*
X533128D01*
Y1061369D01*
G37*
G36*
G01X522038D02*
X521853Y1060769D01*
X520823D01*
X520638Y1061369D01*
Y1061543D01*
X522038D01*
Y1061369D01*
G37*
G36*
G01X525785D02*
X525600Y1060769D01*
X524570D01*
X524385Y1061369D01*
Y1061544D01*
X525785D01*
Y1061369D01*
G37*
G36*
G01X529428D02*
X529243Y1060769D01*
X528213D01*
X528028Y1061369D01*
Y1061543D01*
X529428D01*
Y1061369D01*
G37*
G36*
G01X533128D02*
X532943Y1060769D01*
X531913D01*
X531728Y1061369D01*
Y1061543D01*
X533128D01*
Y1061369D01*
G37*
G36*
G01X518328D02*
X518143Y1060769D01*
X517113D01*
X516928Y1061369D01*
Y1061543D01*
X518328D01*
Y1061369D01*
G37*
G36*
G01D02*
X518143Y1060769D01*
X517113D01*
X516928Y1061369D01*
Y1061543D01*
X518328D01*
Y1061369D01*
G37*
G36*
G01X523912Y1058165D02*
X523727Y1057565D01*
X522697D01*
X522512Y1058165D01*
Y1058340D01*
X523912D01*
Y1058165D01*
G37*
G36*
G01X527645D02*
X527460Y1057565D01*
X526430D01*
X526245Y1058165D01*
Y1058339D01*
X527645D01*
Y1058165D01*
G37*
G36*
G01X531345D02*
X531160Y1057565D01*
X530130D01*
X529945Y1058165D01*
Y1058339D01*
X531345D01*
Y1058165D01*
G37*
G36*
G01X523912D02*
X523727Y1057565D01*
X522697D01*
X522512Y1058165D01*
Y1058340D01*
X523912D01*
Y1058165D01*
G37*
G36*
G01X527645D02*
X527460Y1057565D01*
X526430D01*
X526245Y1058165D01*
Y1058339D01*
X527645D01*
Y1058165D01*
G37*
G36*
G01X531345D02*
X531160Y1057565D01*
X530130D01*
X529945Y1058165D01*
Y1058339D01*
X531345D01*
Y1058165D01*
G37*
G36*
G01X520245D02*
X520060Y1057565D01*
X519030D01*
X518845Y1058165D01*
Y1058339D01*
X520245D01*
Y1058165D01*
G37*
G36*
G01D02*
X520060Y1057565D01*
X519030D01*
X518845Y1058165D01*
Y1058339D01*
X520245D01*
Y1058165D01*
G37*
G36*
G01X526198Y1050149D02*
X526383Y1050749D01*
X527413D01*
X527598Y1050149D01*
Y1049974D01*
X526198D01*
Y1050149D01*
G37*
G36*
G01X522498D02*
X522683Y1050749D01*
X523713D01*
X523898Y1050149D01*
Y1049974D01*
X522498D01*
Y1050149D01*
G37*
G36*
G01X529898D02*
X530083Y1050749D01*
X531113D01*
X531298Y1050149D01*
Y1049974D01*
X529898D01*
Y1050149D01*
G37*
G36*
G01X526198D02*
X526383Y1050749D01*
X527413D01*
X527598Y1050149D01*
Y1049974D01*
X526198D01*
Y1050149D01*
G37*
G36*
G01X522498D02*
X522683Y1050749D01*
X523713D01*
X523898Y1050149D01*
Y1049974D01*
X522498D01*
Y1050149D01*
G37*
G36*
G01X529898D02*
X530083Y1050749D01*
X531113D01*
X531298Y1050149D01*
Y1049974D01*
X529898D01*
Y1050149D01*
G37*
G36*
G01X518798D02*
X518983Y1050749D01*
X520013D01*
X520198Y1050149D01*
Y1049974D01*
X518798D01*
Y1050149D01*
G37*
G36*
G01D02*
X518983Y1050749D01*
X520013D01*
X520198Y1050149D01*
Y1049974D01*
X518798D01*
Y1050149D01*
G37*
G36*
G01X529475Y1048553D02*
X529290Y1047953D01*
X528260D01*
X528075Y1048553D01*
Y1048727D01*
X529475D01*
Y1048553D01*
G37*
G36*
G01X525775D02*
X525590Y1047953D01*
X524560D01*
X524375Y1048553D01*
Y1048727D01*
X525775D01*
Y1048553D01*
G37*
G36*
G01X522075D02*
X521890Y1047953D01*
X520860D01*
X520675Y1048553D01*
Y1048727D01*
X522075D01*
Y1048553D01*
G37*
G36*
G01X533128Y1048551D02*
X532943Y1047951D01*
X531913D01*
X531728Y1048551D01*
Y1048726D01*
X533128D01*
Y1048551D01*
G37*
G36*
G01X529475Y1048553D02*
X529290Y1047953D01*
X528260D01*
X528075Y1048553D01*
Y1048727D01*
X529475D01*
Y1048553D01*
G37*
G36*
G01X525775D02*
X525590Y1047953D01*
X524560D01*
X524375Y1048553D01*
Y1048727D01*
X525775D01*
Y1048553D01*
G37*
G36*
G01X522075D02*
X521890Y1047953D01*
X520860D01*
X520675Y1048553D01*
Y1048727D01*
X522075D01*
Y1048553D01*
G37*
G36*
G01X533128Y1048551D02*
X532943Y1047951D01*
X531913D01*
X531728Y1048551D01*
Y1048726D01*
X533128D01*
Y1048551D01*
G37*
G36*
G01X518375Y1048553D02*
X518190Y1047953D01*
X517160D01*
X516975Y1048553D01*
Y1048727D01*
X518375D01*
Y1048553D01*
G37*
G36*
G01D02*
X518190Y1047953D01*
X517160D01*
X516975Y1048553D01*
Y1048727D01*
X518375D01*
Y1048553D01*
G37*
G36*
G01X522038Y1054961D02*
X521853Y1054361D01*
X520823D01*
X520638Y1054961D01*
Y1055136D01*
X522038D01*
Y1054961D01*
G37*
G36*
G01X525728D02*
X525543Y1054361D01*
X524513D01*
X524328Y1054961D01*
Y1055135D01*
X525728D01*
Y1054961D01*
G37*
G36*
G01X529428D02*
X529243Y1054361D01*
X528213D01*
X528028Y1054961D01*
Y1055135D01*
X529428D01*
Y1054961D01*
G37*
G36*
G01X533128D02*
X532943Y1054361D01*
X531913D01*
X531728Y1054961D01*
Y1055135D01*
X533128D01*
Y1054961D01*
G37*
G36*
G01X522038D02*
X521853Y1054361D01*
X520823D01*
X520638Y1054961D01*
Y1055136D01*
X522038D01*
Y1054961D01*
G37*
G36*
G01X525728D02*
X525543Y1054361D01*
X524513D01*
X524328Y1054961D01*
Y1055135D01*
X525728D01*
Y1054961D01*
G37*
G36*
G01X529428D02*
X529243Y1054361D01*
X528213D01*
X528028Y1054961D01*
Y1055135D01*
X529428D01*
Y1054961D01*
G37*
G36*
G01X533128D02*
X532943Y1054361D01*
X531913D01*
X531728Y1054961D01*
Y1055135D01*
X533128D01*
Y1054961D01*
G37*
G36*
G01X518338D02*
X518153Y1054361D01*
X517123D01*
X516938Y1054961D01*
Y1055135D01*
X518338D01*
Y1054961D01*
G37*
G36*
G01D02*
X518153Y1054361D01*
X517123D01*
X516938Y1054961D01*
Y1055135D01*
X518338D01*
Y1054961D01*
G37*
G36*
G01X520685Y1053353D02*
X520870Y1053953D01*
X521900D01*
X522085Y1053353D01*
Y1053178D01*
X520685D01*
Y1053353D01*
G37*
G36*
G01X524328D02*
X524513Y1053953D01*
X525543D01*
X525728Y1053353D01*
Y1053179D01*
X524328D01*
Y1053353D01*
G37*
G36*
G01X528028D02*
X528213Y1053953D01*
X529243D01*
X529428Y1053353D01*
Y1053179D01*
X528028D01*
Y1053353D01*
G37*
G36*
G01X531728D02*
X531913Y1053953D01*
X532943D01*
X533128Y1053353D01*
Y1053179D01*
X531728D01*
Y1053353D01*
G37*
G36*
G01X520685D02*
X520870Y1053953D01*
X521900D01*
X522085Y1053353D01*
Y1053178D01*
X520685D01*
Y1053353D01*
G37*
G36*
G01X524328D02*
X524513Y1053953D01*
X525543D01*
X525728Y1053353D01*
Y1053179D01*
X524328D01*
Y1053353D01*
G37*
G36*
G01X528028D02*
X528213Y1053953D01*
X529243D01*
X529428Y1053353D01*
Y1053179D01*
X528028D01*
Y1053353D01*
G37*
G36*
G01X531728D02*
X531913Y1053953D01*
X532943D01*
X533128Y1053353D01*
Y1053179D01*
X531728D01*
Y1053353D01*
G37*
G36*
G01X516938D02*
X517123Y1053953D01*
X518153D01*
X518338Y1053353D01*
Y1053179D01*
X516938D01*
Y1053353D01*
G37*
G36*
G01D02*
X517123Y1053953D01*
X518153D01*
X518338Y1053353D01*
Y1053179D01*
X516938D01*
Y1053353D01*
G37*
G36*
G01X522545Y1056557D02*
X522730Y1057157D01*
X523760D01*
X523945Y1056557D01*
Y1056383D01*
X522545D01*
Y1056557D01*
G37*
G36*
G01X526245D02*
X526430Y1057157D01*
X527460D01*
X527645Y1056557D01*
Y1056383D01*
X526245D01*
Y1056557D01*
G37*
G36*
G01X529945D02*
X530130Y1057157D01*
X531160D01*
X531345Y1056557D01*
Y1056383D01*
X529945D01*
Y1056557D01*
G37*
G36*
G01X522545D02*
X522730Y1057157D01*
X523760D01*
X523945Y1056557D01*
Y1056383D01*
X522545D01*
Y1056557D01*
G37*
G36*
G01X526245D02*
X526430Y1057157D01*
X527460D01*
X527645Y1056557D01*
Y1056383D01*
X526245D01*
Y1056557D01*
G37*
G36*
G01X529945D02*
X530130Y1057157D01*
X531160D01*
X531345Y1056557D01*
Y1056383D01*
X529945D01*
Y1056557D01*
G37*
G36*
G01X518812D02*
X518997Y1057157D01*
X520027D01*
X520212Y1056557D01*
Y1056382D01*
X518812D01*
Y1056557D01*
G37*
G36*
G01D02*
X518997Y1057157D01*
X520027D01*
X520212Y1056557D01*
Y1056382D01*
X518812D01*
Y1056557D01*
G37*
G36*
G01X523935Y1051757D02*
X523750Y1051157D01*
X522720D01*
X522535Y1051757D01*
Y1051931D01*
X523935D01*
Y1051757D01*
G37*
G36*
G01X527645D02*
X527460Y1051157D01*
X526430D01*
X526245Y1051757D01*
Y1051931D01*
X527645D01*
Y1051757D01*
G37*
G36*
G01X531345Y1051755D02*
X531160Y1051155D01*
X530130D01*
X529945Y1051755D01*
Y1051930D01*
X531345D01*
Y1051755D01*
G37*
G36*
G01X523935Y1051757D02*
X523750Y1051157D01*
X522720D01*
X522535Y1051757D01*
Y1051931D01*
X523935D01*
Y1051757D01*
G37*
G36*
G01X527645D02*
X527460Y1051157D01*
X526430D01*
X526245Y1051757D01*
Y1051931D01*
X527645D01*
Y1051757D01*
G37*
G36*
G01X531345Y1051755D02*
X531160Y1051155D01*
X530130D01*
X529945Y1051755D01*
Y1051930D01*
X531345D01*
Y1051755D01*
G37*
G36*
G01X520188Y1051757D02*
X520003Y1051157D01*
X518973D01*
X518788Y1051757D01*
Y1051932D01*
X520188D01*
Y1051757D01*
G37*
G36*
G01D02*
X520003Y1051157D01*
X518973D01*
X518788Y1051757D01*
Y1051932D01*
X520188D01*
Y1051757D01*
G37*
G36*
G01X527645Y1077391D02*
X527460Y1076791D01*
X526430D01*
X526245Y1077391D01*
Y1077565D01*
X527645D01*
Y1077391D01*
G37*
G36*
G01X523912D02*
X523727Y1076791D01*
X522697D01*
X522512Y1077391D01*
Y1077566D01*
X523912D01*
Y1077391D01*
G37*
G36*
G01X531345D02*
X531160Y1076791D01*
X530130D01*
X529945Y1077391D01*
Y1077565D01*
X531345D01*
Y1077391D01*
G37*
G36*
G01X527645D02*
X527460Y1076791D01*
X526430D01*
X526245Y1077391D01*
Y1077565D01*
X527645D01*
Y1077391D01*
G37*
G36*
G01X523912D02*
X523727Y1076791D01*
X522697D01*
X522512Y1077391D01*
Y1077566D01*
X523912D01*
Y1077391D01*
G37*
G36*
G01X531345D02*
X531160Y1076791D01*
X530130D01*
X529945Y1077391D01*
Y1077565D01*
X531345D01*
Y1077391D01*
G37*
G36*
G01X520245D02*
X520060Y1076791D01*
X519030D01*
X518845Y1077391D01*
Y1077565D01*
X520245D01*
Y1077391D01*
G37*
G36*
G01D02*
X520060Y1076791D01*
X519030D01*
X518845Y1077391D01*
Y1077565D01*
X520245D01*
Y1077391D01*
G37*
G36*
G01X526198Y1069375D02*
X526383Y1069975D01*
X527413D01*
X527598Y1069375D01*
Y1069200D01*
X526198D01*
Y1069375D01*
G37*
G36*
G01X522498D02*
X522683Y1069975D01*
X523713D01*
X523898Y1069375D01*
Y1069200D01*
X522498D01*
Y1069375D01*
G37*
G36*
G01X529898D02*
X530083Y1069975D01*
X531113D01*
X531298Y1069375D01*
Y1069200D01*
X529898D01*
Y1069375D01*
G37*
G36*
G01X526198D02*
X526383Y1069975D01*
X527413D01*
X527598Y1069375D01*
Y1069200D01*
X526198D01*
Y1069375D01*
G37*
G36*
G01X522498D02*
X522683Y1069975D01*
X523713D01*
X523898Y1069375D01*
Y1069200D01*
X522498D01*
Y1069375D01*
G37*
G36*
G01X529898D02*
X530083Y1069975D01*
X531113D01*
X531298Y1069375D01*
Y1069200D01*
X529898D01*
Y1069375D01*
G37*
G36*
G01X518798D02*
X518983Y1069975D01*
X520013D01*
X520198Y1069375D01*
Y1069200D01*
X518798D01*
Y1069375D01*
G37*
G36*
G01D02*
X518983Y1069975D01*
X520013D01*
X520198Y1069375D01*
Y1069200D01*
X518798D01*
Y1069375D01*
G37*
G36*
G01X528028Y1066171D02*
X528213Y1066771D01*
X529243D01*
X529428Y1066171D01*
Y1065996D01*
X528028D01*
Y1066171D01*
G37*
G36*
G01X524361Y1066169D02*
X524546Y1066769D01*
X525576D01*
X525761Y1066169D01*
Y1065995D01*
X524361D01*
Y1066169D01*
G37*
G36*
G01X520628Y1066171D02*
X520813Y1066771D01*
X521843D01*
X522028Y1066171D01*
Y1065996D01*
X520628D01*
Y1066171D01*
G37*
G36*
G01X531728D02*
X531913Y1066771D01*
X532943D01*
X533128Y1066171D01*
Y1065996D01*
X531728D01*
Y1066171D01*
G37*
G36*
G01X528028D02*
X528213Y1066771D01*
X529243D01*
X529428Y1066171D01*
Y1065996D01*
X528028D01*
Y1066171D01*
G37*
G36*
G01X524361Y1066169D02*
X524546Y1066769D01*
X525576D01*
X525761Y1066169D01*
Y1065995D01*
X524361D01*
Y1066169D01*
G37*
G36*
G01X520628Y1066171D02*
X520813Y1066771D01*
X521843D01*
X522028Y1066171D01*
Y1065996D01*
X520628D01*
Y1066171D01*
G37*
G36*
G01X531728D02*
X531913Y1066771D01*
X532943D01*
X533128Y1066171D01*
Y1065996D01*
X531728D01*
Y1066171D01*
G37*
G36*
G01X516928D02*
X517113Y1066771D01*
X518143D01*
X518328Y1066171D01*
Y1065996D01*
X516928D01*
Y1066171D01*
G37*
G36*
G01D02*
X517113Y1066771D01*
X518143D01*
X518328Y1066171D01*
Y1065996D01*
X516928D01*
Y1066171D01*
G37*
G36*
G01X522075Y1067779D02*
X521890Y1067179D01*
X520860D01*
X520675Y1067779D01*
Y1067953D01*
X522075D01*
Y1067779D01*
G37*
G36*
G01X525775D02*
X525590Y1067179D01*
X524560D01*
X524375Y1067779D01*
Y1067953D01*
X525775D01*
Y1067779D01*
G37*
G36*
G01X529475D02*
X529290Y1067179D01*
X528260D01*
X528075Y1067779D01*
Y1067953D01*
X529475D01*
Y1067779D01*
G37*
G36*
G01X533170D02*
X532985Y1067179D01*
X531955D01*
X531770Y1067779D01*
Y1067954D01*
X533170D01*
Y1067779D01*
G37*
G36*
G01X522075D02*
X521890Y1067179D01*
X520860D01*
X520675Y1067779D01*
Y1067953D01*
X522075D01*
Y1067779D01*
G37*
G36*
G01X525775D02*
X525590Y1067179D01*
X524560D01*
X524375Y1067779D01*
Y1067953D01*
X525775D01*
Y1067779D01*
G37*
G36*
G01X529475D02*
X529290Y1067179D01*
X528260D01*
X528075Y1067779D01*
Y1067953D01*
X529475D01*
Y1067779D01*
G37*
G36*
G01X533170D02*
X532985Y1067179D01*
X531955D01*
X531770Y1067779D01*
Y1067954D01*
X533170D01*
Y1067779D01*
G37*
G36*
G01X518375D02*
X518190Y1067179D01*
X517160D01*
X516975Y1067779D01*
Y1067953D01*
X518375D01*
Y1067779D01*
G37*
G36*
G01D02*
X518190Y1067179D01*
X517160D01*
X516975Y1067779D01*
Y1067953D01*
X518375D01*
Y1067779D01*
G37*
G36*
G01X523935Y1064575D02*
X523750Y1063975D01*
X522720D01*
X522535Y1064575D01*
Y1064749D01*
X523935D01*
Y1064575D01*
G37*
G36*
G01X527635Y1064573D02*
X527450Y1063973D01*
X526420D01*
X526235Y1064573D01*
Y1064748D01*
X527635D01*
Y1064573D01*
G37*
G36*
G01X531345D02*
X531160Y1063973D01*
X530130D01*
X529945Y1064573D01*
Y1064748D01*
X531345D01*
Y1064573D01*
G37*
G36*
G01X523935Y1064575D02*
X523750Y1063975D01*
X522720D01*
X522535Y1064575D01*
Y1064749D01*
X523935D01*
Y1064575D01*
G37*
G36*
G01X527635Y1064573D02*
X527450Y1063973D01*
X526420D01*
X526235Y1064573D01*
Y1064748D01*
X527635D01*
Y1064573D01*
G37*
G36*
G01X531345D02*
X531160Y1063973D01*
X530130D01*
X529945Y1064573D01*
Y1064748D01*
X531345D01*
Y1064573D01*
G37*
G36*
G01X520245D02*
X520060Y1063973D01*
X519030D01*
X518845Y1064573D01*
Y1064748D01*
X520245D01*
Y1064573D01*
G37*
G36*
G01D02*
X520060Y1063973D01*
X519030D01*
X518845Y1064573D01*
Y1064748D01*
X520245D01*
Y1064573D01*
G37*
G36*
G01X528028Y1078987D02*
X528213Y1079587D01*
X529243D01*
X529428Y1078987D01*
Y1078813D01*
X528028D01*
Y1078987D01*
G37*
G36*
G01X524338D02*
X524523Y1079587D01*
X525553D01*
X525738Y1078987D01*
Y1078812D01*
X524338D01*
Y1078987D01*
G37*
G36*
G01X520638D02*
X520823Y1079587D01*
X521853D01*
X522038Y1078987D01*
Y1078813D01*
X520638D01*
Y1078987D01*
G37*
G36*
G01X531728D02*
X531913Y1079587D01*
X532943D01*
X533128Y1078987D01*
Y1078813D01*
X531728D01*
Y1078987D01*
G37*
G36*
G01X528028D02*
X528213Y1079587D01*
X529243D01*
X529428Y1078987D01*
Y1078813D01*
X528028D01*
Y1078987D01*
G37*
G36*
G01X524338D02*
X524523Y1079587D01*
X525553D01*
X525738Y1078987D01*
Y1078812D01*
X524338D01*
Y1078987D01*
G37*
G36*
G01X520638D02*
X520823Y1079587D01*
X521853D01*
X522038Y1078987D01*
Y1078813D01*
X520638D01*
Y1078987D01*
G37*
G36*
G01X531728D02*
X531913Y1079587D01*
X532943D01*
X533128Y1078987D01*
Y1078813D01*
X531728D01*
Y1078987D01*
G37*
G36*
G01X516928D02*
X517113Y1079587D01*
X518143D01*
X518328Y1078987D01*
Y1078813D01*
X516928D01*
Y1078987D01*
G37*
G36*
G01D02*
X517113Y1079587D01*
X518143D01*
X518328Y1078987D01*
Y1078813D01*
X516928D01*
Y1078987D01*
G37*
G36*
G01X522038Y1074187D02*
X521853Y1073587D01*
X520823D01*
X520638Y1074187D01*
Y1074362D01*
X522038D01*
Y1074187D01*
G37*
G36*
G01X525728D02*
X525543Y1073587D01*
X524513D01*
X524328Y1074187D01*
Y1074361D01*
X525728D01*
Y1074187D01*
G37*
G36*
G01X529428D02*
X529243Y1073587D01*
X528213D01*
X528028Y1074187D01*
Y1074361D01*
X529428D01*
Y1074187D01*
G37*
G36*
G01X533128D02*
X532943Y1073587D01*
X531913D01*
X531728Y1074187D01*
Y1074361D01*
X533128D01*
Y1074187D01*
G37*
G36*
G01X522038D02*
X521853Y1073587D01*
X520823D01*
X520638Y1074187D01*
Y1074362D01*
X522038D01*
Y1074187D01*
G37*
G36*
G01X525728D02*
X525543Y1073587D01*
X524513D01*
X524328Y1074187D01*
Y1074361D01*
X525728D01*
Y1074187D01*
G37*
G36*
G01X529428D02*
X529243Y1073587D01*
X528213D01*
X528028Y1074187D01*
Y1074361D01*
X529428D01*
Y1074187D01*
G37*
G36*
G01X533128D02*
X532943Y1073587D01*
X531913D01*
X531728Y1074187D01*
Y1074361D01*
X533128D01*
Y1074187D01*
G37*
G36*
G01X518338D02*
X518153Y1073587D01*
X517123D01*
X516938Y1074187D01*
Y1074361D01*
X518338D01*
Y1074187D01*
G37*
G36*
G01D02*
X518153Y1073587D01*
X517123D01*
X516938Y1074187D01*
Y1074361D01*
X518338D01*
Y1074187D01*
G37*
G36*
G01X520685Y1072579D02*
X520870Y1073179D01*
X521900D01*
X522085Y1072579D01*
Y1072404D01*
X520685D01*
Y1072579D01*
G37*
G36*
G01X524328D02*
X524513Y1073179D01*
X525543D01*
X525728Y1072579D01*
Y1072405D01*
X524328D01*
Y1072579D01*
G37*
G36*
G01X528028D02*
X528213Y1073179D01*
X529243D01*
X529428Y1072579D01*
Y1072405D01*
X528028D01*
Y1072579D01*
G37*
G36*
G01X531728D02*
X531913Y1073179D01*
X532943D01*
X533128Y1072579D01*
Y1072405D01*
X531728D01*
Y1072579D01*
G37*
G36*
G01X520685D02*
X520870Y1073179D01*
X521900D01*
X522085Y1072579D01*
Y1072404D01*
X520685D01*
Y1072579D01*
G37*
G36*
G01X524328D02*
X524513Y1073179D01*
X525543D01*
X525728Y1072579D01*
Y1072405D01*
X524328D01*
Y1072579D01*
G37*
G36*
G01X528028D02*
X528213Y1073179D01*
X529243D01*
X529428Y1072579D01*
Y1072405D01*
X528028D01*
Y1072579D01*
G37*
G36*
G01X531728D02*
X531913Y1073179D01*
X532943D01*
X533128Y1072579D01*
Y1072405D01*
X531728D01*
Y1072579D01*
G37*
G36*
G01X516938D02*
X517123Y1073179D01*
X518153D01*
X518338Y1072579D01*
Y1072405D01*
X516938D01*
Y1072579D01*
G37*
G36*
G01D02*
X517123Y1073179D01*
X518153D01*
X518338Y1072579D01*
Y1072405D01*
X516938D01*
Y1072579D01*
G37*
G36*
G01X526245Y1075783D02*
X526430Y1076383D01*
X527460D01*
X527645Y1075783D01*
Y1075609D01*
X526245D01*
Y1075783D01*
G37*
G36*
G01X529945D02*
X530130Y1076383D01*
X531160D01*
X531345Y1075783D01*
Y1075609D01*
X529945D01*
Y1075783D01*
G37*
G36*
G01X522545D02*
X522730Y1076383D01*
X523760D01*
X523945Y1075783D01*
Y1075609D01*
X522545D01*
Y1075783D01*
G37*
G36*
G01X526245D02*
X526430Y1076383D01*
X527460D01*
X527645Y1075783D01*
Y1075609D01*
X526245D01*
Y1075783D01*
G37*
G36*
G01X529945D02*
X530130Y1076383D01*
X531160D01*
X531345Y1075783D01*
Y1075609D01*
X529945D01*
Y1075783D01*
G37*
G36*
G01X522545D02*
X522730Y1076383D01*
X523760D01*
X523945Y1075783D01*
Y1075609D01*
X522545D01*
Y1075783D01*
G37*
G36*
G01X518812D02*
X518997Y1076383D01*
X520027D01*
X520212Y1075783D01*
Y1075608D01*
X518812D01*
Y1075783D01*
G37*
G36*
G01D02*
X518997Y1076383D01*
X520027D01*
X520212Y1075783D01*
Y1075608D01*
X518812D01*
Y1075783D01*
G37*
G36*
G01X523935Y1070981D02*
X523750Y1070381D01*
X522720D01*
X522535Y1070981D01*
Y1071156D01*
X523935D01*
Y1070981D01*
G37*
G36*
G01X527645D02*
X527460Y1070381D01*
X526430D01*
X526245Y1070981D01*
Y1071156D01*
X527645D01*
Y1070981D01*
G37*
G36*
G01X531345D02*
X531160Y1070381D01*
X530130D01*
X529945Y1070981D01*
Y1071156D01*
X531345D01*
Y1070981D01*
G37*
G36*
G01X523935D02*
X523750Y1070381D01*
X522720D01*
X522535Y1070981D01*
Y1071156D01*
X523935D01*
Y1070981D01*
G37*
G36*
G01X527645D02*
X527460Y1070381D01*
X526430D01*
X526245Y1070981D01*
Y1071156D01*
X527645D01*
Y1070981D01*
G37*
G36*
G01X531345D02*
X531160Y1070381D01*
X530130D01*
X529945Y1070981D01*
Y1071156D01*
X531345D01*
Y1070981D01*
G37*
G36*
G01X520188Y1070983D02*
X520003Y1070383D01*
X518973D01*
X518788Y1070983D01*
Y1071157D01*
X520188D01*
Y1070983D01*
G37*
G36*
G01D02*
X520003Y1070383D01*
X518973D01*
X518788Y1070983D01*
Y1071157D01*
X520188D01*
Y1070983D01*
G37*
G36*
G01X529428Y1080595D02*
X529243Y1079995D01*
X528213D01*
X528028Y1080595D01*
Y1080769D01*
X529428D01*
Y1080595D01*
G37*
G36*
G01X525785D02*
X525600Y1079995D01*
X524570D01*
X524385Y1080595D01*
Y1080770D01*
X525785D01*
Y1080595D01*
G37*
G36*
G01X522038D02*
X521853Y1079995D01*
X520823D01*
X520638Y1080595D01*
Y1080769D01*
X522038D01*
Y1080595D01*
G37*
G36*
G01X533128D02*
X532943Y1079995D01*
X531913D01*
X531728Y1080595D01*
Y1080769D01*
X533128D01*
Y1080595D01*
G37*
G36*
G01X529428D02*
X529243Y1079995D01*
X528213D01*
X528028Y1080595D01*
Y1080769D01*
X529428D01*
Y1080595D01*
G37*
G36*
G01X525785D02*
X525600Y1079995D01*
X524570D01*
X524385Y1080595D01*
Y1080770D01*
X525785D01*
Y1080595D01*
G37*
G36*
G01X522038D02*
X521853Y1079995D01*
X520823D01*
X520638Y1080595D01*
Y1080769D01*
X522038D01*
Y1080595D01*
G37*
G36*
G01X533128D02*
X532943Y1079995D01*
X531913D01*
X531728Y1080595D01*
Y1080769D01*
X533128D01*
Y1080595D01*
G37*
G36*
G01X518328D02*
X518143Y1079995D01*
X517113D01*
X516928Y1080595D01*
Y1080769D01*
X518328D01*
Y1080595D01*
G37*
G36*
G01D02*
X518143Y1079995D01*
X517113D01*
X516928Y1080595D01*
Y1080769D01*
X518328D01*
Y1080595D01*
G37*
G36*
G01X526235Y1082191D02*
X526420Y1082791D01*
X527450D01*
X527635Y1082191D01*
Y1082017D01*
X526235D01*
Y1082191D01*
G37*
G36*
G01X522488D02*
X522673Y1082791D01*
X523703D01*
X523888Y1082191D01*
Y1082016D01*
X522488D01*
Y1082191D01*
G37*
G36*
G01X529949D02*
X530134Y1082791D01*
X531164D01*
X531349Y1082191D01*
Y1082017D01*
X529949D01*
Y1082191D01*
G37*
G36*
G01X526235D02*
X526420Y1082791D01*
X527450D01*
X527635Y1082191D01*
Y1082017D01*
X526235D01*
Y1082191D01*
G37*
G36*
G01X522488D02*
X522673Y1082791D01*
X523703D01*
X523888Y1082191D01*
Y1082016D01*
X522488D01*
Y1082191D01*
G37*
G36*
G01X529949D02*
X530134Y1082791D01*
X531164D01*
X531349Y1082191D01*
Y1082017D01*
X529949D01*
Y1082191D01*
G37*
G36*
G01X518845D02*
X519030Y1082791D01*
X520060D01*
X520245Y1082191D01*
Y1082017D01*
X518845D01*
Y1082191D01*
G37*
G36*
G01D02*
X519030Y1082791D01*
X520060D01*
X520245Y1082191D01*
Y1082017D01*
X518845D01*
Y1082191D01*
G37*
G36*
G01X526245Y1088600D02*
X526430Y1089200D01*
X527460D01*
X527645Y1088600D01*
Y1088426D01*
X526245D01*
Y1088600D01*
G37*
G36*
G01X522535D02*
X522720Y1089200D01*
X523750D01*
X523935Y1088600D01*
Y1088426D01*
X522535D01*
Y1088600D01*
G37*
G36*
G01X529945D02*
X530130Y1089200D01*
X531160D01*
X531345Y1088600D01*
Y1088426D01*
X529945D01*
Y1088600D01*
G37*
G36*
G01X526245D02*
X526430Y1089200D01*
X527460D01*
X527645Y1088600D01*
Y1088426D01*
X526245D01*
Y1088600D01*
G37*
G36*
G01X522535D02*
X522720Y1089200D01*
X523750D01*
X523935Y1088600D01*
Y1088426D01*
X522535D01*
Y1088600D01*
G37*
G36*
G01X529945D02*
X530130Y1089200D01*
X531160D01*
X531345Y1088600D01*
Y1088426D01*
X529945D01*
Y1088600D01*
G37*
G36*
G01X518835Y1088599D02*
X519020Y1089199D01*
X520050D01*
X520235Y1088599D01*
Y1088425D01*
X518835D01*
Y1088599D01*
G37*
G36*
G01D02*
X519020Y1089199D01*
X520050D01*
X520235Y1088599D01*
Y1088425D01*
X518835D01*
Y1088599D01*
G37*
G36*
G01X520628Y1085396D02*
X520813Y1085996D01*
X521843D01*
X522028Y1085396D01*
Y1085222D01*
X520628D01*
Y1085396D01*
G37*
G36*
G01X524361D02*
X524546Y1085996D01*
X525576D01*
X525761Y1085396D01*
Y1085221D01*
X524361D01*
Y1085396D01*
G37*
G36*
G01X528028D02*
X528213Y1085996D01*
X529243D01*
X529428Y1085396D01*
Y1085222D01*
X528028D01*
Y1085396D01*
G37*
G36*
G01X531728D02*
X531913Y1085996D01*
X532943D01*
X533128Y1085396D01*
Y1085222D01*
X531728D01*
Y1085396D01*
G37*
G36*
G01X520628D02*
X520813Y1085996D01*
X521843D01*
X522028Y1085396D01*
Y1085222D01*
X520628D01*
Y1085396D01*
G37*
G36*
G01X524361D02*
X524546Y1085996D01*
X525576D01*
X525761Y1085396D01*
Y1085221D01*
X524361D01*
Y1085396D01*
G37*
G36*
G01X528028D02*
X528213Y1085996D01*
X529243D01*
X529428Y1085396D01*
Y1085222D01*
X528028D01*
Y1085396D01*
G37*
G36*
G01X531728D02*
X531913Y1085996D01*
X532943D01*
X533128Y1085396D01*
Y1085222D01*
X531728D01*
Y1085396D01*
G37*
G36*
G01X516928D02*
X517113Y1085996D01*
X518143D01*
X518328Y1085396D01*
Y1085222D01*
X516928D01*
Y1085396D01*
G37*
G36*
G01D02*
X517113Y1085996D01*
X518143D01*
X518328Y1085396D01*
Y1085222D01*
X516928D01*
Y1085396D01*
G37*
G36*
G01X529428Y1087003D02*
X529243Y1086403D01*
X528213D01*
X528028Y1087003D01*
Y1087178D01*
X529428D01*
Y1087003D01*
G37*
G36*
G01X525728D02*
X525543Y1086403D01*
X524513D01*
X524328Y1087003D01*
Y1087178D01*
X525728D01*
Y1087003D01*
G37*
G36*
G01X522061Y1087005D02*
X521876Y1086405D01*
X520846D01*
X520661Y1087005D01*
Y1087179D01*
X522061D01*
Y1087005D01*
G37*
G36*
G01X533128Y1087003D02*
X532943Y1086403D01*
X531913D01*
X531728Y1087003D01*
Y1087178D01*
X533128D01*
Y1087003D01*
G37*
G36*
G01X529428D02*
X529243Y1086403D01*
X528213D01*
X528028Y1087003D01*
Y1087178D01*
X529428D01*
Y1087003D01*
G37*
G36*
G01X525728D02*
X525543Y1086403D01*
X524513D01*
X524328Y1087003D01*
Y1087178D01*
X525728D01*
Y1087003D01*
G37*
G36*
G01X522061Y1087005D02*
X521876Y1086405D01*
X520846D01*
X520661Y1087005D01*
Y1087179D01*
X522061D01*
Y1087005D01*
G37*
G36*
G01X533128Y1087003D02*
X532943Y1086403D01*
X531913D01*
X531728Y1087003D01*
Y1087178D01*
X533128D01*
Y1087003D01*
G37*
G36*
G01X518328D02*
X518143Y1086403D01*
X517113D01*
X516928Y1087003D01*
Y1087178D01*
X518328D01*
Y1087003D01*
G37*
G36*
G01D02*
X518143Y1086403D01*
X517113D01*
X516928Y1087003D01*
Y1087178D01*
X518328D01*
Y1087003D01*
G37*
G36*
G01X527635Y1083799D02*
X527450Y1083199D01*
X526420D01*
X526235Y1083799D01*
Y1083973D01*
X527635D01*
Y1083799D01*
G37*
G36*
G01X523935D02*
X523750Y1083199D01*
X522720D01*
X522535Y1083799D01*
Y1083974D01*
X523935D01*
Y1083799D01*
G37*
G36*
G01X531325D02*
X531140Y1083199D01*
X530110D01*
X529925Y1083799D01*
Y1083974D01*
X531325D01*
Y1083799D01*
G37*
G36*
G01X527635D02*
X527450Y1083199D01*
X526420D01*
X526235Y1083799D01*
Y1083973D01*
X527635D01*
Y1083799D01*
G37*
G36*
G01X523935D02*
X523750Y1083199D01*
X522720D01*
X522535Y1083799D01*
Y1083974D01*
X523935D01*
Y1083799D01*
G37*
G36*
G01X531325D02*
X531140Y1083199D01*
X530110D01*
X529925Y1083799D01*
Y1083974D01*
X531325D01*
Y1083799D01*
G37*
G36*
G01X520245D02*
X520060Y1083199D01*
X519030D01*
X518845Y1083799D01*
Y1083973D01*
X520245D01*
Y1083799D01*
G37*
G36*
G01D02*
X520060Y1083199D01*
X519030D01*
X518845Y1083799D01*
Y1083973D01*
X520245D01*
Y1083799D01*
G37*
G36*
G01X522028Y1093411D02*
X521843Y1092811D01*
X520813D01*
X520628Y1093411D01*
Y1093586D01*
X522028D01*
Y1093411D01*
G37*
G36*
G01X525728D02*
X525543Y1092811D01*
X524513D01*
X524328Y1093411D01*
Y1093586D01*
X525728D01*
Y1093411D01*
G37*
G36*
G01X529461Y1093413D02*
X529276Y1092813D01*
X528246D01*
X528061Y1093413D01*
Y1093587D01*
X529461D01*
Y1093413D01*
G37*
G36*
G01X533137D02*
X532952Y1092813D01*
X531922D01*
X531737Y1093413D01*
Y1093587D01*
X533137D01*
Y1093413D01*
G37*
G36*
G01X522028Y1093411D02*
X521843Y1092811D01*
X520813D01*
X520628Y1093411D01*
Y1093586D01*
X522028D01*
Y1093411D01*
G37*
G36*
G01X525728D02*
X525543Y1092811D01*
X524513D01*
X524328Y1093411D01*
Y1093586D01*
X525728D01*
Y1093411D01*
G37*
G36*
G01X529461Y1093413D02*
X529276Y1092813D01*
X528246D01*
X528061Y1093413D01*
Y1093587D01*
X529461D01*
Y1093413D01*
G37*
G36*
G01X533137D02*
X532952Y1092813D01*
X531922D01*
X531737Y1093413D01*
Y1093587D01*
X533137D01*
Y1093413D01*
G37*
G36*
G01X518338D02*
X518153Y1092813D01*
X517123D01*
X516938Y1093413D01*
Y1093587D01*
X518338D01*
Y1093413D01*
G37*
G36*
G01D02*
X518153Y1092813D01*
X517123D01*
X516938Y1093413D01*
Y1093587D01*
X518338D01*
Y1093413D01*
G37*
G36*
G01X520661Y1091803D02*
X520846Y1092403D01*
X521876D01*
X522061Y1091803D01*
Y1091629D01*
X520661D01*
Y1091803D01*
G37*
G36*
G01X524328Y1091804D02*
X524513Y1092404D01*
X525543D01*
X525728Y1091804D01*
Y1091630D01*
X524328D01*
Y1091804D01*
G37*
G36*
G01X528028D02*
X528213Y1092404D01*
X529243D01*
X529428Y1091804D01*
Y1091630D01*
X528028D01*
Y1091804D01*
G37*
G36*
G01X531728D02*
X531913Y1092404D01*
X532943D01*
X533128Y1091804D01*
Y1091630D01*
X531728D01*
Y1091804D01*
G37*
G36*
G01X520661Y1091803D02*
X520846Y1092403D01*
X521876D01*
X522061Y1091803D01*
Y1091629D01*
X520661D01*
Y1091803D01*
G37*
G36*
G01X524328Y1091804D02*
X524513Y1092404D01*
X525543D01*
X525728Y1091804D01*
Y1091630D01*
X524328D01*
Y1091804D01*
G37*
G36*
G01X528028D02*
X528213Y1092404D01*
X529243D01*
X529428Y1091804D01*
Y1091630D01*
X528028D01*
Y1091804D01*
G37*
G36*
G01X531728D02*
X531913Y1092404D01*
X532943D01*
X533128Y1091804D01*
Y1091630D01*
X531728D01*
Y1091804D01*
G37*
G36*
G01X516938Y1091803D02*
X517123Y1092403D01*
X518153D01*
X518338Y1091803D01*
Y1091629D01*
X516938D01*
Y1091803D01*
G37*
G36*
G01D02*
X517123Y1092403D01*
X518153D01*
X518338Y1091803D01*
Y1091629D01*
X516938D01*
Y1091803D01*
G37*
G36*
G01X522545Y1095009D02*
X522730Y1095609D01*
X523760D01*
X523945Y1095009D01*
Y1094835D01*
X522545D01*
Y1095009D01*
G37*
G36*
G01X526235Y1095008D02*
X526420Y1095608D01*
X527450D01*
X527635Y1095008D01*
Y1094834D01*
X526235D01*
Y1095008D01*
G37*
G36*
G01X529911D02*
X530096Y1095608D01*
X531126D01*
X531311Y1095008D01*
Y1094834D01*
X529911D01*
Y1095008D01*
G37*
G36*
G01X522545Y1095009D02*
X522730Y1095609D01*
X523760D01*
X523945Y1095009D01*
Y1094835D01*
X522545D01*
Y1095009D01*
G37*
G36*
G01X526235Y1095008D02*
X526420Y1095608D01*
X527450D01*
X527635Y1095008D01*
Y1094834D01*
X526235D01*
Y1095008D01*
G37*
G36*
G01X529911D02*
X530096Y1095608D01*
X531126D01*
X531311Y1095008D01*
Y1094834D01*
X529911D01*
Y1095008D01*
G37*
G36*
G01X518845Y1095009D02*
X519030Y1095609D01*
X520060D01*
X520245Y1095009D01*
Y1094835D01*
X518845D01*
Y1095009D01*
G37*
G36*
G01D02*
X519030Y1095609D01*
X520060D01*
X520245Y1095009D01*
Y1094835D01*
X518845D01*
Y1095009D01*
G37*
G36*
G01X523935Y1090207D02*
X523750Y1089607D01*
X522720D01*
X522535Y1090207D01*
Y1090382D01*
X523935D01*
Y1090207D01*
G37*
G36*
G01X527645D02*
X527460Y1089607D01*
X526430D01*
X526245Y1090207D01*
Y1090382D01*
X527645D01*
Y1090207D01*
G37*
G36*
G01X531345D02*
X531160Y1089607D01*
X530130D01*
X529945Y1090207D01*
Y1090382D01*
X531345D01*
Y1090207D01*
G37*
G36*
G01X523935D02*
X523750Y1089607D01*
X522720D01*
X522535Y1090207D01*
Y1090382D01*
X523935D01*
Y1090207D01*
G37*
G36*
G01X527645D02*
X527460Y1089607D01*
X526430D01*
X526245Y1090207D01*
Y1090382D01*
X527645D01*
Y1090207D01*
G37*
G36*
G01X531345D02*
X531160Y1089607D01*
X530130D01*
X529945Y1090207D01*
Y1090382D01*
X531345D01*
Y1090207D01*
G37*
G36*
G01X520235Y1090209D02*
X520050Y1089609D01*
X519020D01*
X518835Y1090209D01*
Y1090383D01*
X520235D01*
Y1090209D01*
G37*
G36*
G01D02*
X520050Y1089609D01*
X519020D01*
X518835Y1090209D01*
Y1090383D01*
X520235D01*
Y1090209D01*
G37*
G36*
G01X526245Y1101417D02*
X526430Y1102017D01*
X527460D01*
X527645Y1101417D01*
Y1101243D01*
X526245D01*
Y1101417D01*
G37*
G36*
G01X522488D02*
X522673Y1102017D01*
X523703D01*
X523888Y1101417D01*
Y1101243D01*
X522488D01*
Y1101417D01*
G37*
G36*
G01X529911Y1101416D02*
X530096Y1102016D01*
X531126D01*
X531311Y1101416D01*
Y1101242D01*
X529911D01*
Y1101416D01*
G37*
G36*
G01X526245Y1101417D02*
X526430Y1102017D01*
X527460D01*
X527645Y1101417D01*
Y1101243D01*
X526245D01*
Y1101417D01*
G37*
G36*
G01X522488D02*
X522673Y1102017D01*
X523703D01*
X523888Y1101417D01*
Y1101243D01*
X522488D01*
Y1101417D01*
G37*
G36*
G01X529911Y1101416D02*
X530096Y1102016D01*
X531126D01*
X531311Y1101416D01*
Y1101242D01*
X529911D01*
Y1101416D01*
G37*
G36*
G01X518788D02*
X518973Y1102016D01*
X520003D01*
X520188Y1101416D01*
Y1101242D01*
X518788D01*
Y1101416D01*
G37*
G36*
G01D02*
X518973Y1102016D01*
X520003D01*
X520188Y1101416D01*
Y1101242D01*
X518788D01*
Y1101416D01*
G37*
G36*
G01X527635Y1096617D02*
X527450Y1096017D01*
X526420D01*
X526235Y1096617D01*
Y1096792D01*
X527635D01*
Y1096617D01*
G37*
G36*
G01X523912D02*
X523727Y1096017D01*
X522697D01*
X522512Y1096617D01*
Y1096792D01*
X523912D01*
Y1096617D01*
G37*
G36*
G01X531311D02*
X531126Y1096017D01*
X530096D01*
X529911Y1096617D01*
Y1096792D01*
X531311D01*
Y1096617D01*
G37*
G36*
G01X527635D02*
X527450Y1096017D01*
X526420D01*
X526235Y1096617D01*
Y1096792D01*
X527635D01*
Y1096617D01*
G37*
G36*
G01X523912D02*
X523727Y1096017D01*
X522697D01*
X522512Y1096617D01*
Y1096792D01*
X523912D01*
Y1096617D01*
G37*
G36*
G01X531311D02*
X531126Y1096017D01*
X530096D01*
X529911Y1096617D01*
Y1096792D01*
X531311D01*
Y1096617D01*
G37*
G36*
G01X520212D02*
X520027Y1096017D01*
X518997D01*
X518812Y1096617D01*
Y1096792D01*
X520212D01*
Y1096617D01*
G37*
G36*
G01D02*
X520027Y1096017D01*
X518997D01*
X518812Y1096617D01*
Y1096792D01*
X520212D01*
Y1096617D01*
G37*
G36*
G01X529428Y1099821D02*
X529243Y1099221D01*
X528213D01*
X528028Y1099821D01*
Y1099995D01*
X529428D01*
Y1099821D01*
G37*
G36*
G01X525738Y1099822D02*
X525553Y1099222D01*
X524523D01*
X524338Y1099822D01*
Y1099996D01*
X525738D01*
Y1099822D01*
G37*
G36*
G01X522095Y1099821D02*
X521910Y1099221D01*
X520880D01*
X520695Y1099821D01*
Y1099995D01*
X522095D01*
Y1099821D01*
G37*
G36*
G01X533194D02*
X533009Y1099221D01*
X531979D01*
X531794Y1099821D01*
Y1099995D01*
X533194D01*
Y1099821D01*
G37*
G36*
G01X529428D02*
X529243Y1099221D01*
X528213D01*
X528028Y1099821D01*
Y1099995D01*
X529428D01*
Y1099821D01*
G37*
G36*
G01X525738Y1099822D02*
X525553Y1099222D01*
X524523D01*
X524338Y1099822D01*
Y1099996D01*
X525738D01*
Y1099822D01*
G37*
G36*
G01X522095Y1099821D02*
X521910Y1099221D01*
X520880D01*
X520695Y1099821D01*
Y1099995D01*
X522095D01*
Y1099821D01*
G37*
G36*
G01X533194D02*
X533009Y1099221D01*
X531979D01*
X531794Y1099821D01*
Y1099995D01*
X533194D01*
Y1099821D01*
G37*
G36*
G01X520662Y1098212D02*
X520847Y1098812D01*
X521877D01*
X522062Y1098212D01*
Y1098038D01*
X520662D01*
Y1098212D01*
G37*
G36*
G01X524338D02*
X524523Y1098812D01*
X525553D01*
X525738Y1098212D01*
Y1098038D01*
X524338D01*
Y1098212D01*
G37*
G36*
G01X528061D02*
X528246Y1098812D01*
X529276D01*
X529461Y1098212D01*
Y1098038D01*
X528061D01*
Y1098212D01*
G37*
G36*
G01X531761D02*
X531946Y1098812D01*
X532976D01*
X533161Y1098212D01*
Y1098038D01*
X531761D01*
Y1098212D01*
G37*
G36*
G01X520662D02*
X520847Y1098812D01*
X521877D01*
X522062Y1098212D01*
Y1098038D01*
X520662D01*
Y1098212D01*
G37*
G36*
G01X524338D02*
X524523Y1098812D01*
X525553D01*
X525738Y1098212D01*
Y1098038D01*
X524338D01*
Y1098212D01*
G37*
G36*
G01X528061D02*
X528246Y1098812D01*
X529276D01*
X529461Y1098212D01*
Y1098038D01*
X528061D01*
Y1098212D01*
G37*
G36*
G01X531761D02*
X531946Y1098812D01*
X532976D01*
X533161Y1098212D01*
Y1098038D01*
X531761D01*
Y1098212D01*
G37*
G36*
G01X516938Y1098213D02*
X517123Y1098813D01*
X518153D01*
X518338Y1098213D01*
Y1098039D01*
X516938D01*
Y1098213D01*
G37*
G36*
G01D02*
X517123Y1098813D01*
X518153D01*
X518338Y1098213D01*
Y1098039D01*
X516938D01*
Y1098213D01*
G37*
G36*
G01X544288Y850573D02*
X544473Y851173D01*
X545503D01*
X545688Y850573D01*
Y850399D01*
X544288D01*
Y850573D01*
G37*
G36*
G01X538289Y852184D02*
X538104Y851584D01*
X537074D01*
X536889Y852184D01*
Y852358D01*
X538289D01*
Y852184D01*
G37*
G36*
G01X544288Y850573D02*
X544473Y851173D01*
X545503D01*
X545688Y850573D01*
Y850399D01*
X544288D01*
Y850573D01*
G37*
G36*
G01X549402Y852181D02*
X549217Y851581D01*
X548187D01*
X548002Y852181D01*
Y852356D01*
X549402D01*
Y852181D01*
G37*
G36*
G01X547506Y848980D02*
X547321Y848380D01*
X546291D01*
X546106Y848980D01*
Y849155D01*
X547506D01*
Y848980D01*
G37*
G36*
G01X543829Y848972D02*
X543644Y848372D01*
X542614D01*
X542429Y848972D01*
Y849146D01*
X543829D01*
Y848972D01*
G37*
G36*
G01X547506Y848980D02*
X547321Y848380D01*
X546291D01*
X546106Y848980D01*
Y849155D01*
X547506D01*
Y848980D01*
G37*
G36*
G01X543829Y848972D02*
X543644Y848372D01*
X542614D01*
X542429Y848972D01*
Y849146D01*
X543829D01*
Y848972D01*
G37*
G36*
G01X547529Y868205D02*
X547344Y867605D01*
X546314D01*
X546129Y868205D01*
Y868380D01*
X547529D01*
Y868205D01*
G37*
G36*
G01D02*
X547344Y867605D01*
X546314D01*
X546129Y868205D01*
Y868380D01*
X547529D01*
Y868205D01*
G37*
G36*
G01X546097Y853779D02*
X546282Y854379D01*
X547312D01*
X547497Y853779D01*
Y853605D01*
X546097D01*
Y853779D01*
G37*
G36*
G01X542429D02*
X542614Y854379D01*
X543644D01*
X543829Y853779D01*
Y853604D01*
X542429D01*
Y853779D01*
G37*
G36*
G01X546097D02*
X546282Y854379D01*
X547312D01*
X547497Y853779D01*
Y853605D01*
X546097D01*
Y853779D01*
G37*
G36*
G01X542429D02*
X542614Y854379D01*
X543644D01*
X543829Y853779D01*
Y853604D01*
X542429D01*
Y853779D01*
G37*
G36*
G01X545679Y858593D02*
X545494Y857993D01*
X544464D01*
X544279Y858593D01*
Y858768D01*
X545679D01*
Y858593D01*
G37*
G36*
G01X549345D02*
X549160Y857993D01*
X548130D01*
X547945Y858593D01*
Y858767D01*
X549345D01*
Y858593D01*
G37*
G36*
G01X545679D02*
X545494Y857993D01*
X544464D01*
X544279Y858593D01*
Y858768D01*
X545679D01*
Y858593D01*
G37*
G36*
G01X549345D02*
X549160Y857993D01*
X548130D01*
X547945Y858593D01*
Y858767D01*
X549345D01*
Y858593D01*
G37*
G36*
G01X544279Y856985D02*
X544464Y857585D01*
X545494D01*
X545679Y856985D01*
Y856810D01*
X544279D01*
Y856985D01*
G37*
G36*
G01X547945D02*
X548130Y857585D01*
X549160D01*
X549345Y856985D01*
Y856811D01*
X547945D01*
Y856985D01*
G37*
G36*
G01X544279D02*
X544464Y857585D01*
X545494D01*
X545679Y856985D01*
Y856810D01*
X544279D01*
Y856985D01*
G37*
G36*
G01X547945D02*
X548130Y857585D01*
X549160D01*
X549345Y856985D01*
Y856811D01*
X547945D01*
Y856985D01*
G37*
G36*
G01X546162Y860189D02*
X546347Y860789D01*
X547377D01*
X547562Y860189D01*
Y860015D01*
X546162D01*
Y860189D01*
G37*
G36*
G01D02*
X546347Y860789D01*
X547377D01*
X547562Y860189D01*
Y860015D01*
X546162D01*
Y860189D01*
G37*
G36*
G01X547562Y855387D02*
X547377Y854787D01*
X546347D01*
X546162Y855387D01*
Y855562D01*
X547562D01*
Y855387D01*
G37*
G36*
G01X543796D02*
X543611Y854787D01*
X542581D01*
X542396Y855387D01*
Y855562D01*
X543796D01*
Y855387D01*
G37*
G36*
G01X547562D02*
X547377Y854787D01*
X546347D01*
X546162Y855387D01*
Y855562D01*
X547562D01*
Y855387D01*
G37*
G36*
G01X543796D02*
X543611Y854787D01*
X542581D01*
X542396Y855387D01*
Y855562D01*
X543796D01*
Y855387D01*
G37*
G36*
G01X544279Y869801D02*
X544464Y870401D01*
X545494D01*
X545679Y869801D01*
Y869627D01*
X544279D01*
Y869801D01*
G37*
G36*
G01X547979D02*
X548164Y870401D01*
X549194D01*
X549379Y869801D01*
Y869627D01*
X547979D01*
Y869801D01*
G37*
G36*
G01X544279D02*
X544464Y870401D01*
X545494D01*
X545679Y869801D01*
Y869627D01*
X544279D01*
Y869801D01*
G37*
G36*
G01X547979D02*
X548164Y870401D01*
X549194D01*
X549379Y869801D01*
Y869627D01*
X547979D01*
Y869801D01*
G37*
G36*
G01X535029Y898641D02*
X535214Y899241D01*
X536244D01*
X536429Y898641D01*
Y898466D01*
X535029D01*
Y898641D01*
G37*
G36*
G01D02*
X535214Y899241D01*
X536244D01*
X536429Y898641D01*
Y898466D01*
X535029D01*
Y898641D01*
G37*
G36*
G01X538729D02*
X538914Y899241D01*
X539944D01*
X540129Y898641D01*
Y898466D01*
X538729D01*
Y898641D01*
G37*
G36*
G01D02*
X538914Y899241D01*
X539944D01*
X540129Y898641D01*
Y898466D01*
X538729D01*
Y898641D01*
G37*
G36*
G01X533179Y895435D02*
X533364Y896035D01*
X534394D01*
X534579Y895435D01*
Y895261D01*
X533179D01*
Y895435D01*
G37*
G36*
G01D02*
X533364Y896035D01*
X534394D01*
X534579Y895435D01*
Y895261D01*
X533179D01*
Y895435D01*
G37*
G36*
G01X536879D02*
X537064Y896035D01*
X538094D01*
X538279Y895435D01*
Y895261D01*
X536879D01*
Y895435D01*
G37*
G36*
G01D02*
X537064Y896035D01*
X538094D01*
X538279Y895435D01*
Y895261D01*
X536879D01*
Y895435D01*
G37*
G36*
G01X534579Y897045D02*
X534394Y896445D01*
X533364D01*
X533179Y897045D01*
Y897219D01*
X534579D01*
Y897045D01*
G37*
G36*
G01D02*
X534394Y896445D01*
X533364D01*
X533179Y897045D01*
Y897219D01*
X534579D01*
Y897045D01*
G37*
G36*
G01X538279D02*
X538094Y896445D01*
X537064D01*
X536879Y897045D01*
Y897219D01*
X538279D01*
Y897045D01*
G37*
G36*
G01D02*
X538094Y896445D01*
X537064D01*
X536879Y897045D01*
Y897219D01*
X538279D01*
Y897045D01*
G37*
G36*
G01X536429Y893841D02*
X536244Y893241D01*
X535214D01*
X535029Y893841D01*
Y894015D01*
X536429D01*
Y893841D01*
G37*
G36*
G01D02*
X536244Y893241D01*
X535214D01*
X535029Y893841D01*
Y894015D01*
X536429D01*
Y893841D01*
G37*
G36*
G01X536428Y900249D02*
X536243Y899649D01*
X535213D01*
X535028Y900249D01*
Y900423D01*
X536428D01*
Y900249D01*
G37*
G36*
G01D02*
X536243Y899649D01*
X535213D01*
X535028Y900249D01*
Y900423D01*
X536428D01*
Y900249D01*
G37*
G36*
G01X540129Y900251D02*
X539944Y899651D01*
X538914D01*
X538729Y900251D01*
Y900425D01*
X540129D01*
Y900251D01*
G37*
G36*
G01D02*
X539944Y899651D01*
X538914D01*
X538729Y900251D01*
Y900425D01*
X540129D01*
Y900251D01*
G37*
G36*
G01X539561Y916848D02*
X538949Y916708D01*
X538434Y917600D01*
X538861Y918060D01*
X539012Y918147D01*
X539712Y916935D01*
X539561Y916848D01*
G37*
G36*
G01X545679Y916271D02*
X545494Y915671D01*
X544464D01*
X544279Y916271D01*
Y916445D01*
X545679D01*
Y916271D01*
G37*
G36*
G01X541979D02*
X541794Y915671D01*
X540764D01*
X540579Y916271D01*
Y916445D01*
X541979D01*
Y916271D01*
G37*
G36*
G01X539561Y916848D02*
X538949Y916708D01*
X538434Y917600D01*
X538861Y918060D01*
X539012Y918147D01*
X539712Y916935D01*
X539561Y916848D01*
G37*
G36*
G01X545679Y916271D02*
X545494Y915671D01*
X544464D01*
X544279Y916271D01*
Y916445D01*
X545679D01*
Y916271D01*
G37*
G36*
G01X541979D02*
X541794Y915671D01*
X540764D01*
X540579Y916271D01*
Y916445D01*
X541979D01*
Y916271D01*
G37*
G36*
G01X534579D02*
X534394Y915671D01*
X533364D01*
X533179Y916271D01*
Y916445D01*
X534579D01*
Y916271D01*
G37*
G36*
G01D02*
X534394Y915671D01*
X533364D01*
X533179Y916271D01*
Y916445D01*
X534579D01*
Y916271D01*
G37*
G36*
G01X537711Y913644D02*
X537099Y913504D01*
X536584Y914396D01*
X537011Y914856D01*
X537162Y914943D01*
X537862Y913731D01*
X537711Y913644D01*
G37*
G36*
G01X543829Y913067D02*
X543644Y912467D01*
X542614D01*
X542429Y913067D01*
Y913241D01*
X543829D01*
Y913067D01*
G37*
G36*
G01X540129D02*
X539944Y912467D01*
X538914D01*
X538729Y913067D01*
Y913241D01*
X540129D01*
Y913067D01*
G37*
G36*
G01X537711Y913644D02*
X537099Y913504D01*
X536584Y914396D01*
X537011Y914856D01*
X537162Y914943D01*
X537862Y913731D01*
X537711Y913644D01*
G37*
G36*
G01X543829Y913067D02*
X543644Y912467D01*
X542614D01*
X542429Y913067D01*
Y913241D01*
X543829D01*
Y913067D01*
G37*
G36*
G01X540129D02*
X539944Y912467D01*
X538914D01*
X538729Y913067D01*
Y913241D01*
X540129D01*
Y913067D01*
G37*
G36*
G01X537447Y917288D02*
X538059Y917428D01*
X538574Y916536D01*
X538147Y916076D01*
X537996Y915989D01*
X537296Y917201D01*
X537447Y917288D01*
G37*
G36*
G01X544279Y914661D02*
X544464Y915261D01*
X545494D01*
X545679Y914661D01*
Y914487D01*
X544279D01*
Y914661D01*
G37*
G36*
G01X540579D02*
X540764Y915261D01*
X541794D01*
X541979Y914661D01*
Y914487D01*
X540579D01*
Y914661D01*
G37*
G36*
G01X537447Y917288D02*
X538059Y917428D01*
X538574Y916536D01*
X538147Y916076D01*
X537996Y915989D01*
X537296Y917201D01*
X537447Y917288D01*
G37*
G36*
G01X544279Y914661D02*
X544464Y915261D01*
X545494D01*
X545679Y914661D01*
Y914487D01*
X544279D01*
Y914661D01*
G37*
G36*
G01X540579D02*
X540764Y915261D01*
X541794D01*
X541979Y914661D01*
Y914487D01*
X540579D01*
Y914661D01*
G37*
G36*
G01X535029Y911457D02*
X535214Y912057D01*
X536244D01*
X536429Y911457D01*
Y911283D01*
X535029D01*
Y911457D01*
G37*
G36*
G01D02*
X535214Y912057D01*
X536244D01*
X536429Y911457D01*
Y911283D01*
X535029D01*
Y911457D01*
G37*
G36*
G01X538729D02*
X538914Y912057D01*
X539944D01*
X540129Y911457D01*
Y911283D01*
X538729D01*
Y911457D01*
G37*
G36*
G01D02*
X538914Y912057D01*
X539944D01*
X540129Y911457D01*
Y911283D01*
X538729D01*
Y911457D01*
G37*
G36*
G01X533179Y908253D02*
X533364Y908853D01*
X534394D01*
X534579Y908253D01*
Y908078D01*
X533179D01*
Y908253D01*
G37*
G36*
G01D02*
X533364Y908853D01*
X534394D01*
X534579Y908253D01*
Y908078D01*
X533179D01*
Y908253D01*
G37*
G36*
G01X536879D02*
X537064Y908853D01*
X538094D01*
X538279Y908253D01*
Y908078D01*
X536879D01*
Y908253D01*
G37*
G36*
G01X540579D02*
X540764Y908853D01*
X541794D01*
X541979Y908253D01*
Y908078D01*
X540579D01*
Y908253D01*
G37*
G36*
G01X536879D02*
X537064Y908853D01*
X538094D01*
X538279Y908253D01*
Y908078D01*
X536879D01*
Y908253D01*
G37*
G36*
G01X540579D02*
X540764Y908853D01*
X541794D01*
X541979Y908253D01*
Y908078D01*
X540579D01*
Y908253D01*
G37*
G36*
G01X534579Y909861D02*
X534394Y909261D01*
X533364D01*
X533179Y909861D01*
Y910036D01*
X534579D01*
Y909861D01*
G37*
G36*
G01D02*
X534394Y909261D01*
X533364D01*
X533179Y909861D01*
Y910036D01*
X534579D01*
Y909861D01*
G37*
G36*
G01X538279D02*
X538094Y909261D01*
X537064D01*
X536879Y909861D01*
Y910036D01*
X538279D01*
Y909861D01*
G37*
G36*
G01X541979D02*
X541794Y909261D01*
X540764D01*
X540579Y909861D01*
Y910036D01*
X541979D01*
Y909861D01*
G37*
G36*
G01X538279D02*
X538094Y909261D01*
X537064D01*
X536879Y909861D01*
Y910036D01*
X538279D01*
Y909861D01*
G37*
G36*
G01X541979D02*
X541794Y909261D01*
X540764D01*
X540579Y909861D01*
Y910036D01*
X541979D01*
Y909861D01*
G37*
G36*
G01X536429Y906657D02*
X536244Y906057D01*
X535214D01*
X535029Y906657D01*
Y906832D01*
X536429D01*
Y906657D01*
G37*
G36*
G01D02*
X536244Y906057D01*
X535214D01*
X535029Y906657D01*
Y906832D01*
X536429D01*
Y906657D01*
G37*
G36*
G01X540129D02*
X539944Y906057D01*
X538914D01*
X538729Y906657D01*
Y906832D01*
X540129D01*
Y906657D01*
G37*
G36*
G01D02*
X539944Y906057D01*
X538914D01*
X538729Y906657D01*
Y906832D01*
X540129D01*
Y906657D01*
G37*
G36*
G01X534579Y903453D02*
X534394Y902853D01*
X533364D01*
X533179Y903453D01*
Y903628D01*
X534579D01*
Y903453D01*
G37*
G36*
G01D02*
X534394Y902853D01*
X533364D01*
X533179Y903453D01*
Y903628D01*
X534579D01*
Y903453D01*
G37*
G36*
G01X538279D02*
X538094Y902853D01*
X537064D01*
X536879Y903453D01*
Y903628D01*
X538279D01*
Y903453D01*
G37*
G36*
G01D02*
X538094Y902853D01*
X537064D01*
X536879Y903453D01*
Y903628D01*
X538279D01*
Y903453D01*
G37*
G36*
G01X533179Y901845D02*
X533364Y902445D01*
X534394D01*
X534579Y901845D01*
Y901670D01*
X533179D01*
Y901845D01*
G37*
G36*
G01D02*
X533364Y902445D01*
X534394D01*
X534579Y901845D01*
Y901670D01*
X533179D01*
Y901845D01*
G37*
G36*
G01X536879D02*
X537064Y902445D01*
X538094D01*
X538279Y901845D01*
Y901670D01*
X536879D01*
Y901845D01*
G37*
G36*
G01D02*
X537064Y902445D01*
X538094D01*
X538279Y901845D01*
Y901670D01*
X536879D01*
Y901845D01*
G37*
G36*
G01X535029Y905049D02*
X535214Y905649D01*
X536244D01*
X536429Y905049D01*
Y904874D01*
X535029D01*
Y905049D01*
G37*
G36*
G01D02*
X535214Y905649D01*
X536244D01*
X536429Y905049D01*
Y904874D01*
X535029D01*
Y905049D01*
G37*
G36*
G01X538729D02*
X538914Y905649D01*
X539944D01*
X540129Y905049D01*
Y904874D01*
X538729D01*
Y905049D01*
G37*
G36*
G01D02*
X538914Y905649D01*
X539944D01*
X540129Y905049D01*
Y904874D01*
X538729D01*
Y905049D01*
G37*
G36*
G01X536395Y932291D02*
X536210Y931691D01*
X535180D01*
X534995Y932291D01*
Y932465D01*
X536395D01*
Y932291D01*
G37*
G36*
G01D02*
X536210Y931691D01*
X535180D01*
X534995Y932291D01*
Y932465D01*
X536395D01*
Y932291D01*
G37*
G36*
G01X543795D02*
X543610Y931691D01*
X542580D01*
X542395Y932291D01*
Y932465D01*
X543795D01*
Y932291D01*
G37*
G36*
G01X540095D02*
X539910Y931691D01*
X538880D01*
X538695Y932291D01*
Y932465D01*
X540095D01*
Y932291D01*
G37*
G36*
G01X546964Y929658D02*
X546352Y929518D01*
X545837Y930410D01*
X546264Y930870D01*
X546415Y930957D01*
X547115Y929745D01*
X546964Y929658D01*
G37*
G36*
G01X543795Y932291D02*
X543610Y931691D01*
X542580D01*
X542395Y932291D01*
Y932465D01*
X543795D01*
Y932291D01*
G37*
G36*
G01X540095D02*
X539910Y931691D01*
X538880D01*
X538695Y932291D01*
Y932465D01*
X540095D01*
Y932291D01*
G37*
G36*
G01X546964Y929658D02*
X546352Y929518D01*
X545837Y930410D01*
X546264Y930870D01*
X546415Y930957D01*
X547115Y929745D01*
X546964Y929658D01*
G37*
G36*
G01X534995Y930685D02*
X535180Y931285D01*
X536210D01*
X536395Y930685D01*
Y930510D01*
X534995D01*
Y930685D01*
G37*
G36*
G01D02*
X535180Y931285D01*
X536210D01*
X536395Y930685D01*
Y930510D01*
X534995D01*
Y930685D01*
G37*
G36*
G01X538695D02*
X538880Y931285D01*
X539910D01*
X540095Y930685D01*
Y930510D01*
X538695D01*
Y930685D01*
G37*
G36*
G01X542395D02*
X542580Y931285D01*
X543610D01*
X543795Y930685D01*
Y930510D01*
X542395D01*
Y930685D01*
G37*
G36*
G01X544843Y930113D02*
X545455Y930253D01*
X545970Y929361D01*
X545543Y928901D01*
X545392Y928814D01*
X544692Y930026D01*
X544843Y930113D01*
G37*
G36*
G01X538695Y930685D02*
X538880Y931285D01*
X539910D01*
X540095Y930685D01*
Y930510D01*
X538695D01*
Y930685D01*
G37*
G36*
G01X542395D02*
X542580Y931285D01*
X543610D01*
X543795Y930685D01*
Y930510D01*
X542395D01*
Y930685D01*
G37*
G36*
G01X544843Y930113D02*
X545455Y930253D01*
X545970Y929361D01*
X545543Y928901D01*
X545392Y928814D01*
X544692Y930026D01*
X544843Y930113D01*
G37*
G36*
G01X536429Y919475D02*
X536244Y918875D01*
X535214D01*
X535029Y919475D01*
Y919649D01*
X536429D01*
Y919475D01*
G37*
G36*
G01D02*
X536244Y918875D01*
X535214D01*
X535029Y919475D01*
Y919649D01*
X536429D01*
Y919475D01*
G37*
G36*
G01X533179Y921071D02*
X533364Y921671D01*
X534394D01*
X534579Y921071D01*
Y920896D01*
X533179D01*
Y921071D01*
G37*
G36*
G01D02*
X533364Y921671D01*
X534394D01*
X534579Y921071D01*
Y920896D01*
X533179D01*
Y921071D01*
G37*
G36*
G01X542429Y917865D02*
X542614Y918465D01*
X543644D01*
X543829Y917865D01*
Y917691D01*
X542429D01*
Y917865D01*
G37*
G36*
G01X539289Y920508D02*
X539901Y920648D01*
X540416Y919756D01*
X539989Y919296D01*
X539838Y919209D01*
X539138Y920421D01*
X539289Y920508D01*
G37*
G36*
G01X536879Y921071D02*
X537064Y921671D01*
X538094D01*
X538279Y921071D01*
Y920896D01*
X536879D01*
Y921071D01*
G37*
G36*
G01X542429Y917865D02*
X542614Y918465D01*
X543644D01*
X543829Y917865D01*
Y917691D01*
X542429D01*
Y917865D01*
G37*
G36*
G01X539289Y920508D02*
X539901Y920648D01*
X540416Y919756D01*
X539989Y919296D01*
X539838Y919209D01*
X539138Y920421D01*
X539289Y920508D01*
G37*
G36*
G01X536879Y921071D02*
X537064Y921671D01*
X538094D01*
X538279Y921071D01*
Y920896D01*
X536879D01*
Y921071D01*
G37*
G36*
G01X535029Y917865D02*
X535214Y918465D01*
X536244D01*
X536429Y917865D01*
Y917691D01*
X535029D01*
Y917865D01*
G37*
G36*
G01D02*
X535214Y918465D01*
X536244D01*
X536429Y917865D01*
Y917691D01*
X535029D01*
Y917865D01*
G37*
G36*
G01X546692Y933320D02*
X547304Y933460D01*
X547819Y932568D01*
X547392Y932108D01*
X547241Y932021D01*
X546541Y933233D01*
X546692Y933320D01*
G37*
G36*
G01D02*
X547304Y933460D01*
X547819Y932568D01*
X547392Y932108D01*
X547241Y932021D01*
X546541Y933233D01*
X546692Y933320D01*
G37*
G36*
G01X534612Y929087D02*
X534427Y928487D01*
X533397D01*
X533212Y929087D01*
Y929261D01*
X534612D01*
Y929087D01*
G37*
G36*
G01D02*
X534427Y928487D01*
X533397D01*
X533212Y929087D01*
Y929261D01*
X534612D01*
Y929087D01*
G37*
G36*
G01X545115Y926451D02*
X544503Y926311D01*
X543988Y927203D01*
X544415Y927663D01*
X544566Y927750D01*
X545266Y926538D01*
X545115Y926451D01*
G37*
G36*
G01X542012Y929087D02*
X541827Y928487D01*
X540797D01*
X540612Y929087D01*
Y929261D01*
X542012D01*
Y929087D01*
G37*
G36*
G01X538312D02*
X538127Y928487D01*
X537097D01*
X536912Y929087D01*
Y929261D01*
X538312D01*
Y929087D01*
G37*
G36*
G01X547495Y925883D02*
X547310Y925283D01*
X546280D01*
X546095Y925883D01*
Y926057D01*
X547495D01*
Y925883D01*
G37*
G36*
G01X545115Y926451D02*
X544503Y926311D01*
X543988Y927203D01*
X544415Y927663D01*
X544566Y927750D01*
X545266Y926538D01*
X545115Y926451D01*
G37*
G36*
G01X542012Y929087D02*
X541827Y928487D01*
X540797D01*
X540612Y929087D01*
Y929261D01*
X542012D01*
Y929087D01*
G37*
G36*
G01X538312D02*
X538127Y928487D01*
X537097D01*
X536912Y929087D01*
Y929261D01*
X538312D01*
Y929087D01*
G37*
G36*
G01X547495Y925883D02*
X547310Y925283D01*
X546280D01*
X546095Y925883D01*
Y926057D01*
X547495D01*
Y925883D01*
G37*
G36*
G01X534579Y922679D02*
X534394Y922079D01*
X533364D01*
X533179Y922679D01*
Y922854D01*
X534579D01*
Y922679D01*
G37*
G36*
G01D02*
X534394Y922079D01*
X533364D01*
X533179Y922679D01*
Y922854D01*
X534579D01*
Y922679D01*
G37*
G36*
G01X538312D02*
X538127Y922079D01*
X537097D01*
X536912Y922679D01*
Y922853D01*
X538312D01*
Y922679D01*
G37*
G36*
G01X541419Y920037D02*
X540807Y919897D01*
X540292Y920789D01*
X540719Y921249D01*
X540870Y921336D01*
X541570Y920124D01*
X541419Y920037D01*
G37*
G36*
G01X543829Y919475D02*
X543644Y918875D01*
X542614D01*
X542429Y919475D01*
Y919649D01*
X543829D01*
Y919475D01*
G37*
G36*
G01X547529D02*
X547344Y918875D01*
X546314D01*
X546129Y919475D01*
Y919649D01*
X547529D01*
Y919475D01*
G37*
G36*
G01X538312Y922679D02*
X538127Y922079D01*
X537097D01*
X536912Y922679D01*
Y922853D01*
X538312D01*
Y922679D01*
G37*
G36*
G01X541419Y920037D02*
X540807Y919897D01*
X540292Y920789D01*
X540719Y921249D01*
X540870Y921336D01*
X541570Y920124D01*
X541419Y920037D01*
G37*
G36*
G01X543829Y919475D02*
X543644Y918875D01*
X542614D01*
X542429Y919475D01*
Y919649D01*
X543829D01*
Y919475D01*
G37*
G36*
G01X547529D02*
X547344Y918875D01*
X546314D01*
X546129Y919475D01*
Y919649D01*
X547529D01*
Y919475D01*
G37*
G36*
G01X533179Y927479D02*
X533364Y928079D01*
X534394D01*
X534579Y927479D01*
Y927304D01*
X533179D01*
Y927479D01*
G37*
G36*
G01D02*
X533364Y928079D01*
X534394D01*
X534579Y927479D01*
Y927304D01*
X533179D01*
Y927479D01*
G37*
G36*
G01X542992Y926911D02*
X543604Y927051D01*
X544119Y926159D01*
X543692Y925699D01*
X543541Y925612D01*
X542841Y926824D01*
X542992Y926911D01*
G37*
G36*
G01X540612Y927479D02*
X540797Y928079D01*
X541827D01*
X542012Y927479D01*
Y927305D01*
X540612D01*
Y927479D01*
G37*
G36*
G01X536912D02*
X537097Y928079D01*
X538127D01*
X538312Y927479D01*
Y927305D01*
X536912D01*
Y927479D01*
G37*
G36*
G01X542992Y926911D02*
X543604Y927051D01*
X544119Y926159D01*
X543692Y925699D01*
X543541Y925612D01*
X542841Y926824D01*
X542992Y926911D01*
G37*
G36*
G01X540612Y927479D02*
X540797Y928079D01*
X541827D01*
X542012Y927479D01*
Y927305D01*
X540612D01*
Y927479D01*
G37*
G36*
G01X536912D02*
X537097Y928079D01*
X538127D01*
X538312Y927479D01*
Y927305D01*
X536912D01*
Y927479D01*
G37*
G36*
G01X535005Y924275D02*
X535190Y924875D01*
X536220D01*
X536405Y924275D01*
Y924100D01*
X535005D01*
Y924275D01*
G37*
G36*
G01D02*
X535190Y924875D01*
X536220D01*
X536405Y924275D01*
Y924100D01*
X535005D01*
Y924275D01*
G37*
G36*
G01X538695D02*
X538880Y924875D01*
X539910D01*
X540095Y924275D01*
Y924101D01*
X538695D01*
Y924275D01*
G37*
G36*
G01X541164Y923669D02*
X541776Y923809D01*
X542291Y922917D01*
X541864Y922457D01*
X541713Y922370D01*
X541013Y923582D01*
X541164Y923669D01*
G37*
G36*
G01X544279Y921071D02*
X544464Y921671D01*
X545494D01*
X545679Y921071D01*
Y920896D01*
X544279D01*
Y921071D01*
G37*
G36*
G01X538695Y924275D02*
X538880Y924875D01*
X539910D01*
X540095Y924275D01*
Y924101D01*
X538695D01*
Y924275D01*
G37*
G36*
G01X541164Y923669D02*
X541776Y923809D01*
X542291Y922917D01*
X541864Y922457D01*
X541713Y922370D01*
X541013Y923582D01*
X541164Y923669D01*
G37*
G36*
G01X544279Y921071D02*
X544464Y921671D01*
X545494D01*
X545679Y921071D01*
Y920896D01*
X544279D01*
Y921071D01*
G37*
G36*
G01X536405Y925883D02*
X536220Y925283D01*
X535190D01*
X535005Y925883D01*
Y926058D01*
X536405D01*
Y925883D01*
G37*
G36*
G01D02*
X536220Y925283D01*
X535190D01*
X535005Y925883D01*
Y926058D01*
X536405D01*
Y925883D01*
G37*
G36*
G01X543243Y923285D02*
X542631Y923145D01*
X542116Y924037D01*
X542543Y924497D01*
X542694Y924584D01*
X543394Y923372D01*
X543243Y923285D01*
G37*
G36*
G01X540095Y925883D02*
X539910Y925283D01*
X538880D01*
X538695Y925883D01*
Y926057D01*
X540095D01*
Y925883D01*
G37*
G36*
G01X545712Y922679D02*
X545527Y922079D01*
X544497D01*
X544312Y922679D01*
Y922853D01*
X545712D01*
Y922679D01*
G37*
G36*
G01X543243Y923285D02*
X542631Y923145D01*
X542116Y924037D01*
X542543Y924497D01*
X542694Y924584D01*
X543394Y923372D01*
X543243Y923285D01*
G37*
G36*
G01X540095Y925883D02*
X539910Y925283D01*
X538880D01*
X538695Y925883D01*
Y926057D01*
X540095D01*
Y925883D01*
G37*
G36*
G01X545712Y922679D02*
X545527Y922079D01*
X544497D01*
X544312Y922679D01*
Y922853D01*
X545712D01*
Y922679D01*
G37*
G36*
G01X534579Y948313D02*
X534394Y947713D01*
X533364D01*
X533179Y948313D01*
Y948488D01*
X534579D01*
Y948313D01*
G37*
G36*
G01D02*
X534394Y947713D01*
X533364D01*
X533179Y948313D01*
Y948488D01*
X534579D01*
Y948313D01*
G37*
G36*
G01X538279D02*
X538094Y947713D01*
X537064D01*
X536879Y948313D01*
Y948488D01*
X538279D01*
Y948313D01*
G37*
G36*
G01X541979D02*
X541794Y947713D01*
X540764D01*
X540579Y948313D01*
Y948488D01*
X541979D01*
Y948313D01*
G37*
G36*
G01X545679D02*
X545494Y947713D01*
X544464D01*
X544279Y948313D01*
Y948488D01*
X545679D01*
Y948313D01*
G37*
G36*
G01X538279D02*
X538094Y947713D01*
X537064D01*
X536879Y948313D01*
Y948488D01*
X538279D01*
Y948313D01*
G37*
G36*
G01X541979D02*
X541794Y947713D01*
X540764D01*
X540579Y948313D01*
Y948488D01*
X541979D01*
Y948313D01*
G37*
G36*
G01X545679D02*
X545494Y947713D01*
X544464D01*
X544279Y948313D01*
Y948488D01*
X545679D01*
Y948313D01*
G37*
G36*
G01X533179Y940295D02*
X533364Y940895D01*
X534394D01*
X534579Y940295D01*
Y940121D01*
X533179D01*
Y940295D01*
G37*
G36*
G01D02*
X533364Y940895D01*
X534394D01*
X534579Y940295D01*
Y940121D01*
X533179D01*
Y940295D01*
G37*
G36*
G01X540579D02*
X540764Y940895D01*
X541794D01*
X541979Y940295D01*
Y940121D01*
X540579D01*
Y940295D01*
G37*
G36*
G01X536879D02*
X537064Y940895D01*
X538094D01*
X538279Y940295D01*
Y940121D01*
X536879D01*
Y940295D01*
G37*
G36*
G01X544279D02*
X544464Y940895D01*
X545494D01*
X545679Y940295D01*
Y940121D01*
X544279D01*
Y940295D01*
G37*
G36*
G01X540579D02*
X540764Y940895D01*
X541794D01*
X541979Y940295D01*
Y940121D01*
X540579D01*
Y940295D01*
G37*
G36*
G01X536879D02*
X537064Y940895D01*
X538094D01*
X538279Y940295D01*
Y940121D01*
X536879D01*
Y940295D01*
G37*
G36*
G01X544279D02*
X544464Y940895D01*
X545494D01*
X545679Y940295D01*
Y940121D01*
X544279D01*
Y940295D01*
G37*
G36*
G01X535029Y937091D02*
X535214Y937691D01*
X536244D01*
X536429Y937091D01*
Y936917D01*
X535029D01*
Y937091D01*
G37*
G36*
G01D02*
X535214Y937691D01*
X536244D01*
X536429Y937091D01*
Y936917D01*
X535029D01*
Y937091D01*
G37*
G36*
G01X542429D02*
X542614Y937691D01*
X543644D01*
X543829Y937091D01*
Y936917D01*
X542429D01*
Y937091D01*
G37*
G36*
G01X538729D02*
X538914Y937691D01*
X539944D01*
X540129Y937091D01*
Y936917D01*
X538729D01*
Y937091D01*
G37*
G36*
G01X542429D02*
X542614Y937691D01*
X543644D01*
X543829Y937091D01*
Y936917D01*
X542429D01*
Y937091D01*
G37*
G36*
G01X538729D02*
X538914Y937691D01*
X539944D01*
X540129Y937091D01*
Y936917D01*
X538729D01*
Y937091D01*
G37*
G36*
G01X536429Y938701D02*
X536244Y938101D01*
X535214D01*
X535029Y938701D01*
Y938875D01*
X536429D01*
Y938701D01*
G37*
G36*
G01D02*
X536244Y938101D01*
X535214D01*
X535029Y938701D01*
Y938875D01*
X536429D01*
Y938701D01*
G37*
G36*
G01X540129D02*
X539944Y938101D01*
X538914D01*
X538729Y938701D01*
Y938875D01*
X540129D01*
Y938701D01*
G37*
G36*
G01X543829D02*
X543644Y938101D01*
X542614D01*
X542429Y938701D01*
Y938875D01*
X543829D01*
Y938701D01*
G37*
G36*
G01X547529D02*
X547344Y938101D01*
X546314D01*
X546129Y938701D01*
Y938875D01*
X547529D01*
Y938701D01*
G37*
G36*
G01X540129D02*
X539944Y938101D01*
X538914D01*
X538729Y938701D01*
Y938875D01*
X540129D01*
Y938701D01*
G37*
G36*
G01X543829D02*
X543644Y938101D01*
X542614D01*
X542429Y938701D01*
Y938875D01*
X543829D01*
Y938701D01*
G37*
G36*
G01X547529D02*
X547344Y938101D01*
X546314D01*
X546129Y938701D01*
Y938875D01*
X547529D01*
Y938701D01*
G37*
G36*
G01X534579Y935495D02*
X534394Y934895D01*
X533364D01*
X533179Y935495D01*
Y935670D01*
X534579D01*
Y935495D01*
G37*
G36*
G01D02*
X534394Y934895D01*
X533364D01*
X533179Y935495D01*
Y935670D01*
X534579D01*
Y935495D01*
G37*
G36*
G01X541979D02*
X541794Y934895D01*
X540764D01*
X540579Y935495D01*
Y935670D01*
X541979D01*
Y935495D01*
G37*
G36*
G01X538279D02*
X538094Y934895D01*
X537064D01*
X536879Y935495D01*
Y935670D01*
X538279D01*
Y935495D01*
G37*
G36*
G01X545679D02*
X545494Y934895D01*
X544464D01*
X544279Y935495D01*
Y935670D01*
X545679D01*
Y935495D01*
G37*
G36*
G01X541979D02*
X541794Y934895D01*
X540764D01*
X540579Y935495D01*
Y935670D01*
X541979D01*
Y935495D01*
G37*
G36*
G01X538279D02*
X538094Y934895D01*
X537064D01*
X536879Y935495D01*
Y935670D01*
X538279D01*
Y935495D01*
G37*
G36*
G01X545679D02*
X545494Y934895D01*
X544464D01*
X544279Y935495D01*
Y935670D01*
X545679D01*
Y935495D01*
G37*
G36*
G01X533212Y933889D02*
X533397Y934489D01*
X534427D01*
X534612Y933889D01*
Y933714D01*
X533212D01*
Y933889D01*
G37*
G36*
G01D02*
X533397Y934489D01*
X534427D01*
X534612Y933889D01*
Y933714D01*
X533212D01*
Y933889D01*
G37*
G36*
G01X536912D02*
X537097Y934489D01*
X538127D01*
X538312Y933889D01*
Y933714D01*
X536912D01*
Y933889D01*
G37*
G36*
G01X540612D02*
X540797Y934489D01*
X541827D01*
X542012Y933889D01*
Y933714D01*
X540612D01*
Y933889D01*
G37*
G36*
G01X544312D02*
X544497Y934489D01*
X545527D01*
X545712Y933889D01*
Y933714D01*
X544312D01*
Y933889D01*
G37*
G36*
G01X536912D02*
X537097Y934489D01*
X538127D01*
X538312Y933889D01*
Y933714D01*
X536912D01*
Y933889D01*
G37*
G36*
G01X540612D02*
X540797Y934489D01*
X541827D01*
X542012Y933889D01*
Y933714D01*
X540612D01*
Y933889D01*
G37*
G36*
G01X544312D02*
X544497Y934489D01*
X545527D01*
X545712Y933889D01*
Y933714D01*
X544312D01*
Y933889D01*
G37*
G36*
G01X536416Y945109D02*
X536231Y944509D01*
X535201D01*
X535016Y945109D01*
Y945283D01*
X536416D01*
Y945109D01*
G37*
G36*
G01D02*
X536231Y944509D01*
X535201D01*
X535016Y945109D01*
Y945283D01*
X536416D01*
Y945109D01*
G37*
G36*
G01X540095Y945107D02*
X539910Y944507D01*
X538880D01*
X538695Y945107D01*
Y945282D01*
X540095D01*
Y945107D01*
G37*
G36*
G01X543795D02*
X543610Y944507D01*
X542580D01*
X542395Y945107D01*
Y945282D01*
X543795D01*
Y945107D01*
G37*
G36*
G01X540095D02*
X539910Y944507D01*
X538880D01*
X538695Y945107D01*
Y945282D01*
X540095D01*
Y945107D01*
G37*
G36*
G01X543795D02*
X543610Y944507D01*
X542580D01*
X542395Y945107D01*
Y945282D01*
X543795D01*
Y945107D01*
G37*
G36*
G01X547495D02*
X547310Y944507D01*
X546280D01*
X546095Y945107D01*
Y945282D01*
X547495D01*
Y945107D01*
G37*
G36*
G01D02*
X547310Y944507D01*
X546280D01*
X546095Y945107D01*
Y945282D01*
X547495D01*
Y945107D01*
G37*
G36*
G01X535029Y943499D02*
X535214Y944099D01*
X536244D01*
X536429Y943499D01*
Y943324D01*
X535029D01*
Y943499D01*
G37*
G36*
G01D02*
X535214Y944099D01*
X536244D01*
X536429Y943499D01*
Y943324D01*
X535029D01*
Y943499D01*
G37*
G36*
G01X546095Y943501D02*
X546280Y944101D01*
X547310D01*
X547495Y943501D01*
Y943326D01*
X546095D01*
Y943501D01*
G37*
G36*
G01X542395D02*
X542580Y944101D01*
X543610D01*
X543795Y943501D01*
Y943326D01*
X542395D01*
Y943501D01*
G37*
G36*
G01X538695D02*
X538880Y944101D01*
X539910D01*
X540095Y943501D01*
Y943326D01*
X538695D01*
Y943501D01*
G37*
G36*
G01X546095D02*
X546280Y944101D01*
X547310D01*
X547495Y943501D01*
Y943326D01*
X546095D01*
Y943501D01*
G37*
G36*
G01X542395D02*
X542580Y944101D01*
X543610D01*
X543795Y943501D01*
Y943326D01*
X542395D01*
Y943501D01*
G37*
G36*
G01X538695D02*
X538880Y944101D01*
X539910D01*
X540095Y943501D01*
Y943326D01*
X538695D01*
Y943501D01*
G37*
G36*
G01X533179Y946705D02*
X533364Y947305D01*
X534394D01*
X534579Y946705D01*
Y946530D01*
X533179D01*
Y946705D01*
G37*
G36*
G01D02*
X533364Y947305D01*
X534394D01*
X534579Y946705D01*
Y946530D01*
X533179D01*
Y946705D01*
G37*
G36*
G01X536912D02*
X537097Y947305D01*
X538127D01*
X538312Y946705D01*
Y946531D01*
X536912D01*
Y946705D01*
G37*
G36*
G01X540612D02*
X540797Y947305D01*
X541827D01*
X542012Y946705D01*
Y946531D01*
X540612D01*
Y946705D01*
G37*
G36*
G01X536912D02*
X537097Y947305D01*
X538127D01*
X538312Y946705D01*
Y946531D01*
X536912D01*
Y946705D01*
G37*
G36*
G01X540612D02*
X540797Y947305D01*
X541827D01*
X542012Y946705D01*
Y946531D01*
X540612D01*
Y946705D01*
G37*
G36*
G01X544312D02*
X544497Y947305D01*
X545527D01*
X545712Y946705D01*
Y946531D01*
X544312D01*
Y946705D01*
G37*
G36*
G01D02*
X544497Y947305D01*
X545527D01*
X545712Y946705D01*
Y946531D01*
X544312D01*
Y946705D01*
G37*
G36*
G01X534579Y941905D02*
X534394Y941305D01*
X533364D01*
X533179Y941905D01*
Y942079D01*
X534579D01*
Y941905D01*
G37*
G36*
G01D02*
X534394Y941305D01*
X533364D01*
X533179Y941905D01*
Y942079D01*
X534579D01*
Y941905D01*
G37*
G36*
G01X545712Y941903D02*
X545527Y941303D01*
X544497D01*
X544312Y941903D01*
Y942078D01*
X545712D01*
Y941903D01*
G37*
G36*
G01X542012D02*
X541827Y941303D01*
X540797D01*
X540612Y941903D01*
Y942078D01*
X542012D01*
Y941903D01*
G37*
G36*
G01X538312D02*
X538127Y941303D01*
X537097D01*
X536912Y941903D01*
Y942078D01*
X538312D01*
Y941903D01*
G37*
G36*
G01X545712D02*
X545527Y941303D01*
X544497D01*
X544312Y941903D01*
Y942078D01*
X545712D01*
Y941903D01*
G37*
G36*
G01X542012D02*
X541827Y941303D01*
X540797D01*
X540612Y941903D01*
Y942078D01*
X542012D01*
Y941903D01*
G37*
G36*
G01X538312D02*
X538127Y941303D01*
X537097D01*
X536912Y941903D01*
Y942078D01*
X538312D01*
Y941903D01*
G37*
G36*
G01X533179Y953113D02*
X533364Y953713D01*
X534394D01*
X534579Y953113D01*
Y952938D01*
X533179D01*
Y953113D01*
G37*
G36*
G01D02*
X533364Y953713D01*
X534394D01*
X534579Y953113D01*
Y952938D01*
X533179D01*
Y953113D01*
G37*
G36*
G01X544279D02*
X544464Y953713D01*
X545494D01*
X545679Y953113D01*
Y952938D01*
X544279D01*
Y953113D01*
G37*
G36*
G01X540579D02*
X540764Y953713D01*
X541794D01*
X541979Y953113D01*
Y952938D01*
X540579D01*
Y953113D01*
G37*
G36*
G01X536879D02*
X537064Y953713D01*
X538094D01*
X538279Y953113D01*
Y952938D01*
X536879D01*
Y953113D01*
G37*
G36*
G01X544279D02*
X544464Y953713D01*
X545494D01*
X545679Y953113D01*
Y952938D01*
X544279D01*
Y953113D01*
G37*
G36*
G01X540579D02*
X540764Y953713D01*
X541794D01*
X541979Y953113D01*
Y952938D01*
X540579D01*
Y953113D01*
G37*
G36*
G01X536879D02*
X537064Y953713D01*
X538094D01*
X538279Y953113D01*
Y952938D01*
X536879D01*
Y953113D01*
G37*
G36*
G01X535029Y949909D02*
X535214Y950509D01*
X536244D01*
X536429Y949909D01*
Y949734D01*
X535029D01*
Y949909D01*
G37*
G36*
G01D02*
X535214Y950509D01*
X536244D01*
X536429Y949909D01*
Y949734D01*
X535029D01*
Y949909D01*
G37*
G36*
G01X542429D02*
X542614Y950509D01*
X543644D01*
X543829Y949909D01*
Y949734D01*
X542429D01*
Y949909D01*
G37*
G36*
G01X538729D02*
X538914Y950509D01*
X539944D01*
X540129Y949909D01*
Y949734D01*
X538729D01*
Y949909D01*
G37*
G36*
G01X542429D02*
X542614Y950509D01*
X543644D01*
X543829Y949909D01*
Y949734D01*
X542429D01*
Y949909D01*
G37*
G36*
G01X538729D02*
X538914Y950509D01*
X539944D01*
X540129Y949909D01*
Y949734D01*
X538729D01*
Y949909D01*
G37*
G36*
G01X536429Y951517D02*
X536244Y950917D01*
X535214D01*
X535029Y951517D01*
Y951692D01*
X536429D01*
Y951517D01*
G37*
G36*
G01D02*
X536244Y950917D01*
X535214D01*
X535029Y951517D01*
Y951692D01*
X536429D01*
Y951517D01*
G37*
G36*
G01X543829D02*
X543644Y950917D01*
X542614D01*
X542429Y951517D01*
Y951692D01*
X543829D01*
Y951517D01*
G37*
G36*
G01X540129D02*
X539944Y950917D01*
X538914D01*
X538729Y951517D01*
Y951692D01*
X540129D01*
Y951517D01*
G37*
G36*
G01X547529D02*
X547344Y950917D01*
X546314D01*
X546129Y951517D01*
Y951692D01*
X547529D01*
Y951517D01*
G37*
G36*
G01X543829D02*
X543644Y950917D01*
X542614D01*
X542429Y951517D01*
Y951692D01*
X543829D01*
Y951517D01*
G37*
G36*
G01X540129D02*
X539944Y950917D01*
X538914D01*
X538729Y951517D01*
Y951692D01*
X540129D01*
Y951517D01*
G37*
G36*
G01X547529D02*
X547344Y950917D01*
X546314D01*
X546129Y951517D01*
Y951692D01*
X547529D01*
Y951517D01*
G37*
G36*
G01X533179Y959521D02*
X533364Y960121D01*
X534394D01*
X534579Y959521D01*
Y959347D01*
X533179D01*
Y959521D01*
G37*
G36*
G01D02*
X533364Y960121D01*
X534394D01*
X534579Y959521D01*
Y959347D01*
X533179D01*
Y959521D01*
G37*
G36*
G01X536879D02*
X537064Y960121D01*
X538094D01*
X538279Y959521D01*
Y959347D01*
X536879D01*
Y959521D01*
G37*
G36*
G01D02*
X537064Y960121D01*
X538094D01*
X538279Y959521D01*
Y959347D01*
X536879D01*
Y959521D01*
G37*
G36*
G01X536429Y957927D02*
X536244Y957327D01*
X535214D01*
X535029Y957927D01*
Y958101D01*
X536429D01*
Y957927D01*
G37*
G36*
G01D02*
X536244Y957327D01*
X535214D01*
X535029Y957927D01*
Y958101D01*
X536429D01*
Y957927D01*
G37*
G36*
G01X535005Y962725D02*
X535190Y963325D01*
X536220D01*
X536405Y962725D01*
Y962551D01*
X535005D01*
Y962725D01*
G37*
G36*
G01D02*
X535190Y963325D01*
X536220D01*
X536405Y962725D01*
Y962551D01*
X535005D01*
Y962725D01*
G37*
G36*
G01X534579Y961131D02*
X534394Y960531D01*
X533364D01*
X533179Y961131D01*
Y961305D01*
X534579D01*
Y961131D01*
G37*
G36*
G01D02*
X534394Y960531D01*
X533364D01*
X533179Y961131D01*
Y961305D01*
X534579D01*
Y961131D01*
G37*
G36*
G01X535011Y1006897D02*
X534826Y1006297D01*
X533796D01*
X533611Y1006897D01*
Y1007072D01*
X535011D01*
Y1006897D01*
G37*
G36*
G01D02*
X534826Y1006297D01*
X533796D01*
X533611Y1006897D01*
Y1007072D01*
X535011D01*
Y1006897D01*
G37*
G36*
G01X538751Y1006895D02*
X538566Y1006295D01*
X537536D01*
X537351Y1006895D01*
Y1007070D01*
X538751D01*
Y1006895D01*
G37*
G36*
G01X542445D02*
X542260Y1006295D01*
X541230D01*
X541045Y1006895D01*
Y1007070D01*
X542445D01*
Y1006895D01*
G37*
G36*
G01X538751D02*
X538566Y1006295D01*
X537536D01*
X537351Y1006895D01*
Y1007070D01*
X538751D01*
Y1006895D01*
G37*
G36*
G01X542445D02*
X542260Y1006295D01*
X541230D01*
X541045Y1006895D01*
Y1007070D01*
X542445D01*
Y1006895D01*
G37*
G36*
G01X536861Y1003693D02*
X536676Y1003093D01*
X535646D01*
X535461Y1003693D01*
Y1003867D01*
X536861D01*
Y1003693D01*
G37*
G36*
G01D02*
X536676Y1003093D01*
X535646D01*
X535461Y1003693D01*
Y1003867D01*
X536861D01*
Y1003693D01*
G37*
G36*
G01X540528Y1003691D02*
X540343Y1003091D01*
X539313D01*
X539128Y1003691D01*
Y1003866D01*
X540528D01*
Y1003691D01*
G37*
G36*
G01X544228D02*
X544043Y1003091D01*
X543013D01*
X542828Y1003691D01*
Y1003866D01*
X544228D01*
Y1003691D01*
G37*
G36*
G01X540528D02*
X540343Y1003091D01*
X539313D01*
X539128Y1003691D01*
Y1003866D01*
X540528D01*
Y1003691D01*
G37*
G36*
G01X544228D02*
X544043Y1003091D01*
X543013D01*
X542828Y1003691D01*
Y1003866D01*
X544228D01*
Y1003691D01*
G37*
G36*
G01X535461Y1008493D02*
X535646Y1009093D01*
X536676D01*
X536861Y1008493D01*
Y1008318D01*
X535461D01*
Y1008493D01*
G37*
G36*
G01D02*
X535646Y1009093D01*
X536676D01*
X536861Y1008493D01*
Y1008318D01*
X535461D01*
Y1008493D01*
G37*
G36*
G01X542829D02*
X543014Y1009093D01*
X544044D01*
X544229Y1008493D01*
Y1008319D01*
X542829D01*
Y1008493D01*
G37*
G36*
G01X539128D02*
X539313Y1009093D01*
X540343D01*
X540528Y1008493D01*
Y1008319D01*
X539128D01*
Y1008493D01*
G37*
G36*
G01X542829D02*
X543014Y1009093D01*
X544044D01*
X544229Y1008493D01*
Y1008319D01*
X542829D01*
Y1008493D01*
G37*
G36*
G01X539128D02*
X539313Y1009093D01*
X540343D01*
X540528Y1008493D01*
Y1008319D01*
X539128D01*
Y1008493D01*
G37*
G36*
G01X533611Y1005289D02*
X533796Y1005889D01*
X534826D01*
X535011Y1005289D01*
Y1005114D01*
X533611D01*
Y1005289D01*
G37*
G36*
G01D02*
X533796Y1005889D01*
X534826D01*
X535011Y1005289D01*
Y1005114D01*
X533611D01*
Y1005289D01*
G37*
G36*
G01X544745D02*
X544930Y1005889D01*
X545960D01*
X546145Y1005289D01*
Y1005114D01*
X544745D01*
Y1005289D01*
G37*
G36*
G01X541045D02*
X541230Y1005889D01*
X542260D01*
X542445Y1005289D01*
Y1005114D01*
X541045D01*
Y1005289D01*
G37*
G36*
G01X537291D02*
X537476Y1005889D01*
X538506D01*
X538691Y1005289D01*
Y1005114D01*
X537291D01*
Y1005289D01*
G37*
G36*
G01X544745D02*
X544930Y1005889D01*
X545960D01*
X546145Y1005289D01*
Y1005114D01*
X544745D01*
Y1005289D01*
G37*
G36*
G01X541045D02*
X541230Y1005889D01*
X542260D01*
X542445Y1005289D01*
Y1005114D01*
X541045D01*
Y1005289D01*
G37*
G36*
G01X537291D02*
X537476Y1005889D01*
X538506D01*
X538691Y1005289D01*
Y1005114D01*
X537291D01*
Y1005289D01*
G37*
G36*
G01X547129Y1030345D02*
X547741Y1030485D01*
X548256Y1029593D01*
X547829Y1029133D01*
X547678Y1029046D01*
X546978Y1030258D01*
X547129Y1030345D01*
G37*
G36*
G01D02*
X547741Y1030485D01*
X548256Y1029593D01*
X547829Y1029133D01*
X547678Y1029046D01*
X546978Y1030258D01*
X547129Y1030345D01*
G37*
G36*
G01X535461Y1027719D02*
X535646Y1028319D01*
X536676D01*
X536861Y1027719D01*
Y1027544D01*
X535461D01*
Y1027719D01*
G37*
G36*
G01D02*
X535646Y1028319D01*
X536676D01*
X536861Y1027719D01*
Y1027544D01*
X535461D01*
Y1027719D01*
G37*
G36*
G01X545271Y1027156D02*
X545883Y1027296D01*
X546398Y1026404D01*
X545971Y1025944D01*
X545820Y1025857D01*
X545120Y1027069D01*
X545271Y1027156D01*
G37*
G36*
G01X542861Y1027719D02*
X543046Y1028319D01*
X544076D01*
X544261Y1027719D01*
Y1027544D01*
X542861D01*
Y1027719D01*
G37*
G36*
G01X539161D02*
X539346Y1028319D01*
X540376D01*
X540561Y1027719D01*
Y1027544D01*
X539161D01*
Y1027719D01*
G37*
G36*
G01X545271Y1027156D02*
X545883Y1027296D01*
X546398Y1026404D01*
X545971Y1025944D01*
X545820Y1025857D01*
X545120Y1027069D01*
X545271Y1027156D01*
G37*
G36*
G01X542861Y1027719D02*
X543046Y1028319D01*
X544076D01*
X544261Y1027719D01*
Y1027544D01*
X542861D01*
Y1027719D01*
G37*
G36*
G01X539161D02*
X539346Y1028319D01*
X540376D01*
X540561Y1027719D01*
Y1027544D01*
X539161D01*
Y1027719D01*
G37*
G36*
G01X536861Y1029327D02*
X536676Y1028727D01*
X535646D01*
X535461Y1029327D01*
Y1029502D01*
X536861D01*
Y1029327D01*
G37*
G36*
G01D02*
X536676Y1028727D01*
X535646D01*
X535461Y1029327D01*
Y1029502D01*
X536861D01*
Y1029327D01*
G37*
G36*
G01X547401Y1026685D02*
X546789Y1026545D01*
X546274Y1027437D01*
X546701Y1027897D01*
X546852Y1027984D01*
X547552Y1026772D01*
X547401Y1026685D01*
G37*
G36*
G01X540561Y1029327D02*
X540376Y1028727D01*
X539346D01*
X539161Y1029327D01*
Y1029502D01*
X540561D01*
Y1029327D01*
G37*
G36*
G01X544261D02*
X544076Y1028727D01*
X543046D01*
X542861Y1029327D01*
Y1029502D01*
X544261D01*
Y1029327D01*
G37*
G36*
G01X547401Y1026685D02*
X546789Y1026545D01*
X546274Y1027437D01*
X546701Y1027897D01*
X546852Y1027984D01*
X547552Y1026772D01*
X547401Y1026685D01*
G37*
G36*
G01X540561Y1029327D02*
X540376Y1028727D01*
X539346D01*
X539161Y1029327D01*
Y1029502D01*
X540561D01*
Y1029327D01*
G37*
G36*
G01X544261D02*
X544076Y1028727D01*
X543046D01*
X542861Y1029327D01*
Y1029502D01*
X544261D01*
Y1029327D01*
G37*
G36*
G01X535011Y1026123D02*
X534826Y1025523D01*
X533796D01*
X533611Y1026123D01*
Y1026297D01*
X535011D01*
Y1026123D01*
G37*
G36*
G01D02*
X534826Y1025523D01*
X533796D01*
X533611Y1026123D01*
Y1026297D01*
X535011D01*
Y1026123D01*
G37*
G36*
G01X542411D02*
X542226Y1025523D01*
X541196D01*
X541011Y1026123D01*
Y1026297D01*
X542411D01*
Y1026123D01*
G37*
G36*
G01X538711D02*
X538526Y1025523D01*
X537496D01*
X537311Y1026123D01*
Y1026297D01*
X538711D01*
Y1026123D01*
G37*
G36*
G01X542411D02*
X542226Y1025523D01*
X541196D01*
X541011Y1026123D01*
Y1026297D01*
X542411D01*
Y1026123D01*
G37*
G36*
G01X538711D02*
X538526Y1025523D01*
X537496D01*
X537311Y1026123D01*
Y1026297D01*
X538711D01*
Y1026123D01*
G37*
G36*
G01X549218Y1029946D02*
X548606Y1029806D01*
X548091Y1030698D01*
X548518Y1031158D01*
X548669Y1031245D01*
X549369Y1030033D01*
X549218Y1029946D01*
G37*
G36*
G01D02*
X548606Y1029806D01*
X548091Y1030698D01*
X548518Y1031158D01*
X548669Y1031245D01*
X549369Y1030033D01*
X549218Y1029946D01*
G37*
G36*
G01X533645Y1043741D02*
X533830Y1044341D01*
X534860D01*
X535045Y1043741D01*
Y1043566D01*
X533645D01*
Y1043741D01*
G37*
G36*
G01D02*
X533830Y1044341D01*
X534860D01*
X535045Y1043741D01*
Y1043566D01*
X533645D01*
Y1043741D01*
G37*
G36*
G01X544745D02*
X544930Y1044341D01*
X545960D01*
X546145Y1043741D01*
Y1043566D01*
X544745D01*
Y1043741D01*
G37*
G36*
G01X541045D02*
X541230Y1044341D01*
X542260D01*
X542445Y1043741D01*
Y1043566D01*
X541045D01*
Y1043741D01*
G37*
G36*
G01X537345D02*
X537530Y1044341D01*
X538560D01*
X538745Y1043741D01*
Y1043566D01*
X537345D01*
Y1043741D01*
G37*
G36*
G01X544745D02*
X544930Y1044341D01*
X545960D01*
X546145Y1043741D01*
Y1043566D01*
X544745D01*
Y1043741D01*
G37*
G36*
G01X541045D02*
X541230Y1044341D01*
X542260D01*
X542445Y1043741D01*
Y1043566D01*
X541045D01*
Y1043741D01*
G37*
G36*
G01X537345D02*
X537530Y1044341D01*
X538560D01*
X538745Y1043741D01*
Y1043566D01*
X537345D01*
Y1043741D01*
G37*
G36*
G01X535461Y1040535D02*
X535646Y1041135D01*
X536676D01*
X536861Y1040535D01*
Y1040361D01*
X535461D01*
Y1040535D01*
G37*
G36*
G01D02*
X535646Y1041135D01*
X536676D01*
X536861Y1040535D01*
Y1040361D01*
X535461D01*
Y1040535D01*
G37*
G36*
G01X546528Y1040537D02*
X546713Y1041137D01*
X547743D01*
X547928Y1040537D01*
Y1040362D01*
X546528D01*
Y1040537D01*
G37*
G36*
G01X542828D02*
X543013Y1041137D01*
X544043D01*
X544228Y1040537D01*
Y1040362D01*
X542828D01*
Y1040537D01*
G37*
G36*
G01X539161Y1040535D02*
X539346Y1041135D01*
X540376D01*
X540561Y1040535D01*
Y1040361D01*
X539161D01*
Y1040535D01*
G37*
G36*
G01X546528Y1040537D02*
X546713Y1041137D01*
X547743D01*
X547928Y1040537D01*
Y1040362D01*
X546528D01*
Y1040537D01*
G37*
G36*
G01X542828D02*
X543013Y1041137D01*
X544043D01*
X544228Y1040537D01*
Y1040362D01*
X542828D01*
Y1040537D01*
G37*
G36*
G01X539161Y1040535D02*
X539346Y1041135D01*
X540376D01*
X540561Y1040535D01*
Y1040361D01*
X539161D01*
Y1040535D01*
G37*
G36*
G01X536828Y1042143D02*
X536643Y1041543D01*
X535613D01*
X535428Y1042143D01*
Y1042318D01*
X536828D01*
Y1042143D01*
G37*
G36*
G01D02*
X536643Y1041543D01*
X535613D01*
X535428Y1042143D01*
Y1042318D01*
X536828D01*
Y1042143D01*
G37*
G36*
G01X547928D02*
X547743Y1041543D01*
X546713D01*
X546528Y1042143D01*
Y1042318D01*
X547928D01*
Y1042143D01*
G37*
G36*
G01X544228D02*
X544043Y1041543D01*
X543013D01*
X542828Y1042143D01*
Y1042318D01*
X544228D01*
Y1042143D01*
G37*
G36*
G01X540528D02*
X540343Y1041543D01*
X539313D01*
X539128Y1042143D01*
Y1042318D01*
X540528D01*
Y1042143D01*
G37*
G36*
G01X547928D02*
X547743Y1041543D01*
X546713D01*
X546528Y1042143D01*
Y1042318D01*
X547928D01*
Y1042143D01*
G37*
G36*
G01X544228D02*
X544043Y1041543D01*
X543013D01*
X542828Y1042143D01*
Y1042318D01*
X544228D01*
Y1042143D01*
G37*
G36*
G01X540528D02*
X540343Y1041543D01*
X539313D01*
X539128Y1042143D01*
Y1042318D01*
X540528D01*
Y1042143D01*
G37*
G36*
G01X535011Y1038941D02*
X534826Y1038341D01*
X533796D01*
X533611Y1038941D01*
Y1039115D01*
X535011D01*
Y1038941D01*
G37*
G36*
G01D02*
X534826Y1038341D01*
X533796D01*
X533611Y1038941D01*
Y1039115D01*
X535011D01*
Y1038941D01*
G37*
G36*
G01X546145Y1038939D02*
X545960Y1038339D01*
X544930D01*
X544745Y1038939D01*
Y1039114D01*
X546145D01*
Y1038939D01*
G37*
G36*
G01X542435D02*
X542250Y1038339D01*
X541220D01*
X541035Y1038939D01*
Y1039114D01*
X542435D01*
Y1038939D01*
G37*
G36*
G01X538711Y1038941D02*
X538526Y1038341D01*
X537496D01*
X537311Y1038941D01*
Y1039115D01*
X538711D01*
Y1038941D01*
G37*
G36*
G01X546145Y1038939D02*
X545960Y1038339D01*
X544930D01*
X544745Y1038939D01*
Y1039114D01*
X546145D01*
Y1038939D01*
G37*
G36*
G01X542435D02*
X542250Y1038339D01*
X541220D01*
X541035Y1038939D01*
Y1039114D01*
X542435D01*
Y1038939D01*
G37*
G36*
G01X538711Y1038941D02*
X538526Y1038341D01*
X537496D01*
X537311Y1038941D01*
Y1039115D01*
X538711D01*
Y1038941D01*
G37*
G36*
G01X533611Y1030923D02*
X533796Y1031523D01*
X534826D01*
X535011Y1030923D01*
Y1030748D01*
X533611D01*
Y1030923D01*
G37*
G36*
G01D02*
X533796Y1031523D01*
X534826D01*
X535011Y1030923D01*
Y1030748D01*
X533611D01*
Y1030923D01*
G37*
G36*
G01X544711D02*
X544896Y1031523D01*
X545926D01*
X546111Y1030923D01*
Y1030748D01*
X544711D01*
Y1030923D01*
G37*
G36*
G01X541011D02*
X541196Y1031523D01*
X542226D01*
X542411Y1030923D01*
Y1030748D01*
X541011D01*
Y1030923D01*
G37*
G36*
G01X537311D02*
X537496Y1031523D01*
X538526D01*
X538711Y1030923D01*
Y1030748D01*
X537311D01*
Y1030923D01*
G37*
G36*
G01X544711D02*
X544896Y1031523D01*
X545926D01*
X546111Y1030923D01*
Y1030748D01*
X544711D01*
Y1030923D01*
G37*
G36*
G01X541011D02*
X541196Y1031523D01*
X542226D01*
X542411Y1030923D01*
Y1030748D01*
X541011D01*
Y1030923D01*
G37*
G36*
G01X537311D02*
X537496Y1031523D01*
X538526D01*
X538711Y1030923D01*
Y1030748D01*
X537311D01*
Y1030923D01*
G37*
G36*
G01X535428Y1046945D02*
X535613Y1047545D01*
X536643D01*
X536828Y1046945D01*
Y1046771D01*
X535428D01*
Y1046945D01*
G37*
G36*
G01D02*
X535613Y1047545D01*
X536643D01*
X536828Y1046945D01*
Y1046771D01*
X535428D01*
Y1046945D01*
G37*
G36*
G01X546528D02*
X546713Y1047545D01*
X547743D01*
X547928Y1046945D01*
Y1046771D01*
X546528D01*
Y1046945D01*
G37*
G36*
G01X542828D02*
X543013Y1047545D01*
X544043D01*
X544228Y1046945D01*
Y1046771D01*
X542828D01*
Y1046945D01*
G37*
G36*
G01X539128D02*
X539313Y1047545D01*
X540343D01*
X540528Y1046945D01*
Y1046771D01*
X539128D01*
Y1046945D01*
G37*
G36*
G01X546528D02*
X546713Y1047545D01*
X547743D01*
X547928Y1046945D01*
Y1046771D01*
X546528D01*
Y1046945D01*
G37*
G36*
G01X542828D02*
X543013Y1047545D01*
X544043D01*
X544228Y1046945D01*
Y1046771D01*
X542828D01*
Y1046945D01*
G37*
G36*
G01X539128D02*
X539313Y1047545D01*
X540343D01*
X540528Y1046945D01*
Y1046771D01*
X539128D01*
Y1046945D01*
G37*
G36*
G01X535045Y1045347D02*
X534860Y1044747D01*
X533830D01*
X533645Y1045347D01*
Y1045522D01*
X535045D01*
Y1045347D01*
G37*
G36*
G01D02*
X534860Y1044747D01*
X533830D01*
X533645Y1045347D01*
Y1045522D01*
X535045D01*
Y1045347D01*
G37*
G36*
G01X546145D02*
X545960Y1044747D01*
X544930D01*
X544745Y1045347D01*
Y1045522D01*
X546145D01*
Y1045347D01*
G37*
G36*
G01X549845D02*
X549660Y1044747D01*
X548630D01*
X548445Y1045347D01*
Y1045522D01*
X549845D01*
Y1045347D01*
G37*
G36*
G01X538745D02*
X538560Y1044747D01*
X537530D01*
X537345Y1045347D01*
Y1045522D01*
X538745D01*
Y1045347D01*
G37*
G36*
G01X542445D02*
X542260Y1044747D01*
X541230D01*
X541045Y1045347D01*
Y1045522D01*
X542445D01*
Y1045347D01*
G37*
G36*
G01X546145D02*
X545960Y1044747D01*
X544930D01*
X544745Y1045347D01*
Y1045522D01*
X546145D01*
Y1045347D01*
G37*
G36*
G01X549845D02*
X549660Y1044747D01*
X548630D01*
X548445Y1045347D01*
Y1045522D01*
X549845D01*
Y1045347D01*
G37*
G36*
G01X538745D02*
X538560Y1044747D01*
X537530D01*
X537345Y1045347D01*
Y1045522D01*
X538745D01*
Y1045347D01*
G37*
G36*
G01X542445D02*
X542260Y1044747D01*
X541230D01*
X541045Y1045347D01*
Y1045522D01*
X542445D01*
Y1045347D01*
G37*
G36*
G01X536861Y1035735D02*
X536676Y1035135D01*
X535646D01*
X535461Y1035735D01*
Y1035910D01*
X536861D01*
Y1035735D01*
G37*
G36*
G01D02*
X536676Y1035135D01*
X535646D01*
X535461Y1035735D01*
Y1035910D01*
X536861D01*
Y1035735D01*
G37*
G36*
G01X547995D02*
X547810Y1035135D01*
X546780D01*
X546595Y1035735D01*
Y1035909D01*
X547995D01*
Y1035735D01*
G37*
G36*
G01X540561D02*
X540376Y1035135D01*
X539346D01*
X539161Y1035735D01*
Y1035910D01*
X540561D01*
Y1035735D01*
G37*
G36*
G01X544285D02*
X544100Y1035135D01*
X543070D01*
X542885Y1035735D01*
Y1035909D01*
X544285D01*
Y1035735D01*
G37*
G36*
G01X547995D02*
X547810Y1035135D01*
X546780D01*
X546595Y1035735D01*
Y1035909D01*
X547995D01*
Y1035735D01*
G37*
G36*
G01X540561D02*
X540376Y1035135D01*
X539346D01*
X539161Y1035735D01*
Y1035910D01*
X540561D01*
Y1035735D01*
G37*
G36*
G01X544285D02*
X544100Y1035135D01*
X543070D01*
X542885Y1035735D01*
Y1035909D01*
X544285D01*
Y1035735D01*
G37*
G36*
G01X535461Y1034127D02*
X535646Y1034727D01*
X536676D01*
X536861Y1034127D01*
Y1033952D01*
X535461D01*
Y1034127D01*
G37*
G36*
G01D02*
X535646Y1034727D01*
X536676D01*
X536861Y1034127D01*
Y1033952D01*
X535461D01*
Y1034127D01*
G37*
G36*
G01X548975Y1033559D02*
X549587Y1033699D01*
X550102Y1032807D01*
X549675Y1032347D01*
X549524Y1032260D01*
X548824Y1033472D01*
X548975Y1033559D01*
G37*
G36*
G01X546595Y1034127D02*
X546780Y1034727D01*
X547810D01*
X547995Y1034127D01*
Y1033953D01*
X546595D01*
Y1034127D01*
G37*
G36*
G01X542885D02*
X543070Y1034727D01*
X544100D01*
X544285Y1034127D01*
Y1033953D01*
X542885D01*
Y1034127D01*
G37*
G36*
G01X539161D02*
X539346Y1034727D01*
X540376D01*
X540561Y1034127D01*
Y1033952D01*
X539161D01*
Y1034127D01*
G37*
G36*
G01X548975Y1033559D02*
X549587Y1033699D01*
X550102Y1032807D01*
X549675Y1032347D01*
X549524Y1032260D01*
X548824Y1033472D01*
X548975Y1033559D01*
G37*
G36*
G01X546595Y1034127D02*
X546780Y1034727D01*
X547810D01*
X547995Y1034127D01*
Y1033953D01*
X546595D01*
Y1034127D01*
G37*
G36*
G01X542885D02*
X543070Y1034727D01*
X544100D01*
X544285Y1034127D01*
Y1033953D01*
X542885D01*
Y1034127D01*
G37*
G36*
G01X539161D02*
X539346Y1034727D01*
X540376D01*
X540561Y1034127D01*
Y1033952D01*
X539161D01*
Y1034127D01*
G37*
G36*
G01X533611Y1037329D02*
X533796Y1037929D01*
X534826D01*
X535011Y1037329D01*
Y1037154D01*
X533611D01*
Y1037329D01*
G37*
G36*
G01D02*
X533796Y1037929D01*
X534826D01*
X535011Y1037329D01*
Y1037154D01*
X533611D01*
Y1037329D01*
G37*
G36*
G01X544678Y1037333D02*
X544863Y1037933D01*
X545893D01*
X546078Y1037333D01*
Y1037158D01*
X544678D01*
Y1037333D01*
G37*
G36*
G01X548411Y1037329D02*
X548596Y1037929D01*
X549626D01*
X549811Y1037329D01*
Y1037155D01*
X548411D01*
Y1037329D01*
G37*
G36*
G01X537311Y1037331D02*
X537496Y1037931D01*
X538526D01*
X538711Y1037331D01*
Y1037157D01*
X537311D01*
Y1037331D01*
G37*
G36*
G01X541011D02*
X541196Y1037931D01*
X542226D01*
X542411Y1037331D01*
Y1037157D01*
X541011D01*
Y1037331D01*
G37*
G36*
G01X544678Y1037333D02*
X544863Y1037933D01*
X545893D01*
X546078Y1037333D01*
Y1037158D01*
X544678D01*
Y1037333D01*
G37*
G36*
G01X548411Y1037329D02*
X548596Y1037929D01*
X549626D01*
X549811Y1037329D01*
Y1037155D01*
X548411D01*
Y1037329D01*
G37*
G36*
G01X537311Y1037331D02*
X537496Y1037931D01*
X538526D01*
X538711Y1037331D01*
Y1037157D01*
X537311D01*
Y1037331D01*
G37*
G36*
G01X541011D02*
X541196Y1037931D01*
X542226D01*
X542411Y1037331D01*
Y1037157D01*
X541011D01*
Y1037331D01*
G37*
G36*
G01X535010Y1032531D02*
X534825Y1031931D01*
X533795D01*
X533610Y1032531D01*
Y1032705D01*
X535010D01*
Y1032531D01*
G37*
G36*
G01D02*
X534825Y1031931D01*
X533795D01*
X533610Y1032531D01*
Y1032705D01*
X535010D01*
Y1032531D01*
G37*
G36*
G01X538710D02*
X538525Y1031931D01*
X537495D01*
X537310Y1032531D01*
Y1032705D01*
X538710D01*
Y1032531D01*
G37*
G36*
G01X542411D02*
X542226Y1031931D01*
X541196D01*
X541011Y1032531D01*
Y1032706D01*
X542411D01*
Y1032531D01*
G37*
G36*
G01X546078D02*
X545893Y1031931D01*
X544863D01*
X544678Y1032531D01*
Y1032705D01*
X546078D01*
Y1032531D01*
G37*
G36*
G01X538710D02*
X538525Y1031931D01*
X537495D01*
X537310Y1032531D01*
Y1032705D01*
X538710D01*
Y1032531D01*
G37*
G36*
G01X542411D02*
X542226Y1031931D01*
X541196D01*
X541011Y1032531D01*
Y1032706D01*
X542411D01*
Y1032531D01*
G37*
G36*
G01X546078D02*
X545893Y1031931D01*
X544863D01*
X544678Y1032531D01*
Y1032705D01*
X546078D01*
Y1032531D01*
G37*
G36*
G01X533645Y1062967D02*
X533830Y1063567D01*
X534860D01*
X535045Y1062967D01*
Y1062792D01*
X533645D01*
Y1062967D01*
G37*
G36*
G01D02*
X533830Y1063567D01*
X534860D01*
X535045Y1062967D01*
Y1062792D01*
X533645D01*
Y1062967D01*
G37*
G36*
G01X544745D02*
X544930Y1063567D01*
X545960D01*
X546145Y1062967D01*
Y1062792D01*
X544745D01*
Y1062967D01*
G37*
G36*
G01X541045D02*
X541230Y1063567D01*
X542260D01*
X542445Y1062967D01*
Y1062792D01*
X541045D01*
Y1062967D01*
G37*
G36*
G01X537345D02*
X537530Y1063567D01*
X538560D01*
X538745Y1062967D01*
Y1062792D01*
X537345D01*
Y1062967D01*
G37*
G36*
G01X544745D02*
X544930Y1063567D01*
X545960D01*
X546145Y1062967D01*
Y1062792D01*
X544745D01*
Y1062967D01*
G37*
G36*
G01X541045D02*
X541230Y1063567D01*
X542260D01*
X542445Y1062967D01*
Y1062792D01*
X541045D01*
Y1062967D01*
G37*
G36*
G01X537345D02*
X537530Y1063567D01*
X538560D01*
X538745Y1062967D01*
Y1062792D01*
X537345D01*
Y1062967D01*
G37*
G36*
G01X535461Y1059761D02*
X535646Y1060361D01*
X536676D01*
X536861Y1059761D01*
Y1059586D01*
X535461D01*
Y1059761D01*
G37*
G36*
G01D02*
X535646Y1060361D01*
X536676D01*
X536861Y1059761D01*
Y1059586D01*
X535461D01*
Y1059761D01*
G37*
G36*
G01X539160D02*
X539345Y1060361D01*
X540375D01*
X540560Y1059761D01*
Y1059586D01*
X539160D01*
Y1059761D01*
G37*
G36*
G01X546534D02*
X546719Y1060361D01*
X547749D01*
X547934Y1059761D01*
Y1059586D01*
X546534D01*
Y1059761D01*
G37*
G36*
G01X542835D02*
X543020Y1060361D01*
X544050D01*
X544235Y1059761D01*
Y1059586D01*
X542835D01*
Y1059761D01*
G37*
G36*
G01X539160D02*
X539345Y1060361D01*
X540375D01*
X540560Y1059761D01*
Y1059586D01*
X539160D01*
Y1059761D01*
G37*
G36*
G01X546534D02*
X546719Y1060361D01*
X547749D01*
X547934Y1059761D01*
Y1059586D01*
X546534D01*
Y1059761D01*
G37*
G36*
G01X542835D02*
X543020Y1060361D01*
X544050D01*
X544235Y1059761D01*
Y1059586D01*
X542835D01*
Y1059761D01*
G37*
G36*
G01X536828Y1061369D02*
X536643Y1060769D01*
X535613D01*
X535428Y1061369D01*
Y1061543D01*
X536828D01*
Y1061369D01*
G37*
G36*
G01D02*
X536643Y1060769D01*
X535613D01*
X535428Y1061369D01*
Y1061543D01*
X536828D01*
Y1061369D01*
G37*
G36*
G01X547928D02*
X547743Y1060769D01*
X546713D01*
X546528Y1061369D01*
Y1061543D01*
X547928D01*
Y1061369D01*
G37*
G36*
G01X540528D02*
X540343Y1060769D01*
X539313D01*
X539128Y1061369D01*
Y1061543D01*
X540528D01*
Y1061369D01*
G37*
G36*
G01X544228D02*
X544043Y1060769D01*
X543013D01*
X542828Y1061369D01*
Y1061543D01*
X544228D01*
Y1061369D01*
G37*
G36*
G01X547928D02*
X547743Y1060769D01*
X546713D01*
X546528Y1061369D01*
Y1061543D01*
X547928D01*
Y1061369D01*
G37*
G36*
G01X540528D02*
X540343Y1060769D01*
X539313D01*
X539128Y1061369D01*
Y1061543D01*
X540528D01*
Y1061369D01*
G37*
G36*
G01X544228D02*
X544043Y1060769D01*
X543013D01*
X542828Y1061369D01*
Y1061543D01*
X544228D01*
Y1061369D01*
G37*
G36*
G01X535035Y1058165D02*
X534850Y1057565D01*
X533820D01*
X533635Y1058165D01*
Y1058340D01*
X535035D01*
Y1058165D01*
G37*
G36*
G01D02*
X534850Y1057565D01*
X533820D01*
X533635Y1058165D01*
Y1058340D01*
X535035D01*
Y1058165D01*
G37*
G36*
G01X546132D02*
X545947Y1057565D01*
X544917D01*
X544732Y1058165D01*
Y1058340D01*
X546132D01*
Y1058165D01*
G37*
G36*
G01X538687D02*
X538502Y1057565D01*
X537472D01*
X537287Y1058165D01*
Y1058340D01*
X538687D01*
Y1058165D01*
G37*
G36*
G01X542433D02*
X542248Y1057565D01*
X541218D01*
X541033Y1058165D01*
Y1058340D01*
X542433D01*
Y1058165D01*
G37*
G36*
G01X549831D02*
X549646Y1057565D01*
X548616D01*
X548431Y1058165D01*
Y1058340D01*
X549831D01*
Y1058165D01*
G37*
G36*
G01X546132D02*
X545947Y1057565D01*
X544917D01*
X544732Y1058165D01*
Y1058340D01*
X546132D01*
Y1058165D01*
G37*
G36*
G01X538687D02*
X538502Y1057565D01*
X537472D01*
X537287Y1058165D01*
Y1058340D01*
X538687D01*
Y1058165D01*
G37*
G36*
G01X542433D02*
X542248Y1057565D01*
X541218D01*
X541033Y1058165D01*
Y1058340D01*
X542433D01*
Y1058165D01*
G37*
G36*
G01X549831D02*
X549646Y1057565D01*
X548616D01*
X548431Y1058165D01*
Y1058340D01*
X549831D01*
Y1058165D01*
G37*
G36*
G01X533635Y1050149D02*
X533820Y1050749D01*
X534850D01*
X535035Y1050149D01*
Y1049974D01*
X533635D01*
Y1050149D01*
G37*
G36*
G01D02*
X533820Y1050749D01*
X534850D01*
X535035Y1050149D01*
Y1049974D01*
X533635D01*
Y1050149D01*
G37*
G36*
G01X548384D02*
X548569Y1050749D01*
X549599D01*
X549784Y1050149D01*
Y1049974D01*
X548384D01*
Y1050149D01*
G37*
G36*
G01X544685D02*
X544870Y1050749D01*
X545900D01*
X546085Y1050149D01*
Y1049974D01*
X544685D01*
Y1050149D01*
G37*
G36*
G01X540986D02*
X541171Y1050749D01*
X542201D01*
X542386Y1050149D01*
Y1049974D01*
X540986D01*
Y1050149D01*
G37*
G36*
G01X537287D02*
X537472Y1050749D01*
X538502D01*
X538687Y1050149D01*
Y1049974D01*
X537287D01*
Y1050149D01*
G37*
G36*
G01X548384D02*
X548569Y1050749D01*
X549599D01*
X549784Y1050149D01*
Y1049974D01*
X548384D01*
Y1050149D01*
G37*
G36*
G01X544685D02*
X544870Y1050749D01*
X545900D01*
X546085Y1050149D01*
Y1049974D01*
X544685D01*
Y1050149D01*
G37*
G36*
G01X540986D02*
X541171Y1050749D01*
X542201D01*
X542386Y1050149D01*
Y1049974D01*
X540986D01*
Y1050149D01*
G37*
G36*
G01X537287D02*
X537472Y1050749D01*
X538502D01*
X538687Y1050149D01*
Y1049974D01*
X537287D01*
Y1050149D01*
G37*
G36*
G01X536861Y1048553D02*
X536676Y1047953D01*
X535646D01*
X535461Y1048553D01*
Y1048727D01*
X536861D01*
Y1048553D01*
G37*
G36*
G01D02*
X536676Y1047953D01*
X535646D01*
X535461Y1048553D01*
Y1048727D01*
X536861D01*
Y1048553D01*
G37*
G36*
G01X547982D02*
X547797Y1047953D01*
X546767D01*
X546582Y1048553D01*
Y1048727D01*
X547982D01*
Y1048553D01*
G37*
G36*
G01X544283D02*
X544098Y1047953D01*
X543068D01*
X542883Y1048553D01*
Y1048727D01*
X544283D01*
Y1048553D01*
G37*
G36*
G01X540584D02*
X540399Y1047953D01*
X539369D01*
X539184Y1048553D01*
Y1048727D01*
X540584D01*
Y1048553D01*
G37*
G36*
G01X547982D02*
X547797Y1047953D01*
X546767D01*
X546582Y1048553D01*
Y1048727D01*
X547982D01*
Y1048553D01*
G37*
G36*
G01X544283D02*
X544098Y1047953D01*
X543068D01*
X542883Y1048553D01*
Y1048727D01*
X544283D01*
Y1048553D01*
G37*
G36*
G01X540584D02*
X540399Y1047953D01*
X539369D01*
X539184Y1048553D01*
Y1048727D01*
X540584D01*
Y1048553D01*
G37*
G36*
G01X536861Y1054961D02*
X536676Y1054361D01*
X535646D01*
X535461Y1054961D01*
Y1055136D01*
X536861D01*
Y1054961D01*
G37*
G36*
G01D02*
X536676Y1054361D01*
X535646D01*
X535461Y1054961D01*
Y1055136D01*
X536861D01*
Y1054961D01*
G37*
G36*
G01X547992D02*
X547807Y1054361D01*
X546777D01*
X546592Y1054961D01*
Y1055136D01*
X547992D01*
Y1054961D01*
G37*
G36*
G01X540594D02*
X540409Y1054361D01*
X539379D01*
X539194Y1054961D01*
Y1055135D01*
X540594D01*
Y1054961D01*
G37*
G36*
G01X544293D02*
X544108Y1054361D01*
X543078D01*
X542893Y1054961D01*
Y1055135D01*
X544293D01*
Y1054961D01*
G37*
G36*
G01X547992D02*
X547807Y1054361D01*
X546777D01*
X546592Y1054961D01*
Y1055136D01*
X547992D01*
Y1054961D01*
G37*
G36*
G01X540594D02*
X540409Y1054361D01*
X539379D01*
X539194Y1054961D01*
Y1055135D01*
X540594D01*
Y1054961D01*
G37*
G36*
G01X544293D02*
X544108Y1054361D01*
X543078D01*
X542893Y1054961D01*
Y1055135D01*
X544293D01*
Y1054961D01*
G37*
G36*
G01X535461Y1053353D02*
X535646Y1053953D01*
X536676D01*
X536861Y1053353D01*
Y1053178D01*
X535461D01*
Y1053353D01*
G37*
G36*
G01D02*
X535646Y1053953D01*
X536676D01*
X536861Y1053353D01*
Y1053178D01*
X535461D01*
Y1053353D01*
G37*
G36*
G01X546582D02*
X546767Y1053953D01*
X547797D01*
X547982Y1053353D01*
Y1053178D01*
X546582D01*
Y1053353D01*
G37*
G36*
G01X539194D02*
X539379Y1053953D01*
X540409D01*
X540594Y1053353D01*
Y1053179D01*
X539194D01*
Y1053353D01*
G37*
G36*
G01X542893D02*
X543078Y1053953D01*
X544108D01*
X544293Y1053353D01*
Y1053179D01*
X542893D01*
Y1053353D01*
G37*
G36*
G01X546582D02*
X546767Y1053953D01*
X547797D01*
X547982Y1053353D01*
Y1053178D01*
X546582D01*
Y1053353D01*
G37*
G36*
G01X539194D02*
X539379Y1053953D01*
X540409D01*
X540594Y1053353D01*
Y1053179D01*
X539194D01*
Y1053353D01*
G37*
G36*
G01X542893D02*
X543078Y1053953D01*
X544108D01*
X544293Y1053353D01*
Y1053179D01*
X542893D01*
Y1053353D01*
G37*
G36*
G01X533635Y1056557D02*
X533820Y1057157D01*
X534850D01*
X535035Y1056557D01*
Y1056382D01*
X533635D01*
Y1056557D01*
G37*
G36*
G01D02*
X533820Y1057157D01*
X534850D01*
X535035Y1056557D01*
Y1056382D01*
X533635D01*
Y1056557D01*
G37*
G36*
G01X544669D02*
X544854Y1057157D01*
X545884D01*
X546069Y1056557D01*
Y1056382D01*
X544669D01*
Y1056557D01*
G37*
G36*
G01X537287D02*
X537472Y1057157D01*
X538502D01*
X538687Y1056557D01*
Y1056382D01*
X537287D01*
Y1056557D01*
G37*
G36*
G01X540977D02*
X541162Y1057157D01*
X542192D01*
X542377Y1056557D01*
Y1056383D01*
X540977D01*
Y1056557D01*
G37*
G36*
G01X548384D02*
X548569Y1057157D01*
X549599D01*
X549784Y1056557D01*
Y1056382D01*
X548384D01*
Y1056557D01*
G37*
G36*
G01X544669D02*
X544854Y1057157D01*
X545884D01*
X546069Y1056557D01*
Y1056382D01*
X544669D01*
Y1056557D01*
G37*
G36*
G01X537287D02*
X537472Y1057157D01*
X538502D01*
X538687Y1056557D01*
Y1056382D01*
X537287D01*
Y1056557D01*
G37*
G36*
G01X540977D02*
X541162Y1057157D01*
X542192D01*
X542377Y1056557D01*
Y1056383D01*
X540977D01*
Y1056557D01*
G37*
G36*
G01X548384D02*
X548569Y1057157D01*
X549599D01*
X549784Y1056557D01*
Y1056382D01*
X548384D01*
Y1056557D01*
G37*
G36*
G01X535035Y1051757D02*
X534850Y1051157D01*
X533820D01*
X533635Y1051757D01*
Y1051931D01*
X535035D01*
Y1051757D01*
G37*
G36*
G01D02*
X534850Y1051157D01*
X533820D01*
X533635Y1051757D01*
Y1051931D01*
X535035D01*
Y1051757D01*
G37*
G36*
G01X546069D02*
X545884Y1051157D01*
X544854D01*
X544669Y1051757D01*
Y1051931D01*
X546069D01*
Y1051757D01*
G37*
G36*
G01X538687D02*
X538502Y1051157D01*
X537472D01*
X537287Y1051757D01*
Y1051931D01*
X538687D01*
Y1051757D01*
G37*
G36*
G01X542377Y1051755D02*
X542192Y1051155D01*
X541162D01*
X540977Y1051755D01*
Y1051930D01*
X542377D01*
Y1051755D01*
G37*
G36*
G01X549831Y1051757D02*
X549646Y1051157D01*
X548616D01*
X548431Y1051757D01*
Y1051931D01*
X549831D01*
Y1051757D01*
G37*
G36*
G01X546069D02*
X545884Y1051157D01*
X544854D01*
X544669Y1051757D01*
Y1051931D01*
X546069D01*
Y1051757D01*
G37*
G36*
G01X538687D02*
X538502Y1051157D01*
X537472D01*
X537287Y1051757D01*
Y1051931D01*
X538687D01*
Y1051757D01*
G37*
G36*
G01X542377Y1051755D02*
X542192Y1051155D01*
X541162D01*
X540977Y1051755D01*
Y1051930D01*
X542377D01*
Y1051755D01*
G37*
G36*
G01X549831Y1051757D02*
X549646Y1051157D01*
X548616D01*
X548431Y1051757D01*
Y1051931D01*
X549831D01*
Y1051757D01*
G37*
G36*
G01X535035Y1077391D02*
X534850Y1076791D01*
X533820D01*
X533635Y1077391D01*
Y1077566D01*
X535035D01*
Y1077391D01*
G37*
G36*
G01D02*
X534850Y1076791D01*
X533820D01*
X533635Y1077391D01*
Y1077566D01*
X535035D01*
Y1077391D01*
G37*
G36*
G01X542411D02*
X542226Y1076791D01*
X541196D01*
X541011Y1077391D01*
Y1077566D01*
X542411D01*
Y1077391D01*
G37*
G36*
G01X538711D02*
X538526Y1076791D01*
X537496D01*
X537311Y1077391D01*
Y1077566D01*
X538711D01*
Y1077391D01*
G37*
G36*
G01X542411D02*
X542226Y1076791D01*
X541196D01*
X541011Y1077391D01*
Y1077566D01*
X542411D01*
Y1077391D01*
G37*
G36*
G01X538711D02*
X538526Y1076791D01*
X537496D01*
X537311Y1077391D01*
Y1077566D01*
X538711D01*
Y1077391D01*
G37*
G36*
G01X533612Y1069373D02*
X533797Y1069973D01*
X534827D01*
X535012Y1069373D01*
Y1069199D01*
X533612D01*
Y1069373D01*
G37*
G36*
G01D02*
X533797Y1069973D01*
X534827D01*
X535012Y1069373D01*
Y1069199D01*
X533612D01*
Y1069373D01*
G37*
G36*
G01X544745Y1069375D02*
X544930Y1069975D01*
X545960D01*
X546145Y1069375D01*
Y1069200D01*
X544745D01*
Y1069375D01*
G37*
G36*
G01X541045D02*
X541230Y1069975D01*
X542260D01*
X542445Y1069375D01*
Y1069200D01*
X541045D01*
Y1069375D01*
G37*
G36*
G01X537345D02*
X537530Y1069975D01*
X538560D01*
X538745Y1069375D01*
Y1069200D01*
X537345D01*
Y1069375D01*
G37*
G36*
G01X544745D02*
X544930Y1069975D01*
X545960D01*
X546145Y1069375D01*
Y1069200D01*
X544745D01*
Y1069375D01*
G37*
G36*
G01X541045D02*
X541230Y1069975D01*
X542260D01*
X542445Y1069375D01*
Y1069200D01*
X541045D01*
Y1069375D01*
G37*
G36*
G01X537345D02*
X537530Y1069975D01*
X538560D01*
X538745Y1069375D01*
Y1069200D01*
X537345D01*
Y1069375D01*
G37*
G36*
G01X535428Y1066171D02*
X535613Y1066771D01*
X536643D01*
X536828Y1066171D01*
Y1065996D01*
X535428D01*
Y1066171D01*
G37*
G36*
G01D02*
X535613Y1066771D01*
X536643D01*
X536828Y1066171D01*
Y1065996D01*
X535428D01*
Y1066171D01*
G37*
G36*
G01X542828D02*
X543013Y1066771D01*
X544043D01*
X544228Y1066171D01*
Y1065996D01*
X542828D01*
Y1066171D01*
G37*
G36*
G01X539128D02*
X539313Y1066771D01*
X540343D01*
X540528Y1066171D01*
Y1065996D01*
X539128D01*
Y1066171D01*
G37*
G36*
G01X542828D02*
X543013Y1066771D01*
X544043D01*
X544228Y1066171D01*
Y1065996D01*
X542828D01*
Y1066171D01*
G37*
G36*
G01X539128D02*
X539313Y1066771D01*
X540343D01*
X540528Y1066171D01*
Y1065996D01*
X539128D01*
Y1066171D01*
G37*
G36*
G01X536828Y1067777D02*
X536643Y1067177D01*
X535613D01*
X535428Y1067777D01*
Y1067952D01*
X536828D01*
Y1067777D01*
G37*
G36*
G01D02*
X536643Y1067177D01*
X535613D01*
X535428Y1067777D01*
Y1067952D01*
X536828D01*
Y1067777D01*
G37*
G36*
G01X540528D02*
X540343Y1067177D01*
X539313D01*
X539128Y1067777D01*
Y1067952D01*
X540528D01*
Y1067777D01*
G37*
G36*
G01X544228D02*
X544043Y1067177D01*
X543013D01*
X542828Y1067777D01*
Y1067952D01*
X544228D01*
Y1067777D01*
G37*
G36*
G01X540528D02*
X540343Y1067177D01*
X539313D01*
X539128Y1067777D01*
Y1067952D01*
X540528D01*
Y1067777D01*
G37*
G36*
G01X544228D02*
X544043Y1067177D01*
X543013D01*
X542828Y1067777D01*
Y1067952D01*
X544228D01*
Y1067777D01*
G37*
G36*
G01X535045Y1064573D02*
X534860Y1063973D01*
X533830D01*
X533645Y1064573D01*
Y1064748D01*
X535045D01*
Y1064573D01*
G37*
G36*
G01D02*
X534860Y1063973D01*
X533830D01*
X533645Y1064573D01*
Y1064748D01*
X535045D01*
Y1064573D01*
G37*
G36*
G01X538745D02*
X538560Y1063973D01*
X537530D01*
X537345Y1064573D01*
Y1064748D01*
X538745D01*
Y1064573D01*
G37*
G36*
G01X542445D02*
X542260Y1063973D01*
X541230D01*
X541045Y1064573D01*
Y1064748D01*
X542445D01*
Y1064573D01*
G37*
G36*
G01X538745D02*
X538560Y1063973D01*
X537530D01*
X537345Y1064573D01*
Y1064748D01*
X538745D01*
Y1064573D01*
G37*
G36*
G01X542445D02*
X542260Y1063973D01*
X541230D01*
X541045Y1064573D01*
Y1064748D01*
X542445D01*
Y1064573D01*
G37*
G36*
G01X535461Y1078987D02*
X535646Y1079587D01*
X536676D01*
X536861Y1078987D01*
Y1078812D01*
X535461D01*
Y1078987D01*
G37*
G36*
G01D02*
X535646Y1079587D01*
X536676D01*
X536861Y1078987D01*
Y1078812D01*
X535461D01*
Y1078987D01*
G37*
G36*
G01X542861D02*
X543046Y1079587D01*
X544076D01*
X544261Y1078987D01*
Y1078812D01*
X542861D01*
Y1078987D01*
G37*
G36*
G01X539161D02*
X539346Y1079587D01*
X540376D01*
X540561Y1078987D01*
Y1078812D01*
X539161D01*
Y1078987D01*
G37*
G36*
G01X542861D02*
X543046Y1079587D01*
X544076D01*
X544261Y1078987D01*
Y1078812D01*
X542861D01*
Y1078987D01*
G37*
G36*
G01X539161D02*
X539346Y1079587D01*
X540376D01*
X540561Y1078987D01*
Y1078812D01*
X539161D01*
Y1078987D01*
G37*
G36*
G01X536861Y1074187D02*
X536676Y1073587D01*
X535646D01*
X535461Y1074187D01*
Y1074362D01*
X536861D01*
Y1074187D01*
G37*
G36*
G01D02*
X536676Y1073587D01*
X535646D01*
X535461Y1074187D01*
Y1074362D01*
X536861D01*
Y1074187D01*
G37*
G36*
G01X540561D02*
X540376Y1073587D01*
X539346D01*
X539161Y1074187D01*
Y1074362D01*
X540561D01*
Y1074187D01*
G37*
G36*
G01X544283D02*
X544098Y1073587D01*
X543068D01*
X542883Y1074187D01*
Y1074362D01*
X544283D01*
Y1074187D01*
G37*
G36*
G01X540561D02*
X540376Y1073587D01*
X539346D01*
X539161Y1074187D01*
Y1074362D01*
X540561D01*
Y1074187D01*
G37*
G36*
G01X544283D02*
X544098Y1073587D01*
X543068D01*
X542883Y1074187D01*
Y1074362D01*
X544283D01*
Y1074187D01*
G37*
G36*
G01X535428Y1072579D02*
X535613Y1073179D01*
X536643D01*
X536828Y1072579D01*
Y1072405D01*
X535428D01*
Y1072579D01*
G37*
G36*
G01D02*
X535613Y1073179D01*
X536643D01*
X536828Y1072579D01*
Y1072405D01*
X535428D01*
Y1072579D01*
G37*
G36*
G01X539128D02*
X539313Y1073179D01*
X540343D01*
X540528Y1072579D01*
Y1072405D01*
X539128D01*
Y1072579D01*
G37*
G36*
G01X542828D02*
X543013Y1073179D01*
X544043D01*
X544228Y1072579D01*
Y1072405D01*
X542828D01*
Y1072579D01*
G37*
G36*
G01X539128D02*
X539313Y1073179D01*
X540343D01*
X540528Y1072579D01*
Y1072405D01*
X539128D01*
Y1072579D01*
G37*
G36*
G01X542828D02*
X543013Y1073179D01*
X544043D01*
X544228Y1072579D01*
Y1072405D01*
X542828D01*
Y1072579D01*
G37*
G36*
G01X533635Y1075783D02*
X533820Y1076383D01*
X534850D01*
X535035Y1075783D01*
Y1075608D01*
X533635D01*
Y1075783D01*
G37*
G36*
G01D02*
X533820Y1076383D01*
X534850D01*
X535035Y1075783D01*
Y1075608D01*
X533635D01*
Y1075783D01*
G37*
G36*
G01X537311D02*
X537496Y1076383D01*
X538526D01*
X538711Y1075783D01*
Y1075608D01*
X537311D01*
Y1075783D01*
G37*
G36*
G01X540987D02*
X541172Y1076383D01*
X542202D01*
X542387Y1075783D01*
Y1075608D01*
X540987D01*
Y1075783D01*
G37*
G36*
G01X537311D02*
X537496Y1076383D01*
X538526D01*
X538711Y1075783D01*
Y1075608D01*
X537311D01*
Y1075783D01*
G37*
G36*
G01X540987D02*
X541172Y1076383D01*
X542202D01*
X542387Y1075783D01*
Y1075608D01*
X540987D01*
Y1075783D01*
G37*
G36*
G01X535045Y1070981D02*
X534860Y1070381D01*
X533830D01*
X533645Y1070981D01*
Y1071156D01*
X535045D01*
Y1070981D01*
G37*
G36*
G01D02*
X534860Y1070381D01*
X533830D01*
X533645Y1070981D01*
Y1071156D01*
X535045D01*
Y1070981D01*
G37*
G36*
G01X538745D02*
X538560Y1070381D01*
X537530D01*
X537345Y1070981D01*
Y1071156D01*
X538745D01*
Y1070981D01*
G37*
G36*
G01X542445D02*
X542260Y1070381D01*
X541230D01*
X541045Y1070981D01*
Y1071156D01*
X542445D01*
Y1070981D01*
G37*
G36*
G01X538745D02*
X538560Y1070381D01*
X537530D01*
X537345Y1070981D01*
Y1071156D01*
X538745D01*
Y1070981D01*
G37*
G36*
G01X542445D02*
X542260Y1070381D01*
X541230D01*
X541045Y1070981D01*
Y1071156D01*
X542445D01*
Y1070981D01*
G37*
G36*
G01X536828Y1080595D02*
X536643Y1079995D01*
X535613D01*
X535428Y1080595D01*
Y1080769D01*
X536828D01*
Y1080595D01*
G37*
G36*
G01D02*
X536643Y1079995D01*
X535613D01*
X535428Y1080595D01*
Y1080769D01*
X536828D01*
Y1080595D01*
G37*
G36*
G01X540528D02*
X540343Y1079995D01*
X539313D01*
X539128Y1080595D01*
Y1080769D01*
X540528D01*
Y1080595D01*
G37*
G36*
G01D02*
X540343Y1079995D01*
X539313D01*
X539128Y1080595D01*
Y1080769D01*
X540528D01*
Y1080595D01*
G37*
G36*
G01X533645Y1082192D02*
X533830Y1082792D01*
X534860D01*
X535045Y1082192D01*
Y1082018D01*
X533645D01*
Y1082192D01*
G37*
G36*
G01D02*
X533830Y1082792D01*
X534860D01*
X535045Y1082192D01*
Y1082018D01*
X533645D01*
Y1082192D01*
G37*
G36*
G01X541045D02*
X541230Y1082792D01*
X542260D01*
X542445Y1082192D01*
Y1082018D01*
X541045D01*
Y1082192D01*
G37*
G36*
G01X537345D02*
X537530Y1082792D01*
X538560D01*
X538745Y1082192D01*
Y1082018D01*
X537345D01*
Y1082192D01*
G37*
G36*
G01X541045D02*
X541230Y1082792D01*
X542260D01*
X542445Y1082192D01*
Y1082018D01*
X541045D01*
Y1082192D01*
G37*
G36*
G01X537345D02*
X537530Y1082792D01*
X538560D01*
X538745Y1082192D01*
Y1082018D01*
X537345D01*
Y1082192D01*
G37*
G36*
G01X533635Y1088599D02*
X533820Y1089199D01*
X534850D01*
X535035Y1088599D01*
Y1088425D01*
X533635D01*
Y1088599D01*
G37*
G36*
G01D02*
X533820Y1089199D01*
X534850D01*
X535035Y1088599D01*
Y1088425D01*
X533635D01*
Y1088599D01*
G37*
G36*
G01X541011D02*
X541196Y1089199D01*
X542226D01*
X542411Y1088599D01*
Y1088425D01*
X541011D01*
Y1088599D01*
G37*
G36*
G01X537311D02*
X537496Y1089199D01*
X538526D01*
X538711Y1088599D01*
Y1088425D01*
X537311D01*
Y1088599D01*
G37*
G36*
G01X544843Y1090014D02*
X544416Y1090474D01*
X544931Y1091366D01*
X545543Y1091226D01*
X545694Y1091139D01*
X544994Y1089927D01*
X544843Y1090014D01*
G37*
G36*
G01X541011Y1088599D02*
X541196Y1089199D01*
X542226D01*
X542411Y1088599D01*
Y1088425D01*
X541011D01*
Y1088599D01*
G37*
G36*
G01X537311D02*
X537496Y1089199D01*
X538526D01*
X538711Y1088599D01*
Y1088425D01*
X537311D01*
Y1088599D01*
G37*
G36*
G01X544843Y1090014D02*
X544416Y1090474D01*
X544931Y1091366D01*
X545543Y1091226D01*
X545694Y1091139D01*
X544994Y1089927D01*
X544843Y1090014D01*
G37*
G36*
G01X535428Y1085396D02*
X535613Y1085996D01*
X536643D01*
X536828Y1085396D01*
Y1085222D01*
X535428D01*
Y1085396D01*
G37*
G36*
G01D02*
X535613Y1085996D01*
X536643D01*
X536828Y1085396D01*
Y1085222D01*
X535428D01*
Y1085396D01*
G37*
G36*
G01X539128D02*
X539313Y1085996D01*
X540343D01*
X540528Y1085396D01*
Y1085222D01*
X539128D01*
Y1085396D01*
G37*
G36*
G01X542828D02*
X543013Y1085996D01*
X544043D01*
X544228Y1085396D01*
Y1085222D01*
X542828D01*
Y1085396D01*
G37*
G36*
G01X546693Y1086810D02*
X546266Y1087270D01*
X546781Y1088162D01*
X547393Y1088022D01*
X547544Y1087935D01*
X546844Y1086723D01*
X546693Y1086810D01*
G37*
G36*
G01X539128Y1085396D02*
X539313Y1085996D01*
X540343D01*
X540528Y1085396D01*
Y1085222D01*
X539128D01*
Y1085396D01*
G37*
G36*
G01X542828D02*
X543013Y1085996D01*
X544043D01*
X544228Y1085396D01*
Y1085222D01*
X542828D01*
Y1085396D01*
G37*
G36*
G01X546693Y1086810D02*
X546266Y1087270D01*
X546781Y1088162D01*
X547393Y1088022D01*
X547544Y1087935D01*
X546844Y1086723D01*
X546693Y1086810D01*
G37*
G36*
G01X536861Y1087005D02*
X536676Y1086405D01*
X535646D01*
X535461Y1087005D01*
Y1087179D01*
X536861D01*
Y1087005D01*
G37*
G36*
G01D02*
X536676Y1086405D01*
X535646D01*
X535461Y1087005D01*
Y1087179D01*
X536861D01*
Y1087005D01*
G37*
G36*
G01X544261D02*
X544076Y1086405D01*
X543046D01*
X542861Y1087005D01*
Y1087179D01*
X544261D01*
Y1087005D01*
G37*
G36*
G01X540561D02*
X540376Y1086405D01*
X539346D01*
X539161Y1087005D01*
Y1087179D01*
X540561D01*
Y1087005D01*
G37*
G36*
G01X545979Y1088794D02*
X546406Y1088334D01*
X545891Y1087442D01*
X545279Y1087582D01*
X545128Y1087669D01*
X545828Y1088881D01*
X545979Y1088794D01*
G37*
G36*
G01X544261Y1087005D02*
X544076Y1086405D01*
X543046D01*
X542861Y1087005D01*
Y1087179D01*
X544261D01*
Y1087005D01*
G37*
G36*
G01X540561D02*
X540376Y1086405D01*
X539346D01*
X539161Y1087005D01*
Y1087179D01*
X540561D01*
Y1087005D01*
G37*
G36*
G01X545979Y1088794D02*
X546406Y1088334D01*
X545891Y1087442D01*
X545279Y1087582D01*
X545128Y1087669D01*
X545828Y1088881D01*
X545979Y1088794D01*
G37*
G36*
G01X535045Y1083799D02*
X534860Y1083199D01*
X533830D01*
X533645Y1083799D01*
Y1083974D01*
X535045D01*
Y1083799D01*
G37*
G36*
G01D02*
X534860Y1083199D01*
X533830D01*
X533645Y1083799D01*
Y1083974D01*
X535045D01*
Y1083799D01*
G37*
G36*
G01X542445D02*
X542260Y1083199D01*
X541230D01*
X541045Y1083799D01*
Y1083974D01*
X542445D01*
Y1083799D01*
G37*
G36*
G01X538745D02*
X538560Y1083199D01*
X537530D01*
X537345Y1083799D01*
Y1083974D01*
X538745D01*
Y1083799D01*
G37*
G36*
G01X546145D02*
X545960Y1083199D01*
X544930D01*
X544745Y1083799D01*
Y1083974D01*
X546145D01*
Y1083799D01*
G37*
G36*
G01X542445D02*
X542260Y1083199D01*
X541230D01*
X541045Y1083799D01*
Y1083974D01*
X542445D01*
Y1083799D01*
G37*
G36*
G01X538745D02*
X538560Y1083199D01*
X537530D01*
X537345Y1083799D01*
Y1083974D01*
X538745D01*
Y1083799D01*
G37*
G36*
G01X546145D02*
X545960Y1083199D01*
X544930D01*
X544745Y1083799D01*
Y1083974D01*
X546145D01*
Y1083799D01*
G37*
G36*
G01X536837Y1093411D02*
X536652Y1092811D01*
X535622D01*
X535437Y1093411D01*
Y1093586D01*
X536837D01*
Y1093411D01*
G37*
G36*
G01D02*
X536652Y1092811D01*
X535622D01*
X535437Y1093411D01*
Y1093586D01*
X536837D01*
Y1093411D01*
G37*
G36*
G01X540561Y1093413D02*
X540376Y1092813D01*
X539346D01*
X539161Y1093413D01*
Y1093587D01*
X540561D01*
Y1093413D01*
G37*
G36*
G01X542271Y1095187D02*
X542698Y1094727D01*
X542183Y1093835D01*
X541571Y1093975D01*
X541420Y1094062D01*
X542120Y1095274D01*
X542271Y1095187D01*
G37*
G36*
G01X540561Y1093413D02*
X540376Y1092813D01*
X539346D01*
X539161Y1093413D01*
Y1093587D01*
X540561D01*
Y1093413D01*
G37*
G36*
G01X542271Y1095187D02*
X542698Y1094727D01*
X542183Y1093835D01*
X541571Y1093975D01*
X541420Y1094062D01*
X542120Y1095274D01*
X542271Y1095187D01*
G37*
G36*
G01X535437Y1091804D02*
X535622Y1092404D01*
X536652D01*
X536837Y1091804D01*
Y1091630D01*
X535437D01*
Y1091804D01*
G37*
G36*
G01D02*
X535622Y1092404D01*
X536652D01*
X536837Y1091804D01*
Y1091630D01*
X535437D01*
Y1091804D01*
G37*
G36*
G01X539161Y1091803D02*
X539346Y1092403D01*
X540376D01*
X540561Y1091803D01*
Y1091629D01*
X539161D01*
Y1091803D01*
G37*
G36*
G01X543001Y1093234D02*
X542574Y1093694D01*
X543089Y1094586D01*
X543701Y1094446D01*
X543852Y1094359D01*
X543152Y1093147D01*
X543001Y1093234D01*
G37*
G36*
G01X539161Y1091803D02*
X539346Y1092403D01*
X540376D01*
X540561Y1091803D01*
Y1091629D01*
X539161D01*
Y1091803D01*
G37*
G36*
G01X543001Y1093234D02*
X542574Y1093694D01*
X543089Y1094586D01*
X543701Y1094446D01*
X543852Y1094359D01*
X543152Y1093147D01*
X543001Y1093234D01*
G37*
G36*
G01X533644Y1095009D02*
X533829Y1095609D01*
X534859D01*
X535044Y1095009D01*
Y1094835D01*
X533644D01*
Y1095009D01*
G37*
G36*
G01D02*
X533829Y1095609D01*
X534859D01*
X535044Y1095009D01*
Y1094835D01*
X533644D01*
Y1095009D01*
G37*
G36*
G01X537311Y1095008D02*
X537496Y1095608D01*
X538526D01*
X538711Y1095008D01*
Y1094834D01*
X537311D01*
Y1095008D01*
G37*
G36*
G01D02*
X537496Y1095608D01*
X538526D01*
X538711Y1095008D01*
Y1094834D01*
X537311D01*
Y1095008D01*
G37*
G36*
G01X535044Y1090207D02*
X534859Y1089607D01*
X533829D01*
X533644Y1090207D01*
Y1090382D01*
X535044D01*
Y1090207D01*
G37*
G36*
G01D02*
X534859Y1089607D01*
X533829D01*
X533644Y1090207D01*
Y1090382D01*
X535044D01*
Y1090207D01*
G37*
G36*
G01X538711Y1090209D02*
X538526Y1089609D01*
X537496D01*
X537311Y1090209D01*
Y1090383D01*
X538711D01*
Y1090209D01*
G37*
G36*
G01X542411D02*
X542226Y1089609D01*
X541196D01*
X541011Y1090209D01*
Y1090383D01*
X542411D01*
Y1090209D01*
G37*
G36*
G01X544129Y1091998D02*
X544556Y1091538D01*
X544041Y1090646D01*
X543429Y1090786D01*
X543278Y1090873D01*
X543978Y1092085D01*
X544129Y1091998D01*
G37*
G36*
G01X545971Y1095187D02*
X546398Y1094727D01*
X545883Y1093835D01*
X545271Y1093975D01*
X545120Y1094062D01*
X545820Y1095274D01*
X545971Y1095187D01*
G37*
G36*
G01X538711Y1090209D02*
X538526Y1089609D01*
X537496D01*
X537311Y1090209D01*
Y1090383D01*
X538711D01*
Y1090209D01*
G37*
G36*
G01X542411D02*
X542226Y1089609D01*
X541196D01*
X541011Y1090209D01*
Y1090383D01*
X542411D01*
Y1090209D01*
G37*
G36*
G01X544129Y1091998D02*
X544556Y1091538D01*
X544041Y1090646D01*
X543429Y1090786D01*
X543278Y1090873D01*
X543978Y1092085D01*
X544129Y1091998D01*
G37*
G36*
G01X545971Y1095187D02*
X546398Y1094727D01*
X545883Y1093835D01*
X545271Y1093975D01*
X545120Y1094062D01*
X545820Y1095274D01*
X545971Y1095187D01*
G37*
G36*
G01X533587Y1101417D02*
X533772Y1102017D01*
X534802D01*
X534987Y1101417D01*
Y1101243D01*
X533587D01*
Y1101417D01*
G37*
G36*
G01D02*
X533772Y1102017D01*
X534802D01*
X534987Y1101417D01*
Y1101243D01*
X533587D01*
Y1101417D01*
G37*
G36*
G01X537451Y1102847D02*
X537024Y1103307D01*
X537539Y1104199D01*
X538151Y1104059D01*
X538302Y1103972D01*
X537602Y1102760D01*
X537451Y1102847D01*
G37*
G36*
G01X544688Y1107827D02*
X544873Y1108427D01*
X545903D01*
X546088Y1107827D01*
Y1107652D01*
X544688D01*
Y1107827D01*
G37*
G36*
G01X541011Y1107825D02*
X541196Y1108425D01*
X542226D01*
X542411Y1107825D01*
Y1107651D01*
X541011D01*
Y1107825D01*
G37*
G36*
G01X539293Y1106036D02*
X538866Y1106496D01*
X539381Y1107388D01*
X539993Y1107248D01*
X540144Y1107161D01*
X539444Y1105949D01*
X539293Y1106036D01*
G37*
G36*
G01X537451Y1102847D02*
X537024Y1103307D01*
X537539Y1104199D01*
X538151Y1104059D01*
X538302Y1103972D01*
X537602Y1102760D01*
X537451Y1102847D01*
G37*
G36*
G01X544688Y1107827D02*
X544873Y1108427D01*
X545903D01*
X546088Y1107827D01*
Y1107652D01*
X544688D01*
Y1107827D01*
G37*
G36*
G01X541011Y1107825D02*
X541196Y1108425D01*
X542226D01*
X542411Y1107825D01*
Y1107651D01*
X541011D01*
Y1107825D01*
G37*
G36*
G01X539293Y1106036D02*
X538866Y1106496D01*
X539381Y1107388D01*
X539993Y1107248D01*
X540144Y1107161D01*
X539444Y1105949D01*
X539293Y1106036D01*
G37*
G36*
G01X535011Y1096617D02*
X534826Y1096017D01*
X533796D01*
X533611Y1096617D01*
Y1096792D01*
X535011D01*
Y1096617D01*
G37*
G36*
G01D02*
X534826Y1096017D01*
X533796D01*
X533611Y1096617D01*
Y1096792D01*
X535011D01*
Y1096617D01*
G37*
G36*
G01X540429Y1098407D02*
X540856Y1097947D01*
X540341Y1097055D01*
X539729Y1097195D01*
X539578Y1097282D01*
X540278Y1098494D01*
X540429Y1098407D01*
G37*
G36*
G01X538711Y1096617D02*
X538526Y1096017D01*
X537496D01*
X537311Y1096617D01*
Y1096792D01*
X538711D01*
Y1096617D01*
G37*
G36*
G01X542279Y1101611D02*
X542706Y1101151D01*
X542191Y1100259D01*
X541579Y1100399D01*
X541428Y1100486D01*
X542128Y1101698D01*
X542279Y1101611D01*
G37*
G36*
G01X546136Y1103025D02*
X545951Y1102425D01*
X544921D01*
X544736Y1103025D01*
Y1103199D01*
X546136D01*
Y1103025D01*
G37*
G36*
G01X540429Y1098407D02*
X540856Y1097947D01*
X540341Y1097055D01*
X539729Y1097195D01*
X539578Y1097282D01*
X540278Y1098494D01*
X540429Y1098407D01*
G37*
G36*
G01X538711Y1096617D02*
X538526Y1096017D01*
X537496D01*
X537311Y1096617D01*
Y1096792D01*
X538711D01*
Y1096617D01*
G37*
G36*
G01X542279Y1101611D02*
X542706Y1101151D01*
X542191Y1100259D01*
X541579Y1100399D01*
X541428Y1100486D01*
X542128Y1101698D01*
X542279Y1101611D01*
G37*
G36*
G01X546136Y1103025D02*
X545951Y1102425D01*
X544921D01*
X544736Y1103025D01*
Y1103199D01*
X546136D01*
Y1103025D01*
G37*
G36*
G01X536861Y1099822D02*
X536676Y1099222D01*
X535646D01*
X535461Y1099822D01*
Y1099996D01*
X536861D01*
Y1099822D01*
G37*
G36*
G01D02*
X536676Y1099222D01*
X535646D01*
X535461Y1099822D01*
Y1099996D01*
X536861D01*
Y1099822D01*
G37*
G36*
G01X538579Y1101611D02*
X539006Y1101151D01*
X538491Y1100259D01*
X537879Y1100399D01*
X537728Y1100486D01*
X538428Y1101698D01*
X538579Y1101611D01*
G37*
G36*
G01X540421Y1104800D02*
X540848Y1104340D01*
X540333Y1103448D01*
X539721Y1103588D01*
X539570Y1103675D01*
X540270Y1104887D01*
X540421Y1104800D01*
G37*
G36*
G01X547986Y1106230D02*
X547801Y1105630D01*
X546771D01*
X546586Y1106230D01*
Y1106404D01*
X547986D01*
Y1106230D01*
G37*
G36*
G01X544285D02*
X544100Y1105630D01*
X543070D01*
X542885Y1106230D01*
Y1106404D01*
X544285D01*
Y1106230D01*
G37*
G36*
G01X538579Y1101611D02*
X539006Y1101151D01*
X538491Y1100259D01*
X537879Y1100399D01*
X537728Y1100486D01*
X538428Y1101698D01*
X538579Y1101611D01*
G37*
G36*
G01X540421Y1104800D02*
X540848Y1104340D01*
X540333Y1103448D01*
X539721Y1103588D01*
X539570Y1103675D01*
X540270Y1104887D01*
X540421Y1104800D01*
G37*
G36*
G01X547986Y1106230D02*
X547801Y1105630D01*
X546771D01*
X546586Y1106230D01*
Y1106404D01*
X547986D01*
Y1106230D01*
G37*
G36*
G01X544285D02*
X544100Y1105630D01*
X543070D01*
X542885Y1106230D01*
Y1106404D01*
X544285D01*
Y1106230D01*
G37*
G36*
G01X535461Y1098212D02*
X535646Y1098812D01*
X536676D01*
X536861Y1098212D01*
Y1098038D01*
X535461D01*
Y1098212D01*
G37*
G36*
G01D02*
X535646Y1098812D01*
X536676D01*
X536861Y1098212D01*
Y1098038D01*
X535461D01*
Y1098212D01*
G37*
G36*
G01X539293Y1099627D02*
X538866Y1100087D01*
X539381Y1100979D01*
X539993Y1100839D01*
X540144Y1100752D01*
X539444Y1099540D01*
X539293Y1099627D01*
G37*
G36*
G01X541151Y1102847D02*
X540724Y1103307D01*
X541239Y1104199D01*
X541851Y1104059D01*
X542002Y1103972D01*
X541302Y1102760D01*
X541151Y1102847D01*
G37*
G36*
G01X542838Y1104623D02*
X543023Y1105223D01*
X544053D01*
X544238Y1104623D01*
Y1104448D01*
X542838D01*
Y1104623D01*
G37*
G36*
G01X539293Y1099627D02*
X538866Y1100087D01*
X539381Y1100979D01*
X539993Y1100839D01*
X540144Y1100752D01*
X539444Y1099540D01*
X539293Y1099627D01*
G37*
G36*
G01X541151Y1102847D02*
X540724Y1103307D01*
X541239Y1104199D01*
X541851Y1104059D01*
X542002Y1103972D01*
X541302Y1102760D01*
X541151Y1102847D01*
G37*
G36*
G01X542838Y1104623D02*
X543023Y1105223D01*
X544053D01*
X544238Y1104623D01*
Y1104448D01*
X542838D01*
Y1104623D01*
G37*
G36*
G01X544129Y1098407D02*
X544556Y1097947D01*
X544041Y1097055D01*
X543429Y1097195D01*
X543278Y1097282D01*
X543978Y1098494D01*
X544129Y1098407D01*
G37*
G36*
G01D02*
X544556Y1097947D01*
X544041Y1097055D01*
X543429Y1097195D01*
X543278Y1097282D01*
X543978Y1098494D01*
X544129Y1098407D01*
G37*
G36*
G01X544851Y1096439D02*
X544424Y1096899D01*
X544939Y1097791D01*
X545551Y1097651D01*
X545702Y1097564D01*
X545002Y1096352D01*
X544851Y1096439D01*
G37*
G36*
G01D02*
X544424Y1096899D01*
X544939Y1097791D01*
X545551Y1097651D01*
X545702Y1097564D01*
X545002Y1096352D01*
X544851Y1096439D01*
G37*
G36*
G01X542993Y1099627D02*
X542566Y1100087D01*
X543081Y1100979D01*
X543693Y1100839D01*
X543844Y1100752D01*
X543144Y1099540D01*
X542993Y1099627D01*
G37*
G36*
G01X544711Y1101416D02*
X544896Y1102016D01*
X545926D01*
X546111Y1101416D01*
Y1101242D01*
X544711D01*
Y1101416D01*
G37*
G36*
G01X541143Y1096423D02*
X540716Y1096883D01*
X541231Y1097775D01*
X541843Y1097635D01*
X541994Y1097548D01*
X541294Y1096336D01*
X541143Y1096423D01*
G37*
G36*
G01X542993Y1099627D02*
X542566Y1100087D01*
X543081Y1100979D01*
X543693Y1100839D01*
X543844Y1100752D01*
X543144Y1099540D01*
X542993Y1099627D01*
G37*
G36*
G01X544711Y1101416D02*
X544896Y1102016D01*
X545926D01*
X546111Y1101416D01*
Y1101242D01*
X544711D01*
Y1101416D01*
G37*
G36*
G01X541143Y1096423D02*
X540716Y1096883D01*
X541231Y1097775D01*
X541843Y1097635D01*
X541994Y1097548D01*
X541294Y1096336D01*
X541143Y1096423D01*
G37*
G36*
G01X555345Y863393D02*
X555530Y863993D01*
X556560D01*
X556745Y863393D01*
Y863219D01*
X555345D01*
Y863393D01*
G37*
G36*
G01X551645D02*
X551830Y863993D01*
X552860D01*
X553045Y863393D01*
Y863219D01*
X551645D01*
Y863393D01*
G37*
G36*
G01X555345D02*
X555530Y863993D01*
X556560D01*
X556745Y863393D01*
Y863219D01*
X555345D01*
Y863393D01*
G37*
G36*
G01X551645D02*
X551830Y863993D01*
X552860D01*
X553045Y863393D01*
Y863219D01*
X551645D01*
Y863393D01*
G37*
G36*
G01X551229Y868205D02*
X551044Y867605D01*
X550014D01*
X549829Y868205D01*
Y868380D01*
X551229D01*
Y868205D01*
G37*
G36*
G01D02*
X551044Y867605D01*
X550014D01*
X549829Y868205D01*
Y868380D01*
X551229D01*
Y868205D01*
G37*
G36*
G01X551262Y861797D02*
X551077Y861197D01*
X550047D01*
X549862Y861797D01*
Y861971D01*
X551262D01*
Y861797D01*
G37*
G36*
G01X554962D02*
X554777Y861197D01*
X553747D01*
X553562Y861797D01*
Y861971D01*
X554962D01*
Y861797D01*
G37*
G36*
G01X551262D02*
X551077Y861197D01*
X550047D01*
X549862Y861797D01*
Y861971D01*
X551262D01*
Y861797D01*
G37*
G36*
G01X554962D02*
X554777Y861197D01*
X553747D01*
X553562Y861797D01*
Y861971D01*
X554962D01*
Y861797D01*
G37*
G36*
G01X549797Y853779D02*
X549982Y854379D01*
X551012D01*
X551197Y853779D01*
Y853605D01*
X549797D01*
Y853779D01*
G37*
G36*
G01D02*
X549982Y854379D01*
X551012D01*
X551197Y853779D01*
Y853605D01*
X549797D01*
Y853779D01*
G37*
G36*
G01X553045Y858593D02*
X552860Y857993D01*
X551830D01*
X551645Y858593D01*
Y858767D01*
X553045D01*
Y858593D01*
G37*
G36*
G01D02*
X552860Y857993D01*
X551830D01*
X551645Y858593D01*
Y858767D01*
X553045D01*
Y858593D01*
G37*
G36*
G01X551645Y856985D02*
X551830Y857585D01*
X552860D01*
X553045Y856985D01*
Y856811D01*
X551645D01*
Y856985D01*
G37*
G36*
G01D02*
X551830Y857585D01*
X552860D01*
X553045Y856985D01*
Y856811D01*
X551645D01*
Y856985D01*
G37*
G36*
G01X549862Y860189D02*
X550047Y860789D01*
X551077D01*
X551262Y860189D01*
Y860015D01*
X549862D01*
Y860189D01*
G37*
G36*
G01X553562D02*
X553747Y860789D01*
X554777D01*
X554962Y860189D01*
Y860015D01*
X553562D01*
Y860189D01*
G37*
G36*
G01X549862D02*
X550047Y860789D01*
X551077D01*
X551262Y860189D01*
Y860015D01*
X549862D01*
Y860189D01*
G37*
G36*
G01X553562D02*
X553747Y860789D01*
X554777D01*
X554962Y860189D01*
Y860015D01*
X553562D01*
Y860189D01*
G37*
G36*
G01X551262Y855387D02*
X551077Y854787D01*
X550047D01*
X549862Y855387D01*
Y855562D01*
X551262D01*
Y855387D01*
G37*
G36*
G01D02*
X551077Y854787D01*
X550047D01*
X549862Y855387D01*
Y855562D01*
X551262D01*
Y855387D01*
G37*
G36*
G01X552011Y869901D02*
X552297Y870460D01*
X553312Y870281D01*
X553390Y869658D01*
X553359Y869486D01*
X551981Y869730D01*
X552011Y869901D01*
G37*
G36*
G01D02*
X552297Y870460D01*
X553312Y870281D01*
X553390Y869658D01*
X553359Y869486D01*
X551981Y869730D01*
X552011Y869901D01*
G37*
G36*
G01X551681Y1048553D02*
X551496Y1047953D01*
X550466D01*
X550281Y1048553D01*
Y1048727D01*
X551681D01*
Y1048553D01*
G37*
G36*
G01D02*
X551496Y1047953D01*
X550466D01*
X550281Y1048553D01*
Y1048727D01*
X551681D01*
Y1048553D01*
G37*
G36*
G01X593882Y155572D02*
X596600D01*
X597270Y154902D01*
Y140762D01*
X596422Y139914D01*
X586418D01*
X585580Y140752D01*
Y154562D01*
X586590Y155572D01*
X591538D01*
G03X593882I1172J771D01*
G37*
G36*
G01X766400Y1269300D02*
X1039300D01*
X1041700Y1266900D01*
X1048241D01*
G02X1048561Y1266260I0J-400D01*
G03X1048281Y1265420I1122J-841D01*
G03X1051085I1402J0D01*
G03X1050805Y1266260I-1402J-1D01*
G02X1051125Y1266900I320J240D01*
G01X1061799D01*
G02X1062119Y1266260I0J-400D01*
G03X1061839Y1265420I1122J-841D01*
G03X1064643I1402J0D01*
G03X1064363Y1266260I-1402J-1D01*
G02X1064683Y1266900I320J240D01*
G01X1077941D01*
G02X1078261Y1266260I0J-400D01*
G03X1077981Y1265420I1122J-841D01*
G03X1080785I1402J0D01*
G03X1080505Y1266260I-1402J-1D01*
G02X1080825Y1266900I320J240D01*
G01X1091499D01*
G02X1091819Y1266260I0J-400D01*
G03X1091539Y1265420I1122J-841D01*
G03X1094343I1402J0D01*
G03X1094063Y1266260I-1402J-1D01*
G02X1094383Y1266900I320J240D01*
G01X1105759D01*
G03X1106740Y1266500I981J1003D01*
G03X1107667Y1266850I0J1403D01*
G01X1107724Y1266900D01*
X1108320D01*
Y1266600D01*
X1108240Y1266540D01*
G03X1107681Y1265420I843J-1120D01*
G03X1108041Y1264482I1402J0D01*
G02X1108034Y1263938I-297J-268D01*
G03X1107648Y1262972I1016J-966D01*
G03X1110452I1402J0D01*
G03X1110092Y1263910I-1402J0D01*
G02X1110099Y1264454I297J268D01*
G03X1110485Y1265420I-1016J966D01*
G03X1110205Y1266260I-1402J-1D01*
G02X1110525Y1266900I320J240D01*
G01X1117476D01*
X1121371Y1265286D01*
X1121304Y1265106D01*
G03X1121218Y1264622I1316J-483D01*
G03X1121347Y1264034I1402J-1D01*
G02X1120943Y1263469I-363J-167D01*
G03X1120800Y1263476I-140J-1395D01*
G03X1122202Y1262074I0J-1402D01*
G03X1122073Y1262662I-1402J1D01*
G02X1122477Y1263227I363J167D01*
G03X1122620Y1263220I140J1395D01*
G03X1123893Y1264033I0J1403D01*
G01X1123973Y1264208D01*
X1125500Y1263575D01*
Y1256900D01*
X1124700Y1256100D01*
X1103252D01*
G02X1102875Y1256634I0J400D01*
G03X1102956Y1257102I-1321J470D01*
G03X1100152I-1402J0D01*
G03X1100233Y1256634I1402J2D01*
G02X1099856Y1256100I-377J-134D01*
G01X1084200D01*
X1081300Y1253200D01*
X1060461D01*
G03X1058359I-1051J-928D01*
G01X1020761D01*
G03X1019983Y1253436I-778J-1166D01*
G03X1019205Y1253200I0J-1402D01*
G01X919900D01*
X900500Y1233800D01*
Y1010100D01*
X906800Y1003800D01*
X954900D01*
X956100Y1002600D01*
Y996200D01*
X954600Y994700D01*
X944700D01*
X942200Y992200D01*
Y974400D01*
X946550Y970050D01*
Y955350D01*
X901700Y910500D01*
Y789700D01*
X888284Y776284D01*
X865091Y763977D01*
X855953Y762502D01*
X855880Y762597D01*
G03X854687Y763187I-1193J-911D01*
G03X853267Y762175I0J-1502D01*
G01X853228Y762062D01*
X838461Y759678D01*
X838390Y759788D01*
G03X837127Y760478I-1263J-811D01*
G03X835672Y759349I0J-1502D01*
G01X835640Y759222D01*
X823860Y757320D01*
X823808Y757486D01*
G03X822374Y758541I-1434J-447D01*
G03X820872Y757039I0J-1502D01*
G01Y757012D01*
X820875Y756839D01*
X820410Y756764D01*
X765515Y758985D01*
X765200Y759300D01*
Y763954D01*
X765206Y763977D01*
G03X765249Y764335I-1459J357D01*
G03X765206Y764693I-1502J1D01*
G01X765200Y764716D01*
Y765561D01*
G03X765943Y766798I-658J1237D01*
G03X765897Y767156I-1402J2D01*
G01X765867Y767267D01*
X767798Y769198D01*
G02X768373Y769188I283J-283D01*
G03X769399Y768742I1026J957D01*
G03X770801Y770144I0J1402D01*
G03X770355Y771170I-1403J0D01*
G02X770345Y771745I273J292D01*
G01X770500Y771900D01*
X776912D01*
G02X777176Y771199I0J-400D01*
G03X776697Y770144I922J-1055D01*
G03X779501I1402J0D01*
G03X779022Y771199I-1401J0D01*
G02X779286Y771900I264J301D01*
G01X797912D01*
G02X798176Y771199I0J-400D01*
G03X797697Y770144I922J-1055D01*
G03X800501I1402J0D01*
G03X800022Y771199I-1401J0D01*
G02X800286Y771900I264J301D01*
G01X806612D01*
G02X806876Y771199I0J-400D01*
G03X806397Y770144I922J-1055D01*
G03X807799Y768742I1402J0D01*
G03X808973Y769377I0J1403D01*
G02X809632Y769393I335J-218D01*
G03X810850Y768770I1218J879D01*
G03X812352Y770272I0J1502D01*
G03X811997Y771242I-1503J0D01*
G02X812302Y771900I305J258D01*
G01X814054D01*
G02X814318Y771199I0J-400D01*
G03X813839Y770144I922J-1055D01*
G03X816643I1402J0D01*
G03X816164Y771199I-1401J0D01*
G02X816428Y771900I264J301D01*
G01X827612D01*
G02X827876Y771199I0J-400D01*
G03X827397Y770144I922J-1055D01*
G03X830201I1402J0D01*
G03X829722Y771199I-1401J0D01*
G02X829986Y771900I264J301D01*
G01X836312D01*
G02X836576Y771199I0J-400D01*
G03X836097Y770144I922J-1055D01*
G03X838901I1402J0D01*
G03X837724Y771528I-1402J0D01*
G02X837505Y772205I64J395D01*
G01X840300Y775000D01*
X843521D01*
G02X843836Y774354I0J-400D01*
G03X843539Y773491I1105J-863D01*
G03X846343I1402J0D01*
G03X846046Y774354I-1402J0D01*
G02X846361Y775000I315J246D01*
G01X852221D01*
G02X852536Y774354I0J-400D01*
G03X852239Y773491I1105J-863D01*
G03X855043I1402J0D01*
G03X854746Y774354I-1402J0D01*
G02X855061Y775000I315J246D01*
G01X859100D01*
X862522Y778422D01*
G02X863203Y778173I283J-283D01*
G03X864700Y776798I1497J127D01*
G03Y779802I0J1502D01*
G03X864389Y779770I-3J-1502D01*
G01X864283Y779747D01*
X864065Y779965D01*
X864400Y780300D01*
Y1237600D01*
X861700Y1240300D01*
X853800D01*
X846345Y1247755D01*
X846368Y1247861D01*
G03X846399Y1248155I-1371J293D01*
G03X844997Y1249557I-1402J0D01*
G03X844703Y1249526I-1J-1402D01*
G01X844597Y1249503D01*
X838763Y1255337D01*
G02X838780Y1255918I283J282D01*
G03X839248Y1256964I-935J1046D01*
G03X837846Y1258366I-1402J0D01*
G03X836444Y1256995I0J-1402D01*
G01X836440Y1256800D01*
X809787D01*
G02X809401Y1257303I0J400D01*
G03X809448Y1257664I-1355J360D01*
G03X806644I-1402J0D01*
G03X806691Y1257303I1402J-1D01*
G02X806305Y1256800I-386J-103D01*
G01X780147D01*
G02X779747Y1257214I0J400D01*
G03X779748Y1257264I-1401J53D01*
G03X776944I-1402J0D01*
G03X776945Y1257214I1402J3D01*
G02X776545Y1256800I-400J-14D01*
G01X767208D01*
G03X765088I-1060J-919D01*
G01X749689D01*
X749685Y1256995D01*
G03X746881I-1402J-31D01*
G01X746877Y1256800D01*
X720843D01*
G02X720444Y1257170I0J400D01*
G03X717648I-1398J-106D01*
G02X717249Y1256800I-399J30D01*
G01X707883D01*
X707842Y1256945D01*
G03X705144I-1349J-382D01*
G01X705103Y1256800D01*
X690322D01*
X690318Y1256995D01*
G03X687514I-1402J-31D01*
G01X687510Y1256800D01*
X677678D01*
G02X677316Y1257370I0J400D01*
G03X677448Y1257964I-1270J594D01*
G03X674644I-1402J0D01*
G03X674776Y1257370I1402J0D01*
G02X674414Y1256800I-362J-170D01*
G01X661287D01*
G02X660901Y1257303I0J400D01*
G03X660948Y1257664I-1355J360D01*
G03X658144I-1402J0D01*
G03X658191Y1257303I1402J-1D01*
G02X657805Y1256800I-386J-103D01*
G01X638278D01*
G02X637982Y1257469I0J400D01*
G03X638348Y1258414I-1037J945D01*
G03X637791Y1259533I-1403J0D01*
G02X637776Y1260159I241J319D01*
G03X638279Y1261235I-899J1076D01*
G03X635475I-1402J0D01*
G03X636032Y1260116I1403J0D01*
G02X636047Y1259490I-241J-319D01*
G03X635970Y1259421I897J-1078D01*
G02X635364Y1259480I-278J287D01*
G03X634213Y1260081I-1151J-802D01*
G03Y1257277I0J-1402D01*
G03X635189Y1257672I0J1403D01*
G02X635795Y1257613I278J-287D01*
G03X635910Y1257469I1151J801D01*
G02X635614Y1256800I-296J-269D01*
G01X628400D01*
X627000Y1258200D01*
Y1262300D01*
X628100Y1263400D01*
X630534D01*
G02X630877Y1262794I0J-400D01*
G03X630678Y1262074I1203J-720D01*
G03X633482I1402J0D01*
G03X633283Y1262794I-1402J0D01*
G02X633626Y1263400I343J206D01*
G01X658400D01*
X664150Y1269150D01*
X766250D01*
X766400Y1269300D01*
G37*
G36*
G01X739284Y135262D02*
X760120D01*
X761170Y134212D01*
X758425Y131467D01*
G03X758058Y130582I885J-886D01*
G01Y124170D01*
X750194Y116306D01*
G02X749516Y116525I-283J283D01*
G03X748033Y117790I-1483J-237D01*
G03X746531Y116288I0J-1502D01*
G03X747796Y114805I1502J0D01*
G02X748015Y114127I-64J-395D01*
G01X743260Y109372D01*
G02X742626Y109463I-283J282D01*
G03X741308Y110244I-1318J-722D01*
G03X739806Y108742I0J-1502D01*
G03X740587Y107424I1503J0D01*
G02X740678Y106790I-191J-351D01*
G01X738682Y104794D01*
X735900D01*
G03X735015Y104427I1J-1252D01*
G01X733750Y103162D01*
X728763D01*
G03X728028Y103370I-735J-1195D01*
G03X727337Y103188I0J-1403D01*
G01X727291Y103162D01*
X726720D01*
X721801Y98244D01*
X706930D01*
G03X706045Y97877I1J-1252D01*
G01X705330Y97162D01*
X673320D01*
X671520Y98962D01*
Y132962D01*
X673820Y135262D01*
X715928D01*
X715931Y135065D01*
G03X717433Y133586I1502J23D01*
G03X718618Y134165I0J1502D01*
G02X719248I315J-246D01*
G03X720433Y133586I1185J923D01*
G03X721935Y135065I0J1502D01*
G01X721938Y135262D01*
X737916D01*
X737957Y135243D01*
G03X738600Y135098I644J1357D01*
G03X739243Y135243I-1J1502D01*
G01X739284Y135262D01*
G37*
G36*
G01X959350Y1546218D02*
X959818Y1545750D01*
X966950D01*
X967620Y1546420D01*
Y1551311D01*
G03X969067Y1552862I-1717J3052D01*
G03X970402Y1554262I-67J1400D01*
G03X969160Y1555655I-1402J0D01*
G03X967882Y1557255I-3256J-1290D01*
G01Y1557972D01*
X969160Y1559250D01*
X981680D01*
X982650Y1558280D01*
Y1557469D01*
G03Y1551259I1620J-3105D01*
G01Y1546318D01*
X983118Y1545850D01*
X990350D01*
X991040Y1546540D01*
Y1551342D01*
G03X992433Y1552860I-1770J3022D01*
G01X992466D01*
G03X993868Y1554262I0J1402D01*
G03X992523Y1555663I-1402J0D01*
G03X991372Y1557166I-3253J-1299D01*
G01Y1558742D01*
X991870Y1559240D01*
X1005080D01*
X1005590Y1558730D01*
Y1557207D01*
G03X1004134Y1554364I2046J-2842D01*
G03X1005590Y1551521I3502J-1D01*
G01Y1546410D01*
X1006050Y1545950D01*
X1013850D01*
X1014330Y1546430D01*
Y1551298D01*
G03X1015806Y1552875I-1695J3065D01*
G03X1016009Y1552860I205J1387D01*
G01X1016012D01*
G03Y1555664I0J1402D01*
G03X1015890Y1555659I-4J-1402D01*
G03X1014632Y1557242I-3255J-1295D01*
G01Y1558212D01*
X1015840Y1559420D01*
X1028260D01*
X1029450Y1558230D01*
Y1557504D01*
G03Y1551224I1553J-3140D01*
G01Y1546018D01*
X1029618Y1545850D01*
X1036982D01*
X1037590Y1546458D01*
Y1551242D01*
G03X1039168Y1552866I-1589J3122D01*
G03X1039297Y1552860I130J1396D01*
G01X1039298D01*
G03Y1555664I0J1402D01*
G03X1039254Y1555663I10J-1402D01*
G03X1038012Y1557233I-3253J-1297D01*
G01Y1558962D01*
X1038550Y1559500D01*
X1051920D01*
X1052440Y1558980D01*
Y1557288D01*
G03Y1551440I1929J-2924D01*
G01Y1546260D01*
X1052850Y1545850D01*
X1060482D01*
X1061010Y1546378D01*
Y1551270D01*
G03X1062532Y1552862I-1643J3094D01*
G03X1063866Y1554262I-68J1400D01*
G03X1062623Y1555655I-1402J0D01*
G03X1061452Y1557179I-3257J-1290D01*
G01Y1558935D01*
X1062346Y1559830D01*
X1075350D01*
X1075740Y1559440D01*
Y1557243D01*
G03Y1551485I1994J-2879D01*
G01Y1546160D01*
X1076050Y1545850D01*
X1083850D01*
Y1545860D01*
X1084310Y1546320D01*
Y1551236D01*
G03X1085897Y1552862I-1578J3127D01*
G03X1087232Y1554262I-67J1400D01*
G03X1085990Y1555655I-1402J0D01*
G03X1084602Y1557327I-3256J-1291D01*
G01Y1558645D01*
X1085746Y1559790D01*
X1098830D01*
X1099450Y1559170D01*
Y1557129D01*
G03Y1551599I2151J-2765D01*
G01Y1526160D01*
X1098390Y1525100D01*
X1051010D01*
X1043484Y1517574D01*
X940929Y1526173D01*
G02X940638Y1526789I44J398D01*
G03X940882Y1527610I-1259J821D01*
G03X939380Y1529112I-1502J0D01*
G03X938393Y1528742I0J-1501D01*
G02X937867I-263J302D01*
G03X935893I-987J-1131D01*
G02X935367I-263J302D01*
G03X933393I-987J-1131D01*
G02X932867I-263J302D01*
G03X930893I-987J-1131D01*
G02X930367I-263J302D01*
G03X928393I-987J-1131D01*
G02X927867I-263J302D01*
G03X925893I-987J-1131D01*
G02X925367I-263J302D01*
G03X923393I-987J-1131D01*
G02X922867I-263J302D01*
G03X921880Y1529112I-987J-1131D01*
G03X920451Y1528073I0J-1502D01*
G01X920402Y1527922D01*
X731665Y1543925D01*
X729280Y1546310D01*
Y1563250D01*
X732030Y1566000D01*
Y1576560D01*
X732910Y1577440D01*
X756190D01*
X765210Y1568420D01*
X774080D01*
X783180Y1577520D01*
X797870D01*
X804640Y1570750D01*
X816230D01*
X822960Y1577480D01*
X839790D01*
X846950Y1570320D01*
X858170D01*
X865510Y1577660D01*
X881900D01*
X888450Y1571110D01*
X900800D01*
X907210Y1577520D01*
X941058D01*
X942500Y1576078D01*
Y1562598D01*
X943248Y1561850D01*
X958268D01*
X959350Y1560768D01*
Y1557503D01*
G03Y1551225I1555J-3139D01*
G01Y1546218D01*
G37*
G36*
G01X784829Y122846D02*
X793916D01*
X794100Y122662D01*
Y112362D01*
X780110Y98372D01*
Y89564D01*
X780109Y89555D01*
G03X780034Y87795I20678J-1763D01*
G03X780109Y86035I20753J3D01*
G01X780110Y86026D01*
Y71572D01*
X769598Y61060D01*
X759662Y59084D01*
X754229D01*
X754201Y59250D01*
G03X752720Y60504I-1481J-248D01*
G03X752467Y60483I-3J-1502D01*
G02X752000Y60877I-67J394D01*
G01Y69402D01*
X769100Y86502D01*
Y101588D01*
X770346Y102833D01*
G03X770786Y103895I-1062J1062D01*
G01Y106866D01*
G03X771276Y107977I-1012J1110D01*
G01Y108215D01*
X772276Y110628D01*
X780467Y118819D01*
X780519Y118833D01*
G03X781195Y119222I-385J1451D01*
G01X783735Y121762D01*
X783742Y121768D01*
G03X783843Y121860I-960J1155D01*
G01X784829Y122846D01*
G37*
G36*
G01X867800Y271932D02*
X875760D01*
X877600Y270092D01*
Y262232D01*
X876180Y260812D01*
X762560D01*
X759500Y263872D01*
Y270502D01*
X760930Y271932D01*
X783303D01*
G02X783702Y271504I0J-400D01*
G03X783698Y271400I1498J-110D01*
G03X786702I1502J0D01*
G03X786698Y271504I-1502J-6D01*
G02X787097Y271932I399J28D01*
G01X795542D01*
G02X795942Y271519I0J-400D01*
G03X795941Y271469I1501J-55D01*
G03X798945I1502J0D01*
G03X798944Y271519I-1502J-5D01*
G02X799344Y271932I400J13D01*
G01X827898D01*
G02X828298Y271538I0J-400D01*
G03X831302I1502J24D01*
G02X831702Y271932I400J-6D01*
G01X834795D01*
X834849Y271817D01*
G03X837571I1361J635D01*
G01X837625Y271932D01*
X838137D01*
G03X840763I1313J731D01*
G01X848293D01*
G02X848680Y271430I0J-400D01*
G03X848631Y271049I1453J-381D01*
G03X851635I1502J0D01*
G03X851586Y271430I-1502J0D01*
G02X851973Y271932I387J102D01*
G01X866674D01*
X866708Y271919D01*
G03X867237Y271823I528J1406D01*
G03X867766Y271919I1J1502D01*
G01X867800Y271932D01*
G37*
G36*
G01X774820Y450012D02*
X781240D01*
Y447003D01*
G02X780668Y446642I-400J0D01*
G03X780020Y446789I-648J-1355D01*
G03Y443785I0J-1502D01*
G03X780668Y443932I0J1502D01*
G02X781240Y443571I172J-361D01*
G01Y443153D01*
G02X780668Y442792I-400J0D01*
G03X780020Y442939I-648J-1355D01*
G03Y439935I0J-1502D01*
G03X780668Y440082I0J1502D01*
G02X781240Y439721I172J-361D01*
G01Y438400D01*
X780272Y437432D01*
X761697D01*
G02X761307Y437920I0J400D01*
G03X761342Y438232I-1367J311D01*
G03X760614Y439461I-1401J0D01*
G01X760510Y439518D01*
Y441136D01*
X760682Y441160D01*
G03Y444134I-213J1487D01*
G01X760510Y444158D01*
Y449530D01*
X773820D01*
G03X774705Y449897I-1J1252D01*
G01X774820Y450012D01*
G37*
G36*
G01X817460Y1718640D02*
X900700D01*
X907010Y1712330D01*
Y1681110D01*
X907035Y1681085D01*
Y1666625D01*
X917620Y1656040D01*
X1064400D01*
X1085560Y1634880D01*
X1102280D01*
X1103140Y1634020D01*
Y1607480D01*
X1102240Y1606580D01*
X944270D01*
X917600Y1633250D01*
X816320D01*
X812960Y1636610D01*
Y1714140D01*
X817460Y1718640D01*
G37*
G36*
G01X844263Y108782D02*
X852950D01*
X855640Y106092D01*
Y99262D01*
X853300Y96922D01*
X840072D01*
G02X839680Y97402I0J400D01*
G03X839758Y98179I-3813J775D01*
G01Y105871D01*
G02X839958Y106071I200J0D01*
G03X842692Y107210I-17J3891D01*
G01X844263Y108782D01*
G37*
G36*
G01X883862Y210962D02*
X896520D01*
X898120Y209362D01*
Y198562D01*
X904320Y192362D01*
X922934D01*
G03X924738I902J1201D01*
G01X936020D01*
X939000Y189382D01*
X938967Y189269D01*
G03X938908Y188852I1444J-417D01*
G03X940410Y187350I1502J0D01*
G03X940827Y187409I0J1503D01*
G01X940940Y187442D01*
X941420Y186962D01*
Y185996D01*
G02X940895Y185616I-400J0D01*
G03X940424Y185692I-472J-1426D01*
G03Y182688I0J-1502D01*
G03X940895Y182764I-1J1502D01*
G02X941420Y182384I125J-380D01*
G01Y181272D01*
X940310Y180162D01*
X923552D01*
G02X923246Y180820I0J400D01*
G03X923602Y181791I-1146J971D01*
G03X922096Y183293I-1502J0D01*
G02X921706Y183787I-1J400D01*
G03X921748Y184138I-1460J353D01*
G03X920246Y185640I-1502J0D01*
G03X919108Y185119I0J-1503D01*
G02X918507Y185114I-303J261D01*
G03X917386Y185616I-1121J-1001D01*
G03Y182612I0J-1502D01*
G03X918524Y183133I0J1503D01*
G02X919125Y183138I303J-261D01*
G03X920250Y182636I1121J1000D01*
G02X920640Y182142I1J-400D01*
G03X920598Y181791I1460J-353D01*
G03X920954Y180820I1502J0D01*
G02X920648Y180162I-306J-258D01*
G01X906974D01*
G03X902840Y183172I-6778J-4965D01*
G01X902795Y183187D01*
X902020Y183962D01*
X897920D01*
X896871Y182913D01*
X896837Y182898D01*
G03X892495Y178556I3359J-7701D01*
G01X892480Y178522D01*
X890220Y176262D01*
Y164462D01*
X887020Y161262D01*
X869820D01*
X869320Y161762D01*
Y196420D01*
X871144Y198244D01*
X871274Y198174D01*
G03X871980Y197998I706J1326D01*
G03X873482Y199500I0J1502D01*
G03X873306Y200206I-1502J0D01*
G01X873236Y200336D01*
X883862Y210962D01*
G37*
G36*
G01X971130Y203999D02*
X990270D01*
X991160Y203109D01*
Y185949D01*
X990934Y185723D01*
G02X990270Y185888I-282J283D01*
G03X988835Y186945I-1435J-446D01*
G03X987333Y185443I0J-1502D01*
G03X987522Y184713I1502J-1D01*
G02X987173Y184119I-350J-194D01*
G01X978940D01*
X968430Y173609D01*
Y163349D01*
X965770Y160689D01*
X957100D01*
X950260Y167529D01*
X938620D01*
X933870Y172279D01*
Y176589D01*
X934940Y177659D01*
X947480D01*
X948810Y178989D01*
Y183012D01*
G02X949191Y183412I400J0D01*
G03Y186412I-71J1500D01*
G02X948810Y186812I19J400D01*
G01Y190948D01*
G02X949281Y191341I400J0D01*
G03X949550Y191317I267J1478D01*
G03X951052Y192819I0J1502D01*
G03X950661Y193830I-1503J0D01*
G02X950957Y194499I296J269D01*
G01X961630D01*
X971130Y203999D01*
G37*
G36*
G01X947070Y971702D02*
X945750Y973022D01*
Y991872D01*
X946810Y992932D01*
X962950D01*
X964780Y991102D01*
Y973482D01*
X963000Y971702D01*
X947070D01*
G37*
G36*
G01X954650Y1727190D02*
X1097930D01*
X1098653Y1726467D01*
G02X1098532Y1725818I-282J-283D01*
G03X1096418Y1722570I1438J-3248D01*
G03X1099970Y1719018I3552J0D01*
G03X1102783Y1720402I0J3551D01*
G02X1103500Y1720157I317J-244D01*
G01Y1714983D01*
G02X1102783Y1714738I-400J-1D01*
G03X1099970Y1716122I-2813J-2167D01*
G03Y1709018I0J-3552D01*
G03X1102783Y1710402I0J3551D01*
G02X1103500Y1710157I317J-244D01*
G01Y1682110D01*
X1100710Y1679320D01*
X1082470D01*
X1078220Y1675070D01*
Y1664050D01*
X1076040Y1661870D01*
X958025D01*
G02X957767Y1662576I0J400D01*
G03X958302Y1663725I-966J1149D01*
G03X957558Y1665022I-1503J0D01*
G02X957516Y1665684I202J345D01*
G03X958102Y1666875I-917J1191D01*
G03X955098I-1502J0D01*
G03X955842Y1665578I1503J0D01*
G02X955884Y1664916I-202J-345D01*
G03X955362Y1664160I916J-1191D01*
G02X954697Y1663993I-383J116D01*
G01X949190Y1669500D01*
Y1721730D01*
X954650Y1727190D01*
G37*
G36*
G01X1014221Y155942D02*
G02X1013920Y156605I0J400D01*
G03X1014293Y157596I-1130J991D01*
G01Y157597D01*
G03X1013746Y158756I-1502J0D01*
G02X1013836Y159429I254J309D01*
G03X1014722Y160799I-616J1370D01*
G03X1011718I-1502J0D01*
G01Y160798D01*
G03X1012265Y159639I1502J0D01*
G02X1012175Y158966I-254J-309D01*
G03X1011289Y157596I616J-1370D01*
G03X1011662Y156605I1503J0D01*
G02X1011361Y155942I-301J-263D01*
G01X1009028D01*
X1006591Y158378D01*
G03X1005176Y158964I-1415J-1415D01*
G01X1003968D01*
G02X1003706Y159666I1J400D01*
G03X1004222Y160799I-986J1133D01*
G03X1001218I-1502J0D01*
G03X1002301Y159357I1502J0D01*
G01X1002446Y159315D01*
Y158964D01*
X1001638D01*
X1001235Y159367D01*
G03X999820Y159954I-1416J-1415D01*
G01X992090D01*
X988403Y163640D01*
G03X986988Y164226I-1415J-1415D01*
G01X971821D01*
G03X971387Y164179I-3J-2001D01*
G02X970900Y164569I-87J390D01*
G01Y174299D01*
X979640Y183039D01*
X990140D01*
X992680Y185579D01*
Y203929D01*
X991160Y205449D01*
X973940D01*
X973320Y206069D01*
Y210499D01*
X979614Y216793D01*
G02X980296Y216534I283J-283D01*
G03X981795Y215121I1499J89D01*
G03X983297Y216623I0J1502D01*
G03X981884Y218122I-1502J0D01*
G02X981625Y218804I24J399D01*
G01X984332Y221510D01*
X999730D01*
G02X1000038Y220856I0J-400D01*
G03X999693Y219898I1158J-958D01*
G03X1002697I1502J0D01*
G03X1002352Y220856I-1503J0D01*
G02X1002660Y221510I308J254D01*
G01X1013220D01*
G03X1015972Y222650I0J3892D01*
G01X1018521Y225200D01*
X1018656D01*
X1018710Y225164D01*
G03X1019188Y224961I817J1260D01*
G01X1019243Y224948D01*
X1019848Y224342D01*
Y223899D01*
X1019631D01*
X1019614Y223902D01*
G03X1019355Y223925I-262J-1479D01*
G03Y220921I0J-1502D01*
G03X1019429Y220923I-4J1502D01*
G02X1019848Y220524I19J-399D01*
G01Y220322D01*
G02X1019429Y219923I-400J0D01*
G03X1019355Y219925I-78J-1500D01*
G03Y216921I0J-1502D01*
G03X1019429Y216923I-4J1502D01*
G02X1019848Y216524I19J-399D01*
G01Y215794D01*
X1019667Y215595D01*
G03Y212603I135J-1496D01*
G01X1019848Y212404D01*
Y207862D01*
G03Y205064I87J-1399D01*
G01Y204732D01*
G03Y201934I87J-1399D01*
G01Y196291D01*
G03X1020145Y194802I3892J2D01*
G01X1021076Y192553D01*
G02X1020694Y192000I-369J-153D01*
G03X1020645Y192001I-55J-1501D01*
G03Y188997I0J-1502D01*
G03X1021741Y189472I0J1502D01*
G02X1022402Y189351I291J-274D01*
G01X1022583Y188916D01*
G03X1022615Y188840I3602J1472D01*
G01X1022616Y188839D01*
G03X1021818Y187574I604J-1265D01*
G03X1023220Y186172I1402J0D01*
G03X1023687Y186252I0J1403D01*
G01X1024873Y183388D01*
X1024874Y183386D01*
G03X1024908Y183300I3636J1388D01*
G01X1024991Y183101D01*
G03X1025831Y181847I3592J1498D01*
G01X1026520Y181159D01*
Y156681D01*
X1025780Y155942D01*
X1014221D01*
G37*
G36*
G01X1044008Y253114D02*
X1040891Y256231D01*
G03X1040485Y256502I-884J-885D01*
G01X1035526Y258556D01*
X1032035Y262047D01*
G02X1032188Y262709I282J283D01*
G03X1033204Y264130I-486J1421D01*
G03X1031702Y265632I-1502J0D01*
G03X1030281Y264616I0J-1502D01*
G02X1029619Y264463I-379J129D01*
G01X1028620Y265462D01*
X1025869D01*
G03X1024131I-869J-1099D01*
G01X1022869D01*
G03X1021131I-869J-1099D01*
G01X994620D01*
X989720Y270362D01*
X972320D01*
X970920Y271762D01*
Y296762D01*
X987320Y313162D01*
X1094328D01*
X1100000Y307490D01*
Y290600D01*
X1096160Y286760D01*
Y247982D01*
X1094240Y246062D01*
X1091520D01*
X1085320Y252262D01*
X1085090D01*
X1084605Y252747D01*
G03X1083720Y253114I-886J-885D01*
G01X1044008D01*
G37*
G36*
G01X967690Y353130D02*
X981066D01*
X982328Y351868D01*
Y340468D01*
X981628Y339768D01*
X970384D01*
X967528Y342624D01*
Y352968D01*
X967690Y353130D01*
G37*
G36*
G01X966660Y1564280D02*
X1140370D01*
X1143730Y1560920D01*
Y1549580D01*
X1143160Y1549010D01*
X1140330D01*
X1139550Y1549790D01*
Y1558370D01*
X1137065Y1560855D01*
X1102355D01*
X1102300Y1560910D01*
X1085450D01*
X1083600Y1559060D01*
Y1553970D01*
X1083080Y1553450D01*
X1082030D01*
X1081170Y1554310D01*
Y1559120D01*
X1079440Y1560850D01*
X1061950D01*
X1060450Y1559350D01*
Y1553800D01*
X1060100Y1553450D01*
X1058890D01*
X1058310Y1554030D01*
Y1559170D01*
X1056920Y1560560D01*
X1038110D01*
X1037010Y1559460D01*
Y1553680D01*
X1036490Y1553160D01*
X1035510D01*
X1034580Y1554090D01*
Y1559520D01*
X1033650Y1560450D01*
X1015370D01*
X1013630Y1558710D01*
Y1553910D01*
X1013170Y1553450D01*
X1012130D01*
X1011320Y1554260D01*
Y1558540D01*
X1009590Y1560270D01*
X991470D01*
X990370Y1559170D01*
Y1553970D01*
X989960Y1553560D01*
X988350D01*
X988170Y1553740D01*
Y1557670D01*
X985450Y1560390D01*
X968850D01*
X966880Y1558420D01*
Y1553970D01*
X966070Y1553160D01*
X965130D01*
X964610Y1553680D01*
Y1562230D01*
X966660Y1564280D01*
G37*
G36*
G01X1008815Y424162D02*
X1009620D01*
X1013020Y420762D01*
X1019757D01*
Y420560D01*
Y420548D01*
G03X1022761I1502J0D01*
G01Y420762D01*
X1036620D01*
X1037720Y419662D01*
Y408444D01*
X1037614Y408388D01*
G03X1036818Y407062I706J-1326D01*
G03X1036829Y406880I1502J-1D01*
G01X1036841Y406783D01*
X1035820Y405762D01*
X1001420D01*
X997882Y402224D01*
X997806Y402219D01*
G03X996401Y400814I94J-1499D01*
G01X996396Y400738D01*
X992520Y396862D01*
Y391262D01*
X991720Y390462D01*
X986220D01*
Y420262D01*
X990120Y424162D01*
X1005683D01*
G02X1006013Y423535I1J-400D01*
G03X1005747Y422682I1235J-853D01*
G03X1007249Y421180I1502J0D01*
G03X1007288Y421181I-19J1502D01*
G02X1007659Y420606I11J-400D01*
G03X1007507Y419948I1350J-658D01*
G03X1009009Y421450I1502J0D01*
G03X1008970Y421449I19J-1502D01*
G02X1008599Y422024I-11J400D01*
G03X1008751Y422682I-1350J658D01*
G03X1008485Y423535I-1501J0D01*
G02X1008815Y424162I329J227D01*
G37*
G36*
G01X990780Y153880D02*
Y155552D01*
G02X991193Y155952I400J0D01*
G03X991261Y155950I93J1999D01*
G01X998991D01*
X999394Y155548D01*
G03X1000809Y154962I1415J1415D01*
G01X1004347D01*
X1006784Y152525D01*
G03X1006893Y152424I1414J1416D01*
G02X1006946Y151874I-261J-303D01*
G03X1006627Y150948I1183J-926D01*
G03X1006779Y150289I1502J-1D01*
G02X1006420Y149714I-359J-175D01*
G01X1003239D01*
G02X1002874Y150275I1J400D01*
G03X1003002Y150883I-1374J607D01*
G03X999998I-1502J0D01*
G03X1000126Y150275I1502J-1D01*
G02X999761Y149714I-366J-161D01*
G01X996739D01*
G02X996374Y150275I1J400D01*
G03X996502Y150883I-1374J607D01*
G03X996081Y151926I-1502J0D01*
G02X996118Y152516I287J278D01*
G03X996682Y153689I-938J1173D01*
G03X993678I-1502J0D01*
G03X994099Y152646I1502J0D01*
G02X994062Y152056I-287J-278D01*
G03X993498Y150883I938J-1173D01*
G03X993626Y150275I1502J-1D01*
G02X993261Y149714I-366J-161D01*
G01X990780D01*
Y150914D01*
X990924Y150956D01*
G03Y153838I-423J1441D01*
G01X990780Y153880D01*
G37*
G36*
G01X1005920Y375662D02*
X1019020D01*
X1025720Y368962D01*
X1042920D01*
X1045120Y366762D01*
Y362962D01*
X1023205D01*
G02X1022888Y363605I0J400D01*
G03X1023197Y364518I-1194J913D01*
G03X1020193I-1502J0D01*
G03X1020502Y363605I1503J0D01*
G02X1020185Y362962I-317J-243D01*
G01X1007720D01*
X1004620Y366062D01*
Y374362D01*
X1005920Y375662D01*
G37*
G36*
G01X1239496Y50600D02*
G03X1237722I-887J-1211D01*
G01X1219496D01*
G03X1217722I-887J-1211D01*
G01X1199496D01*
G03X1197722I-887J-1211D01*
G01X1159496D01*
G03X1157722I-887J-1211D01*
G01X1139496D01*
G03X1137722I-887J-1211D01*
G01X1119496D01*
G03X1117722I-887J-1211D01*
G01X1099496D01*
G03X1097722I-887J-1211D01*
G01X1080319D01*
X1076995Y53924D01*
Y85454D01*
X1079269Y87728D01*
X1117129D01*
X1127655Y77202D01*
X1175259D01*
X1175331Y77172D01*
X1188944Y63559D01*
X1221466D01*
X1228384Y56641D01*
X1259934D01*
X1260589Y56511D01*
X1262608Y54492D01*
Y50784D01*
X1262424Y50600D01*
X1259496D01*
G03X1257722I-887J-1211D01*
G01X1239496D01*
G37*
G36*
G01X1546401Y1499348D02*
X1602954D01*
X1612917Y1489386D01*
G03X1613943Y1488960I1027J1025D01*
G01X1615303D01*
X1617075Y1487189D01*
G02X1616812Y1486506I-283J-283D01*
G01X1477106D01*
G03X1476426Y1486214I27J-1001D01*
G01X1438629Y1448416D01*
X1409893D01*
G03X1409213Y1448124I27J-1001D01*
G01X1407099Y1446009D01*
X1405834Y1444744D01*
G02X1405167Y1444968I-273J293D01*
G03X1403687Y1446213I-1480J-257D01*
G03X1402344Y1445385I0J-1503D01*
G02X1401630I-357J179D01*
G03X1400287Y1446213I-1343J-675D01*
G03Y1443209I0J-1502D01*
G03X1401630Y1444037I0J1503D01*
G02X1402344I357J-179D01*
G03X1403623Y1443210I1343J674D01*
G02X1403995Y1442718I-17J-399D01*
G03X1403960Y1442457I967J-263D01*
G01Y1430411D01*
X1398952Y1425403D01*
G03X1398658Y1424695I708J-709D01*
G01Y1401548D01*
G03X1398952Y1400840I1002J1D01*
G01X1404308Y1395484D01*
G03X1405016Y1395190I709J708D01*
G01X1409396D01*
Y1393522D01*
X1410560Y1392358D01*
X1410817D01*
X1411134Y1391992D01*
X1411121Y1391901D01*
G03X1411106Y1391689I1487J-212D01*
G01Y1391687D01*
G03X1412608Y1390185I1502J0D01*
G03X1413881Y1390889I0J1503D01*
G02X1414495Y1390947I331J-224D01*
G01X1415097Y1390345D01*
X1422263D01*
G03X1422264Y1390402I-3001J81D01*
G03X1423945Y1391932I-583J2329D01*
G01X1423965Y1391991D01*
X1424161Y1392134D01*
X1424254Y1392108D01*
G03X1426594Y1392723I643J2314D01*
G01X1428300Y1394429D01*
Y1398774D01*
G03X1428432Y1398788I-198J2494D01*
G01X1428457D01*
Y1400268D01*
X1441184D01*
X1448346Y1393106D01*
G03X1449054Y1392812I709J708D01*
G01X1461826D01*
G03X1462534Y1393106I-1J1002D01*
G01X1465158Y1395730D01*
X1470667D01*
G03X1471375Y1396023I0J1002D01*
G01X1475544Y1400192D01*
X1492843D01*
G03X1493551Y1400485I0J1002D01*
G01X1545343Y1452276D01*
X1616391D01*
X1628485Y1440183D01*
G03X1628810Y1439966I708J708D01*
G01X1629223Y1439795D01*
X1629254Y1439718D01*
G03X1630643Y1438788I1389J572D01*
G03X1632145Y1440290I0J1502D01*
G03X1631660Y1441396I-1502J1D01*
G02Y1441984I270J294D01*
G03X1632145Y1443090I-1017J1105D01*
G03X1630643Y1444592I-1502J0D01*
G03X1629660Y1444225I1J-1502D01*
G02X1629387Y1444235I-131J151D01*
G01X1618136Y1455486D01*
G03X1617428Y1455780I-709J-708D01*
G01X1544306D01*
G03X1543598Y1455486I1J-1002D01*
G01X1491939Y1403828D01*
X1474476D01*
G03X1473768Y1403534I1J-1002D01*
G01X1469466Y1399232D01*
X1464121D01*
G03X1463413Y1398939I0J-1002D01*
G01X1460789Y1396316D01*
X1450091D01*
X1446003Y1400403D01*
X1442909Y1403498D01*
G03X1442201Y1403791I-708J-709D01*
G01X1436271Y1403790D01*
X1428846D01*
Y1404097D01*
X1428938Y1404189D01*
Y1407844D01*
X1428300Y1408482D01*
Y1408770D01*
X1428012D01*
X1427827Y1408956D01*
X1426136D01*
X1424212Y1410880D01*
X1423270D01*
X1422974Y1411357D01*
X1423023Y1411457D01*
G03X1423177Y1412119I-1348J662D01*
G03X1421675Y1413621I-1502J0D01*
G03X1420603Y1413170I1J-1502D01*
G01X1415818Y1417954D01*
Y1419603D01*
X1415562Y1420081D01*
G02X1414990Y1422403I4429J2322D01*
G01Y1422404D01*
G02X1415582Y1424763I5001J-1D01*
G01X1415818Y1425205D01*
Y1425579D01*
X1415989Y1425681D01*
X1417922Y1427614D01*
X1418252D01*
G02X1418606Y1427028I0J-400D01*
G03X1418433Y1426328I1330J-700D01*
G03X1418997Y1425155I1502J0D01*
G02X1419021Y1424550I-250J-313D01*
G03X1418489Y1423404I970J-1147D01*
G03X1421493I1502J0D01*
G03X1420924Y1424581I-1502J0D01*
G02X1420917Y1425192I255J308D01*
G03X1421437Y1426328I-981J1136D01*
G03X1421035Y1427351I-1503J0D01*
G02X1421045Y1427906I293J272D01*
G01X1422421Y1429282D01*
G03X1422451Y1429309I-990J1130D01*
G03X1422560Y1429419I-1011J1111D01*
G01X1422564Y1429424D01*
X1423230Y1430090D01*
Y1432592D01*
X1423807Y1432842D01*
X1423903Y1432752D01*
G03X1424929Y1432347I1026J1098D01*
G01X1424930D01*
G03Y1435353I0J1503D01*
G03X1423481Y1434248I0J-1503D01*
G01X1422931Y1434124D01*
X1422242Y1434814D01*
Y1437031D01*
X1421059Y1438214D01*
X1418470D01*
X1417326Y1437069D01*
Y1436346D01*
X1415342D01*
G02X1414942Y1436752I0J400D01*
G01Y1436774D01*
G03X1411938I-1502J0D01*
G01Y1436771D01*
G03X1412011Y1436310I1502J2D01*
G03X1411592Y1436030I613J-1371D01*
G03X1410723Y1436007I-372J-2373D01*
G03X1410038Y1436172I-684J-1337D01*
G03X1409353Y1436007I-1J-1502D01*
G03X1409145Y1436021I-205J-1488D01*
G03X1408133Y1435629I0J-1502D01*
G02X1407464Y1435924I-269J296D01*
G01Y1440895D01*
X1410136Y1443568D01*
X1411482Y1444914D01*
X1439694D01*
G03X1440374Y1445206I-27J1001D01*
G01X1478171Y1483004D01*
X1621260D01*
X1622546Y1481718D01*
X1675924D01*
X1679004Y1478638D01*
X1685120Y1472521D01*
Y1457425D01*
X1683285Y1455590D01*
X1668569D01*
G03X1667861Y1455296I1J-1002D01*
G01X1663118Y1450553D01*
G03X1662825Y1449845I709J-708D01*
G01Y1444375D01*
G03X1663118Y1443667I1002J0D01*
G01X1666279Y1440506D01*
G03X1666987Y1440213I708J709D01*
G01X1667276Y1440214D01*
X1667304Y1440046D01*
G03X1668786Y1438788I1482J244D01*
G03X1670288Y1440290I0J1502D01*
G03X1669714Y1441471I-1502J0D01*
G02Y1442075I263J302D01*
G03X1670288Y1443256I-928J1181D01*
G03X1668786Y1444758I-1502J0D01*
G03X1667711Y1444305I0J-1502D01*
G01X1667664Y1444258D01*
X1667483D01*
X1666715Y1445026D01*
X1666328Y1445412D01*
Y1448808D01*
X1667426Y1449906D01*
X1669607Y1452086D01*
X1684323D01*
G03X1685031Y1452380I-1J1002D01*
G01X1688330Y1455679D01*
G03X1688624Y1456387I-708J709D01*
G01Y1473559D01*
G03X1688330Y1474267I-1002J-1D01*
G01X1681551Y1481045D01*
G02X1681844Y1481718I293J273D01*
G01X1686102D01*
X1711196Y1456624D01*
Y1424659D01*
X1718300Y1417555D01*
Y1313062D01*
X1715247Y1310009D01*
X1506087D01*
X1494746Y1298668D01*
X1475236D01*
X1462346Y1285778D01*
X1350726D01*
X1325178Y1311326D01*
X1270736D01*
X1228270Y1353792D01*
X1226383D01*
G03X1225625Y1354000I-760J-1284D01*
G01X1182728D01*
G02X1182438Y1354675I0J400D01*
G03X1183402Y1357088I-2538J2413D01*
G03X1176398I-3502J0D01*
G03X1177363Y1354674I3502J0D01*
G02X1177072Y1354000I-291J-274D01*
G01X1158328D01*
G02X1158038Y1354675I0J400D01*
G03X1159002Y1357088I-2538J2413D01*
G03X1151998I-3502J0D01*
G03X1152963Y1354674I3502J0D01*
G02X1152672Y1354000I-291J-274D01*
G01X1133769D01*
X1133513Y1354044D01*
X1133249Y1354091D01*
X1133296Y1354359D01*
X1133352Y1354406D01*
G03X1134602Y1357088I-2252J2682D01*
G03X1131100Y1360590I-3502J0D01*
G03X1127598Y1357103I0J-3502D01*
G01Y1357087D01*
G03X1128071Y1355330I3502J1D01*
G02X1127864Y1355033I-173J-100D01*
G01X1127491Y1355098D01*
X1126896Y1355344D01*
X1126618Y1355459D01*
X1108000Y1374077D01*
Y1497042D01*
X1110306Y1499348D01*
X1265904D01*
X1299401Y1465851D01*
G03X1300286Y1465484I885J884D01*
G01X1349807D01*
X1363034Y1452257D01*
G03X1363919Y1451890I885J884D01*
G01X1366340D01*
G03X1367173Y1451640I830J1252D01*
G01X1367205D01*
G03X1368672Y1453142I-35J1502D01*
G03X1367170Y1454644I-1502J0D01*
G03X1366841Y1454608I-2J-1502D01*
G02X1366356Y1455035I-87J390D01*
G03X1366362Y1455172I-1496J134D01*
G03X1365634Y1456459I-1502J0D01*
G01X1365613Y1456472D01*
X1352622Y1469462D01*
G03X1352567Y1469515I-1034J-1018D01*
G03X1352493Y1469578I-978J-1073D01*
G01X1352387Y1469662D01*
X1352493Y1470022D01*
X1361917D01*
X1363970Y1467970D01*
X1369561Y1462378D01*
G02X1369427Y1461745I-297J-268D01*
G03X1368539Y1460374I614J-1371D01*
G03X1370041Y1458872I1502J0D01*
G03X1370414Y1458919I0J1502D01*
G01X1370426Y1458922D01*
G02X1370928Y1458536I102J-386D01*
G01Y1446633D01*
X1358624Y1434328D01*
G03X1358198Y1433302I1025J-1027D01*
G01Y1424132D01*
G03X1358624Y1423106I1451J1D01*
G01X1362668Y1419061D01*
Y1397862D01*
G03X1363094Y1396836I1451J1D01*
G01X1366928Y1393002D01*
G03X1367954Y1392576I1027J1025D01*
G01X1376669D01*
X1376693Y1392570D01*
G03X1377054Y1392526I361J1459D01*
G03Y1395530I0J1502D01*
G03X1376693Y1395486I0J-1503D01*
G01X1376669Y1395480D01*
X1368555D01*
X1367162Y1396873D01*
G02X1367418Y1397554I283J282D01*
G03X1368818Y1399053I-103J1499D01*
G03X1367316Y1400555I-1502J0D01*
G03X1366249Y1400110I0J-1502D01*
G02X1365572Y1400398I-277J288D01*
G01Y1402113D01*
G02X1366249Y1402401I400J0D01*
G03X1367316Y1401956I1067J1057D01*
G03Y1404960I0J1502D01*
G03X1366249Y1404515I0J-1502D01*
G02X1365572Y1404803I-277J288D01*
G01Y1406113D01*
G02X1366249Y1406401I400J0D01*
G03X1367316Y1405956I1067J1057D01*
G03Y1408960I0J1502D01*
G03X1366249Y1408515I0J-1502D01*
G02X1365572Y1408803I-277J288D01*
G01Y1414106D01*
G02X1365913Y1414248I200J0D01*
G01X1366137Y1414025D01*
G03X1367436Y1413276I1299J752D01*
G03X1368938Y1414778I0J1502D01*
G03X1368189Y1416077I-1501J0D01*
G01X1367322Y1416944D01*
Y1417360D01*
G02X1367746Y1417740I400J-20D01*
G03X1367889Y1417733I145J1495D01*
G03X1369381Y1419059I0J1502D01*
G01X1369387Y1419116D01*
G03X1369392Y1419235I-1498J123D01*
G03X1369237Y1419900I-1504J0D01*
G02X1369589Y1420448I372J148D01*
G01X1370190D01*
X1370214Y1420442D01*
G03X1370577Y1420397I365J1457D01*
G03Y1423401I0J1502D01*
G03X1370214Y1423356I2J-1502D01*
G01X1370190Y1423350D01*
X1368344D01*
X1366259Y1425436D01*
X1365492Y1426203D01*
G02X1365755Y1426886I283J283D01*
G01X1375890D01*
G02X1376123Y1426176I-20J-400D01*
G03X1375573Y1425014I952J-1162D01*
G03X1378577I1502J0D01*
G03X1378027Y1426176I-1502J0D01*
G02X1378260Y1426886I253J310D01*
G01X1379035D01*
G03X1380273Y1427399I0J1750D01*
G01X1386214Y1433340D01*
G03X1386634Y1434014I-1238J1239D01*
G03X1386728Y1434578I-1657J566D01*
G01Y1499348D01*
X1439402D01*
G02X1439684Y1498665I0J-400D01*
G01X1395221Y1454201D01*
G03X1394796Y1453175I1026J-1026D01*
G01Y1444926D01*
X1391031Y1441161D01*
G03X1390606Y1440135I1026J-1026D01*
G01Y1430910D01*
X1386754Y1427058D01*
G03X1386328Y1426032I1025J-1027D01*
G01Y1423182D01*
G03X1386754Y1422156I1451J1D01*
G01X1389616Y1419294D01*
Y1415442D01*
X1387455D01*
X1387431Y1415448D01*
G03X1387068Y1415493I-365J-1457D01*
G03Y1412489I0J-1502D01*
G03X1387431Y1412534I-2J1502D01*
G01X1387455Y1412540D01*
X1390343D01*
G03X1391369Y1412965I0J1451D01*
G01X1392093Y1413689D01*
G03X1392518Y1414715I-1026J1026D01*
G01Y1419895D01*
G03X1392093Y1420921I-1451J0D01*
G01X1391250Y1421765D01*
X1390940Y1422075D01*
G02X1390993Y1422686I283J283D01*
G03X1391672Y1423942I-822J1256D01*
G03X1390202Y1425444I-1502J0D01*
G02X1389927Y1426126I8J400D01*
G01X1390776Y1426975D01*
X1393083Y1429283D01*
G03X1393508Y1430309I-1026J1026D01*
G01Y1439534D01*
X1397273Y1443299D01*
G03X1397698Y1444325I-1026J1026D01*
G01Y1452574D01*
X1444088Y1498964D01*
X1545417D01*
G03X1546401Y1499348I1J1451D01*
G37*
G36*
G01X1103810Y1550570D02*
X1105660D01*
X1107340Y1548890D01*
Y1546500D01*
X1114050Y1539790D01*
X1141720D01*
X1143850Y1541920D01*
X1146550D01*
X1146810Y1541660D01*
Y1539570D01*
X1143890Y1536650D01*
X1112760D01*
X1103580Y1545830D01*
Y1550340D01*
X1103810Y1550570D01*
G37*
G36*
G01X1196600Y313662D02*
X1272200D01*
X1288818Y297044D01*
X1288823Y296968D01*
G03X1289451Y295832I1499J87D01*
G02X1289384Y295142I-232J-326D01*
G03X1288498Y293768I622J-1374D01*
G03X1290005Y292260I1508J0D01*
G03X1291487Y293490I0J1508D01*
G02X1292163Y293699I393J-74D01*
G01X1296400Y289462D01*
Y274062D01*
X1310400Y260062D01*
X1318644D01*
G02X1319010Y259502I0J-400D01*
G03X1318912Y259183I1378J-598D01*
G02X1318387Y258880I-393J75D01*
G03X1317893Y258964I-495J-1418D01*
G03Y255960I0J-1502D01*
G03X1319368Y257180I0J1502D01*
G02X1319893Y257483I393J-75D01*
G03X1320387Y257399I495J1418D01*
G03X1321889Y258901I0J1502D01*
G03X1321764Y259502I-1502J1D01*
G02X1322130Y260062I366J160D01*
G01X1323986D01*
G02X1324361Y259523I0J-400D01*
G03X1324267Y259001I1408J-523D01*
G03X1327271I1502J0D01*
G03X1327177Y259523I-1502J-1D01*
G02X1327552Y260062I375J139D01*
G01X1335800D01*
X1353300Y242562D01*
Y222118D01*
G02X1352825Y221725I-400J0D01*
G03X1352561Y221750I-264J-1377D01*
G03Y218946I0J-1402D01*
G03X1352825Y218971I0J1402D01*
G02X1353300Y218578I75J-393D01*
G01Y218418D01*
G02X1352825Y218025I-400J0D01*
G03X1352561Y218050I-264J-1377D01*
G03Y215246I0J-1402D01*
G03X1352825Y215271I0J1402D01*
G02X1353300Y214878I75J-393D01*
G01Y214718D01*
G02X1352825Y214325I-400J0D01*
G03X1352561Y214350I-264J-1377D01*
G03Y211546I0J-1402D01*
G03X1353494Y211901I1J1402D01*
G01X1353635Y212027D01*
X1356183Y209479D01*
G02X1355870Y208797I-282J-283D01*
G03X1355765Y208801I-106J-1398D01*
G03Y205997I0J-1402D01*
G03X1356895Y206569I0J1402D01*
G02X1357583Y206493I322J-237D01*
G03X1358814Y205659I1282J567D01*
G02X1359200Y205259I-14J-400D01*
G01Y204921D01*
G02X1358814Y204521I-400J0D01*
G03X1357784Y204012I52J-1401D01*
G02X1357096Y204141I-308J255D01*
G03X1355765Y205101I-1331J-443D01*
G03Y202297I0J-1402D01*
G03X1356846Y202807I0J1401D01*
G02X1357534Y202678I308J-255D01*
G03X1358814Y201719I1331J442D01*
G02X1359200Y201319I-14J-400D01*
G01Y200981D01*
G02X1358814Y200581I-400J0D01*
G03Y197779I51J-1401D01*
G02X1359200Y197379I-14J-400D01*
G01Y197041D01*
G02X1358814Y196641I-400J0D01*
G03Y193839I51J-1401D01*
G02X1359200Y193439I-14J-400D01*
G01Y190528D01*
G02X1358705Y190140I-400J0D01*
G03X1358371Y190180I-333J-1362D01*
G03X1357400Y189789I0J-1401D01*
G02X1356821Y189816I-277J289D01*
G03X1355761Y190300I-1060J-919D01*
G03Y187496I0J-1402D01*
G03X1356732Y187887I0J1401D01*
G02X1357311Y187860I277J-289D01*
G03X1358371Y187376I1060J919D01*
G03X1358705Y187416I1J1402D01*
G02X1359200Y187028I95J-388D01*
G01Y184285D01*
G02X1358814Y183885I-400J0D01*
G03Y181083I51J-1401D01*
G02X1359200Y180683I-14J-400D01*
G01Y180345D01*
G02X1358814Y179945I-400J0D01*
G03X1357505Y178886I51J-1401D01*
G02X1356816Y178721I-388J98D01*
G03X1355761Y179200I-1055J-922D01*
G03Y176396I0J-1402D01*
G03X1357121Y177456I0J1402D01*
G02X1357810Y177621I388J-98D01*
G03X1358814Y177143I1055J923D01*
G02X1359200Y176743I-14J-400D01*
G01Y176404D01*
G02X1358814Y176004I-400J0D01*
G03X1357548Y175082I51J-1401D01*
G02X1356859Y174970I-376J137D01*
G03X1355761Y175500I-1098J-872D01*
G03Y172696I0J-1402D01*
G03X1357078Y173619I0J1401D01*
G02X1357767Y173731I376J-137D01*
G03X1358814Y173202I1098J872D01*
G02X1359200Y172802I-14J-400D01*
G01Y172472D01*
G02X1358814Y172072I-400J0D01*
G03X1357596Y171267I51J-1401D01*
G02X1356907Y171206I-362J169D01*
G03X1355761Y171800I-1146J-808D01*
G03Y168996I0J-1402D01*
G03X1357030Y169802I0J1402D01*
G02X1357719Y169863I362J-169D01*
G03X1358814Y169270I1146J808D01*
G02X1359200Y168870I-14J-400D01*
G01Y168533D01*
G02X1358814Y168133I-400J0D01*
G03X1357650Y167432I51J-1401D01*
G02X1356961Y167424I-347J199D01*
G03X1355762Y168100I-1199J-725D01*
G03Y165296I0J-1402D01*
G03X1356977Y165998I0J1402D01*
G02X1357666Y166006I347J-199D01*
G03X1357929Y165688I1200J725D01*
G02X1357945Y165107I-267J-298D01*
G01X1356798Y163960D01*
X1356657Y164076D01*
G03X1355761Y164400I-896J-1077D01*
G03X1354359Y162998I0J-1402D01*
G03X1354683Y162102I1401J0D01*
G01X1354799Y161961D01*
X1354466Y161628D01*
G02X1353821Y161742I-283J283D01*
G03X1352551Y162550I-1270J-594D01*
G03Y159746I0J-1402D01*
G03X1352900Y159790I1J1402D01*
G02X1353400Y159403I100J-387D01*
G01Y159194D01*
G02X1352900Y158807I-400J0D01*
G03X1352550Y158851I-349J-1358D01*
G03Y156047I0J-1402D01*
G03X1352900Y156091I1J1402D01*
G02X1353400Y155704I100J-387D01*
G01Y134462D01*
X1354600Y133262D01*
Y130975D01*
X1353566Y129428D01*
X1341300Y117162D01*
Y111071D01*
X1337858Y105920D01*
X1336300Y104362D01*
X1329100D01*
X1326900Y106562D01*
Y109762D01*
X1317000Y119662D01*
X1308134D01*
G03X1306354I-890J-1210D01*
G01X1304573D01*
X1304046Y120188D01*
G03X1303020Y120614I-1027J-1025D01*
G01X1299620D01*
G03X1298871Y120405I1J-1452D01*
G01X1298737Y120325D01*
X1291000Y128062D01*
Y134862D01*
X1286283Y139579D01*
G02X1286400Y140226I282J283D01*
G03X1287260Y141562I-608J1336D01*
G03X1284326I-1467J0D01*
G03X1284433Y141012I1467J0D01*
G02X1284062Y140462I-371J-150D01*
G01X1279322D01*
Y140664D01*
Y140682D01*
G03X1276318I-1502J0D01*
G01Y140462D01*
X1251700D01*
X1249400Y142762D01*
Y158262D01*
X1251200Y160062D01*
X1270124D01*
G02X1270509Y159553I0J-400D01*
G03X1270452Y159143I1446J-410D01*
G03X1273456I1502J0D01*
G03X1273399Y159553I-1503J0D01*
G02X1273784Y160062I385J109D01*
G01X1292037D01*
G02X1292429Y159581I0J-400D01*
G03X1292400Y159299I1373J-284D01*
G03X1295204I1402J0D01*
G03X1295175Y159581I-1402J-2D01*
G02X1295567Y160062I392J81D01*
G01X1296122D01*
G03X1297892I885J1086D01*
G01X1298400D01*
X1299955Y161617D01*
X1300052Y161606D01*
G03X1300213Y161597I159J1393D01*
G03X1301615Y162999I0J1402D01*
G03X1301606Y163160I-1402J2D01*
G01X1301595Y163257D01*
X1302308Y163970D01*
X1302449Y163835D01*
G03X1303417Y163447I968J1014D01*
G03X1304819Y164849I0J1402D01*
G03X1304431Y165817I-1402J0D01*
G01X1304296Y165958D01*
X1304662Y166324D01*
G02X1305317Y166187I283J-283D01*
G03X1306622Y165297I1305J512D01*
G03X1308024Y166699I0J1402D01*
G03X1307134Y168004I-1402J0D01*
G02X1306997Y168659I146J372D01*
G01X1309289Y170951D01*
X1309405Y170914D01*
G03X1309832Y170847I428J1335D01*
G03X1311234Y172249I0J1402D01*
G03X1311167Y172676I-1402J-1D01*
G01X1311130Y172792D01*
X1311461Y173123D01*
G02X1312030Y173120I283J-283D01*
G03X1313033Y172697I1003J978D01*
G03Y175501I0J1402D01*
G03X1312307Y175298I1J-1402D01*
G02X1311700Y175641I-207J342D01*
G01Y183654D01*
G02X1312306Y183997I400J0D01*
G03X1313027Y183797I722J1202D01*
G03Y186601I0J1402D01*
G03X1312306Y186401I1J-1402D01*
G02X1311700Y186744I-206J343D01*
G01Y187353D01*
G02X1312305Y187696I400J0D01*
G03X1313025Y187497I720J1203D01*
G03Y190301I0J1402D01*
G03X1312305Y190102I0J-1402D01*
G02X1311700Y190445I-205J343D01*
G01Y198451D01*
G02X1312305Y198795I400J0D01*
G03X1313023Y198597I718J1203D01*
G03Y201401I0J1402D01*
G03X1312305Y201203I0J-1401D01*
G02X1311700Y201547I-205J344D01*
G01Y213257D01*
G02X1312307Y213599I400J0D01*
G03X1313032Y213397I725J1200D01*
G03Y216201I0J1402D01*
G03X1312307Y215999I0J-1402D01*
G02X1311700Y216341I-207J342D01*
G01Y219662D01*
X1311222Y220140D01*
X1311230Y220232D01*
G03X1311235Y220349I-1397J118D01*
G03X1309833Y221751I-1402J0D01*
G03X1309716Y221746I1J-1402D01*
G01X1309624Y221738D01*
X1309391Y221971D01*
G02X1309708Y222652I283J283D01*
G03X1309828Y222647I118J1397D01*
G03X1308426Y224049I0J1402D01*
G03X1308431Y223929I1402J-2D01*
G02X1307750Y223612I-398J-34D01*
G01X1295200Y236162D01*
X1295180D01*
G02X1294910Y236856I1J400D01*
G03X1295395Y237962I-1017J1105D01*
G03X1294301Y239407I-1501J0D01*
G02X1294036Y239933I109J385D01*
G03X1294132Y240462I-1406J528D01*
G03X1291128I-1502J0D01*
G03X1292222Y239017I1501J0D01*
G02X1292487Y238491I-109J-385D01*
G03X1292391Y237962I1406J-528D01*
G03X1292876Y236856I1502J-1D01*
G02X1292606Y236162I-271J-294D01*
G01X1265800D01*
X1262700Y239262D01*
Y257662D01*
X1265100Y260062D01*
X1278700D01*
X1281700Y263062D01*
X1281900D01*
X1283600Y264762D01*
Y268280D01*
G03Y270612I-947J1166D01*
G01Y289962D01*
X1271900Y301662D01*
X1217300D01*
X1208100Y292462D01*
X1196000D01*
X1194400Y294062D01*
Y311462D01*
X1196600Y313662D01*
G37*
G36*
G01X1382485Y930620D02*
X1386339D01*
X1388696Y928263D01*
Y920329D01*
G02X1388208Y919939I-400J0D01*
G03X1387921Y919971I-287J-1269D01*
G03Y917369I0J-1301D01*
G03X1388208Y917401I0J1301D01*
G02X1388696Y917011I88J-390D01*
G01Y916199D01*
G03Y914733I1076J-733D01*
G01Y913921D01*
G02X1388208Y913531I-400J0D01*
G03X1387920Y913563I-287J-1269D01*
G03Y910961I0J-1301D01*
G03X1388208Y910993I1J1301D01*
G02X1388696Y910603I88J-390D01*
G01Y909790D01*
G03Y908324I1076J-733D01*
G01Y905299D01*
X1388446Y905049D01*
X1385357D01*
Y905045D01*
X1383869Y903557D01*
G02X1383300Y903560I-283J283D01*
G03X1382371Y903950I-929J-911D01*
G03X1381070Y902649I0J-1301D01*
G03X1381460Y901720I1301J0D01*
G02X1381463Y901151I-280J-286D01*
G01X1380980Y900668D01*
X1380867Y900699D01*
G03X1380520Y900746I-347J-1254D01*
G03X1379219Y899445I0J-1301D01*
G03X1379266Y899098I1301J0D01*
G01X1379297Y898985D01*
X1378216Y897904D01*
Y897465D01*
X1378103Y897411D01*
G03Y895069I569J-1171D01*
G01X1378216Y895015D01*
Y893989D01*
X1377961Y893731D01*
X1377813Y893877D01*
X1377807Y893883D01*
G03X1376820Y894337I-987J-846D01*
G03X1375519Y893036I0J-1301D01*
G03X1376545Y891764I1301J0D01*
G02X1376743Y891091I-85J-391D01*
G01X1376430Y890778D01*
G02X1375871Y890772I-283J283D01*
G03X1374971Y891133I-900J-941D01*
G03X1373670Y889832I0J-1301D01*
G03X1374031Y888932I1302J0D01*
G02X1374025Y888373I-289J-276D01*
G01X1373522Y887870D01*
X1373414Y887895D01*
G03X1373120Y887929I-296J-1268D01*
G03X1371818Y886627I0J-1302D01*
G03X1371892Y886194I1302J0D01*
G01X1371923Y886107D01*
X1371122Y884720D01*
X1371032Y884703D01*
G03X1369969Y883423I239J-1280D01*
G03X1372573I1302J0D01*
G03X1372499Y883856I-1302J0D01*
G01X1372468Y883943D01*
X1373269Y885330D01*
X1373359Y885347D01*
G03X1373487Y885378I-242J1279D01*
G01X1373601Y885411D01*
X1374057Y884955D01*
Y884350D01*
G03X1373669Y883423I913J-927D01*
G03X1373822Y882810I1302J-1D01*
G01X1373892Y882680D01*
X1372787Y881575D01*
Y881484D01*
X1372658Y881435D01*
G03X1371820Y880219I463J-1216D01*
G03X1372287Y879221I1300J0D01*
G02X1372313Y878631I-257J-307D01*
G01X1371862Y878180D01*
X1371741Y878227D01*
G03X1371271Y878315I-470J-1213D01*
G03X1369970Y877014I0J-1301D01*
G03X1369971Y876954I1301J-8D01*
G02X1369572Y876535I-399J-19D01*
G01X1369270D01*
G02X1368871Y876954I0J400D01*
G03X1368872Y877014I-1300J52D01*
G03X1366270I-1301J0D01*
G03X1366271Y876954I1301J-8D01*
G02X1365872Y876535I-399J-19D01*
G01X1365570D01*
G02X1365171Y876954I0J400D01*
G03X1365172Y877014I-1300J52D01*
G03X1362570I-1301J0D01*
G03X1362571Y876954I1301J-8D01*
G02X1362172Y876535I-399J-19D01*
G01X1361870D01*
G02X1361471Y876954I0J400D01*
G03X1361472Y877014I-1300J52D01*
G03X1358870I-1301J0D01*
G03X1359403Y875964I1301J0D01*
G02X1359457Y875365I-236J-323D01*
G01Y875343D01*
G02X1358884Y874983I-400J0D01*
G03X1358320Y875111I-563J-1173D01*
G03X1357019Y873810I0J-1301D01*
G03X1357093Y873378I1301J1D01*
G01X1357123Y873291D01*
X1356321Y871902D01*
X1356231Y871885D01*
G03X1355170Y870606I240J-1279D01*
G03X1357772I1301J0D01*
G03X1357698Y871038I-1301J-1D01*
G01X1357668Y871125D01*
X1358470Y872514D01*
X1358560Y872531D01*
G03X1358884Y872637I-239J1279D01*
G02X1359457Y872277I173J-360D01*
G01Y871694D01*
G03X1358870Y870606I715J-1088D01*
G03X1358914Y870272I1301J1D01*
G01X1358943Y870161D01*
X1357387Y868605D01*
X1355114D01*
X1355080Y868618D01*
G03X1354860Y868680I-462J-1216D01*
G01X1354770Y868697D01*
X1353968Y870087D01*
X1353998Y870174D01*
G03X1354072Y870606I-1227J433D01*
G03X1351470I-1301J0D01*
G03X1352531Y869327I1301J0D01*
G01X1352621Y869310D01*
X1353423Y867920D01*
X1353393Y867833D01*
G03X1353319Y867401I1227J-433D01*
G03X1353336Y867192I1301J1D01*
G01X1353352Y867090D01*
X1351077Y864815D01*
X1350216D01*
G03X1347926I-1145J-618D01*
G01X1346516D01*
G03X1344226I-1145J-618D01*
G01X1342816D01*
G03X1340526I-1145J-618D01*
G01X1339116D01*
G03X1336826I-1145J-618D01*
G01X1335416D01*
G03X1334271Y865498I-1145J-618D01*
G03X1332970Y864197I0J-1301D01*
G01Y864166D01*
X1332972Y864080D01*
X1331397Y862505D01*
X1330535D01*
Y862884D01*
X1330713Y862904D01*
G03X1331872Y864197I-142J1293D01*
G03X1329270I-1301J0D01*
G03X1329725Y863209I1300J0D01*
G02X1329465Y862505I-260J-304D01*
G01X1327977D01*
G02X1327717Y863209I0J400D01*
G03X1328172Y864197I-845J988D01*
G03X1325570I-1301J0D01*
G03X1326025Y863209I1300J0D01*
G02X1325765Y862505I-260J-304D01*
G01X1324217D01*
X1323357Y861645D01*
Y859290D01*
G02X1323159Y859090I-200J0D01*
G03Y856488I12J-1301D01*
G02X1323357Y856288I-2J-200D01*
G01Y852881D01*
G02X1323159Y852681I-200J0D01*
G03X1321869Y851389I11J-1301D01*
G01X1321868Y851306D01*
X1315532Y844970D01*
Y839605D01*
X1294372Y818445D01*
X1294227Y818331D01*
G03X1293619Y817696I1906J-2434D01*
G01X1293609Y817682D01*
X1267101Y791174D01*
X1237434Y767921D01*
X1237315Y767993D01*
G03X1236583Y768200I-733J-1195D01*
G03X1235181Y766798I0J-1402D01*
G03X1235344Y766143I1402J1D01*
G01X1235408Y766021D01*
X1229886Y759753D01*
G02X1229320Y759719I-300J264D01*
G03X1228320Y760100I-1000J-1122D01*
G03X1226898Y759081I0J-1502D01*
G01X1226852Y758945D01*
X1224026D01*
X1223985Y758965D01*
G03X1223327Y759117I-658J-1350D01*
G03X1222669Y758965I0J-1502D01*
G01X1222628Y758945D01*
X1222277D01*
X1219674Y756342D01*
X1215455Y755365D01*
X1212337D01*
Y758259D01*
X1220147Y766069D01*
X1225846D01*
X1226010Y766233D01*
G02X1226646Y766138I283J-283D01*
G03X1227883Y765396I1237J660D01*
G03X1229285Y766798I0J1402D01*
G03X1228543Y768035I-1402J0D01*
G02X1228448Y768671I188J353D01*
G01X1232346Y772569D01*
X1232412D01*
X1239153Y779310D01*
X1242984D01*
X1243307Y779633D01*
Y779634D01*
X1266869Y803196D01*
X1269817D01*
X1286911Y820290D01*
Y839699D01*
X1306957Y859745D01*
Y862445D01*
X1313157Y868645D01*
Y874345D01*
X1314757Y875945D01*
X1315027D01*
X1315076Y875914D01*
G03X1315771Y875713I695J1101D01*
G03X1316513Y875945I0J1301D01*
G01X1318729D01*
G03X1319471Y875713I742J1069D01*
G03X1320213Y875945I0J1301D01*
G01X1322429D01*
G03X1323171Y875713I742J1069D01*
G03X1323913Y875945I0J1301D01*
G01X1326129D01*
G03X1326871Y875713I742J1069D01*
G03X1327613Y875945I0J1301D01*
G01X1329829D01*
G03X1330571Y875713I742J1069D01*
G03X1331313Y875945I0J1301D01*
G01X1333529D01*
G03X1334271Y875713I742J1069D01*
G03X1335013Y875945I0J1301D01*
G01X1337229D01*
G03X1337971Y875713I742J1069D01*
G03X1338713Y875945I0J1301D01*
G01X1340929D01*
G03X1341671Y875713I742J1069D01*
G03X1342866Y876499I0J1301D01*
G01X1342881Y876534D01*
X1343404Y877057D01*
G02X1344083Y876831I283J-283D01*
G03X1345371Y875713I1288J183D01*
G03X1346672Y877014I0J1301D01*
G03X1345554Y878302I-1301J0D01*
G02X1345328Y878981I57J396D01*
G01X1345690Y879343D01*
G02X1346266Y879333I283J-282D01*
G03X1347220Y878917I954J886D01*
G03X1348522Y880219I0J1302D01*
G03X1347624Y881457I-1302J0D01*
G01X1347486Y881502D01*
Y882201D01*
G02X1348164Y882488I400J0D01*
G03X1349071Y882121I906J935D01*
G03X1350373Y883423I0J1302D01*
G03X1350299Y883856I-1302J0D01*
G01X1350268Y883943D01*
X1351069Y885330D01*
X1351159Y885347D01*
G03X1351373Y885406I-238J1280D01*
G01X1351407Y885419D01*
X1354136D01*
X1354169Y885407D01*
G03X1354620Y885326I452J1220D01*
G03X1355921Y886627I0J1301D01*
G03X1355677Y887386I-1301J0D01*
G01Y888245D01*
X1356033Y888601D01*
X1356144Y888573D01*
G03X1356471Y888531I328J1259D01*
G03X1357632Y889245I0J1301D01*
G01X1357688Y889355D01*
X1358954D01*
X1359010Y889245D01*
G03X1361332I1161J587D01*
G01X1361388Y889355D01*
X1362654D01*
X1362710Y889245D01*
G03X1363871Y888531I1161J587D01*
G03X1365172Y889832I0J1301D01*
G03X1364292Y891063I-1301J0D01*
G01X1364157Y891109D01*
Y892075D01*
X1364217Y892135D01*
G02X1364787Y892130I283J-283D01*
G03X1365721Y891735I934J907D01*
G03X1367022Y893036I0J1301D01*
G03X1366491Y894085I-1302J0D01*
G01X1366479Y894094D01*
X1366327Y894246D01*
X1366550Y894469D01*
Y894656D01*
G02X1367096Y895029I400J0D01*
G03X1367570Y894939I475J1211D01*
G03Y897541I0J1301D01*
G03X1367096Y897451I1J-1301D01*
G02X1366550Y897824I-146J373D01*
G01Y898443D01*
G03Y900447I-830J1002D01*
G01Y901065D01*
G02X1367096Y901438I400J1D01*
G03X1367571Y901348I475J1211D01*
G03Y903950I0J1301D01*
G03X1367096Y903860I0J-1301D01*
G02X1366550Y904233I-146J372D01*
G01Y904851D01*
G03Y906855I-830J1002D01*
G01Y907473D01*
G02X1367096Y907846I400J1D01*
G03X1367571Y907756I475J1211D01*
G03Y910358I0J1301D01*
G03X1367096Y910268I0J-1301D01*
G02X1366550Y910641I-146J372D01*
G01Y911260D01*
G03Y913264I-830J1002D01*
G01Y913882D01*
G02X1367096Y914255I400J1D01*
G03X1367571Y914165I475J1211D01*
G03Y916767I0J1301D01*
G03X1367096Y916677I0J-1301D01*
G02X1366550Y917050I-146J372D01*
G01Y917668D01*
G03Y919672I-830J1002D01*
G01Y920291D01*
G02X1367096Y920664I400J1D01*
G03X1367571Y920574I475J1211D01*
G03Y923176I0J1301D01*
G03X1367096Y923086I0J-1301D01*
G02X1366550Y923459I-146J372D01*
G01Y924077D01*
G03Y926081I-830J1002D01*
G01Y926699D01*
G02X1367096Y927072I400J1D01*
G03X1367571Y926982I475J1211D01*
G03X1368872Y928283I0J1301D01*
G03X1368180Y929433I-1302J0D01*
G02X1368085Y930069I188J353D01*
G01X1368535Y930519D01*
X1368673Y930423D01*
G03X1369420Y930187I747J1064D01*
G03X1370389Y930620I0J1301D01*
G01X1372151D01*
G03X1374089I969J868D01*
G01X1375851D01*
G03X1377789I969J868D01*
G01X1379893D01*
X1379933Y930472D01*
G03X1382445I1256J339D01*
G01X1382485Y930620D01*
G37*
G36*
G01X1274831Y136262D02*
X1276950D01*
X1286230Y126982D01*
Y123468D01*
X1276286Y113524D01*
X1274111D01*
X1263815Y123820D01*
Y125246D01*
X1274831Y136262D01*
G37*
G36*
G01X1279182Y1310063D02*
X1324371D01*
X1349956Y1284478D01*
X1463176D01*
X1475586Y1296888D01*
X1494796D01*
X1506527Y1308619D01*
X1575443D01*
X1581700Y1302362D01*
Y1248462D01*
X1562800Y1229562D01*
Y1197084D01*
X1524866Y1159150D01*
Y1146126D01*
X1517784Y1139044D01*
X1503045D01*
X1502904Y1139312D01*
X1502352Y1140355D01*
X1502392Y1140445D01*
G03X1502504Y1140966I-1189J528D01*
G01Y1140987D01*
G03X1501203Y1142274I-1301J-14D01*
G03X1499902Y1140973I0J-1301D01*
G03X1500970Y1139693I1301J0D01*
G01X1501065Y1139676D01*
X1501244Y1139337D01*
G02X1501067Y1139044I-177J-93D01*
G01X1495645D01*
X1495504Y1139312D01*
X1494952Y1140355D01*
X1494992Y1140445D01*
G03X1495104Y1140966I-1189J528D01*
G01Y1140987D01*
G03X1493803Y1142274I-1301J-14D01*
G03X1492502Y1140973I0J-1301D01*
G03X1493570Y1139693I1301J0D01*
G01X1493665Y1139676D01*
X1493844Y1139337D01*
G02X1493667Y1139044I-177J-93D01*
G01X1488245D01*
X1488104Y1139312D01*
X1487552Y1140355D01*
X1487592Y1140445D01*
G03X1487704Y1140966I-1189J528D01*
G01Y1140987D01*
G03X1486403Y1142274I-1301J-14D01*
G03X1485102Y1140973I0J-1301D01*
G03X1486170Y1139693I1301J0D01*
G01X1486265Y1139676D01*
X1486444Y1139337D01*
G02X1486267Y1139044I-177J-93D01*
G01X1480845D01*
X1480704Y1139312D01*
X1480152Y1140355D01*
X1480192Y1140445D01*
G03X1480304Y1140966I-1189J528D01*
G01Y1140987D01*
G03X1479003Y1142274I-1301J-14D01*
G03X1477702Y1140973I0J-1301D01*
G03X1478770Y1139693I1301J0D01*
G01X1478865Y1139676D01*
X1479044Y1139337D01*
G02X1478867Y1139044I-177J-93D01*
G01X1473445D01*
X1473304Y1139312D01*
X1472752Y1140355D01*
X1472792Y1140445D01*
G03X1472904Y1140966I-1189J528D01*
G01Y1140987D01*
G03X1471603Y1142274I-1301J-14D01*
G03X1470302Y1140973I0J-1301D01*
G03X1471370Y1139693I1301J0D01*
G01X1471465Y1139676D01*
X1471644Y1139337D01*
G02X1471467Y1139044I-177J-93D01*
G01X1466045D01*
X1465904Y1139312D01*
X1465352Y1140355D01*
X1465392Y1140445D01*
G03X1465504Y1140966I-1189J528D01*
G01Y1140987D01*
G03X1464203Y1142274I-1301J-14D01*
G03X1462902Y1140973I0J-1301D01*
G03X1463970Y1139693I1301J0D01*
G01X1464065Y1139676D01*
X1464244Y1139337D01*
G02X1464067Y1139044I-177J-93D01*
G01X1458645D01*
X1458504Y1139312D01*
X1457952Y1140355D01*
X1457992Y1140445D01*
G03X1458104Y1140966I-1189J528D01*
G01Y1140987D01*
G03X1456803Y1142274I-1301J-14D01*
G03X1455502Y1140973I0J-1301D01*
G03X1456570Y1139693I1301J0D01*
G01X1456665Y1139676D01*
X1456844Y1139337D01*
G02X1456667Y1139044I-177J-93D01*
G01X1454685D01*
X1453197Y1137556D01*
G02X1452551Y1137672I-283J283D01*
G01X1452540Y1137681D01*
X1452524Y1137752D01*
G03X1451487Y1138749I-1270J-283D01*
G01X1451392Y1138766D01*
X1451060Y1139394D01*
X1450552Y1140355D01*
X1450592Y1140445D01*
G03X1450704Y1140966I-1189J528D01*
G01Y1140987D01*
G03X1449403Y1142274I-1301J-14D01*
G03X1448102Y1140973I0J-1301D01*
G03X1449170Y1139693I1301J0D01*
G01X1449265Y1139676D01*
X1449597Y1139048D01*
X1450105Y1138087D01*
X1450065Y1137997D01*
G03X1449953Y1137470I1189J-528D01*
G01Y1137469D01*
G03X1450966Y1136200I1301J0D01*
G02X1451167Y1135526I-82J-391D01*
G01X1450856Y1135215D01*
G02X1450306Y1135201I-282J283D01*
G03X1449403Y1135565I-903J-938D01*
G03X1448102Y1134264I0J-1301D01*
G03X1448466Y1133361I1302J0D01*
G02X1448452Y1132811I-297J-268D01*
G01X1447946Y1132305D01*
X1447839Y1132329D01*
G03X1447554Y1132361I-287J-1269D01*
G03X1446253Y1131060I0J-1301D01*
G03X1446285Y1130775I1301J2D01*
G01X1446309Y1130668D01*
X1444139Y1128498D01*
Y1126348D01*
G02X1443770Y1125949I-400J0D01*
G03Y1123353I84J-1298D01*
G02X1444139Y1122954I-31J-399D01*
G01Y1119940D01*
G02X1443773Y1119542I-400J0D01*
G03Y1116944I80J-1299D01*
G02X1444139Y1116546I-34J-398D01*
G01Y1113531D01*
G02X1443773Y1113133I-400J0D01*
G03Y1110535I80J-1299D01*
G02X1444139Y1110137I-34J-398D01*
G01Y1107123D01*
G02X1443773Y1106725I-400J0D01*
G03Y1104127I80J-1299D01*
G02X1444139Y1103729I-34J-398D01*
G01Y1100714D01*
G02X1443773Y1100316I-400J0D01*
G03Y1097718I80J-1299D01*
G02X1444139Y1097320I-34J-398D01*
G01Y1094181D01*
X1443870Y1093912D01*
X1443792Y1093908D01*
G03X1442553Y1092608I63J-1300D01*
G03X1443617Y1091329I1301J0D01*
G01X1443780Y1091299D01*
Y1087509D01*
X1443617Y1087479D01*
G03X1442553Y1086200I237J-1279D01*
G01Y1086175D01*
G03X1443065Y1085165I1301J25D01*
G01X1443090Y1085146D01*
X1443100Y1085139D01*
G02X1443152Y1084531I-231J-326D01*
G01X1442715Y1084094D01*
X1442585Y1084159D01*
G03X1442012Y1084296I-581J-1164D01*
G01X1441989D01*
G03X1440703Y1083010I15J-1301D01*
G01Y1082994D01*
G03X1440840Y1082414I1301J1D01*
G01X1440905Y1082284D01*
X1439580Y1080959D01*
X1439553Y1080945D01*
G03X1439000Y1080392I601J-1154D01*
G01X1438986Y1080365D01*
X1438414Y1079793D01*
G02X1437737Y1080009I-283J283D01*
G03X1436454Y1081092I-1283J-218D01*
G03X1435153Y1079791I0J-1301D01*
G03X1436236Y1078508I1301J0D01*
G02X1436451Y1077831I-68J-394D01*
G01X1436361Y1077741D01*
Y1074691D01*
X1436221Y1074663D01*
G03X1435152Y1073383I232J-1280D01*
G03X1436200Y1072107I1301J0D01*
G01X1436361Y1072075D01*
Y1070049D01*
X1436100Y1069788D01*
X1435894Y1069993D01*
X1435900Y1070084D01*
G03X1435903Y1070178I-1298J88D01*
G03X1433301I-1301J0D01*
G03X1434348Y1068902I1301J0D01*
G02X1434541Y1068229I-90J-390D01*
G01X1434222Y1067910D01*
G02X1433673Y1067894I-283J283D01*
G03X1432753Y1068275I-920J-920D01*
G03X1431452Y1066974I0J-1301D01*
G03X1431948Y1065952I1301J0D01*
G01X1431957Y1065945D01*
X1432107Y1065795D01*
X1431906Y1065594D01*
Y1065360D01*
G02X1431381Y1064980I-400J0D01*
G03X1430903Y1065071I-478J-1210D01*
G03Y1062469I0J-1301D01*
G03X1431381Y1062560I0J1301D01*
G02X1431906Y1062180I125J-380D01*
G01Y1061554D01*
G03Y1059576I847J-989D01*
G01Y1058952D01*
G02X1431364Y1058578I-400J0D01*
G03X1430904Y1058662I-460J-1218D01*
G03Y1056060I0J-1301D01*
G03X1431364Y1056144I0J1302D01*
G02X1431906Y1055770I142J-374D01*
G01Y1055146D01*
G03Y1053168I847J-989D01*
G01Y1052542D01*
G02X1431381Y1052162I-400J0D01*
G03X1430903Y1052253I-478J-1210D01*
G03Y1049651I0J-1301D01*
G03X1431381Y1049742I0J1301D01*
G02X1431906Y1049362I125J-380D01*
G01Y1048738D01*
G03Y1046760I847J-989D01*
G01Y1046135D01*
G02X1431364Y1045761I-400J0D01*
G03X1430904Y1045845I-460J-1218D01*
G03Y1043243I0J-1301D01*
G03X1431364Y1043327I0J1302D01*
G02X1431906Y1042953I142J-374D01*
G01Y1042329D01*
G03Y1040351I847J-989D01*
G01Y1039727D01*
G02X1431364Y1039353I-400J0D01*
G03X1430904Y1039437I-460J-1218D01*
G03Y1036835I0J-1301D01*
G03X1431364Y1036919I0J1302D01*
G02X1431906Y1036545I142J-374D01*
G01Y1031816D01*
X1433392Y1030330D01*
G02X1433394Y1029767I-283J-283D01*
G03X1433020Y1028854I927J-913D01*
G03X1434321Y1027553I1301J0D01*
G03X1435286Y1027981I0J1302D01*
G02X1435856I285J-281D01*
G03X1436821Y1027553I965J874D01*
G03X1437622Y1027829I0J1300D01*
G01X1437748Y1027924D01*
X1448532Y1017140D01*
Y1002080D01*
X1449097Y1001515D01*
Y983885D01*
X1442787Y977575D01*
Y972800D01*
G02X1442395Y972400I-400J0D01*
G03X1441481Y972007I18J-1301D01*
G01X1441471Y972003D01*
G02X1440959Y972034I-237J322D01*
G03X1440015Y972440I-944J-894D01*
G03Y969838I0J-1301D01*
G03X1440917Y970201I0J1302D01*
G02X1441469Y970204I278J-288D01*
G03X1442364Y969799I944J895D01*
G01X1442417Y969797D01*
G02X1442787Y969398I-30J-399D01*
G01Y968925D01*
X1448707Y963005D01*
Y949489D01*
X1448410Y949192D01*
Y943916D01*
G02X1447935Y943523I-400J0D01*
G03X1447692Y943546I-244J-1278D01*
G01X1447691D01*
G03X1446812Y943204I0J-1301D01*
G02X1446272I-270J294D01*
G03X1445393Y943546I-879J-959D01*
G01X1445392D01*
G03X1444442Y943133I1J-1301D01*
G02X1443884Y943108I-292J274D01*
G03X1443002Y943452I-881J-957D01*
G03X1442927Y943450I-3J-1301D01*
G01X1442926D01*
G03X1442148Y943133I76J-1299D01*
G01X1442102Y943093D01*
G02X1441582Y943110I-250J311D01*
G03X1440503Y943437I-880J-959D01*
G03X1439848Y943133I199J-1286D01*
G01X1439827Y943114D01*
X1439822Y943110D01*
G02X1439302Y943093I-270J294D01*
G01X1439256Y943133D01*
G03X1438402Y943452I-853J-982D01*
G03X1438352Y943451I1J-1301D01*
G01X1438325Y943450D01*
G03Y940852I77J-1299D01*
G01X1438352Y940851D01*
G03X1438402Y940850I51J1300D01*
G03X1439256Y941169I1J1301D01*
G01X1439302Y941209D01*
G02X1439822Y941192I250J-311D01*
G03X1440901Y940865I880J959D01*
G03X1441556Y941169I-199J1286D01*
G01X1441577Y941188D01*
X1441582Y941192D01*
G02X1442102Y941209I270J-294D01*
G01X1442148Y941169D01*
G03X1443002Y940850I853J982D01*
G03X1443052Y940851I-1J1301D01*
G01X1443079Y940852D01*
G03X1443965Y941276I-77J1299D01*
G02X1444394Y941361I280J-286D01*
G03X1445392Y940894I998J833D01*
G03X1446391Y941361I0J1302D01*
G02X1446693I151J-369D01*
G03X1447692Y940894I999J835D01*
G03X1448141Y940974I0J1300D01*
G01X1448174Y940986D01*
X1448410D01*
Y940598D01*
X1446457Y938645D01*
X1425984D01*
G03X1423856I-1064J-749D01*
G01X1422284D01*
G03X1420156I-1064J-749D01*
G01X1418584D01*
G03X1416456I-1064J-749D01*
G01X1414884D01*
G03X1412756I-1064J-749D01*
G01X1411184D01*
G03X1409056I-1064J-749D01*
G01X1407484D01*
G03X1405356I-1064J-749D01*
G01X1385957D01*
X1384307Y940295D01*
Y940997D01*
G03X1384610Y941204I-575J1167D01*
G02X1385130Y941221I270J-294D01*
G01X1385176Y941181D01*
G03X1386030Y940862I853J982D01*
G03X1386080Y940863I-1J1301D01*
G01X1386107Y940864D01*
G03Y943462I-77J1299D01*
G01X1386080Y943463D01*
G03X1386030Y943464I-51J-1300D01*
G03X1385176Y943145I-1J-1301D01*
G01X1385130Y943105D01*
G02X1384610Y943122I-250J311D01*
G03X1384307Y943329I-878J-960D01*
G01Y958325D01*
X1390387Y964405D01*
Y969640D01*
G02X1390576Y969840I200J0D01*
G03X1391396Y970191I-71J1299D01*
G01X1391441Y970232D01*
G02X1391982Y970213I260J-304D01*
G03X1392896Y969838I914J926D01*
G03Y972440I0J1301D01*
G03X1391982Y972065I0J-1301D01*
G02X1391441Y972046I-281J285D01*
G01X1391396Y972087D01*
G03X1390576Y972438I-891J-948D01*
G02X1390387Y972638I11J200D01*
G01Y978965D01*
X1385017Y984335D01*
Y1012842D01*
G02X1385428Y1013242I400J0D01*
G03X1385449Y1013240I134J1294D01*
G01X1385476Y1013239D01*
G03X1385526Y1013238I51J1300D01*
G03X1386380Y1013557I1J1301D01*
G01X1386426Y1013597D01*
G02X1386926I250J-311D01*
G01X1386972Y1013557D01*
G03X1387826Y1013238I853J982D01*
G03X1387876Y1013239I-1J1301D01*
G01X1387903Y1013240D01*
G03Y1015838I-77J1299D01*
G01X1387876Y1015839D01*
G03X1387826Y1015840I-51J-1300D01*
G03X1386972Y1015521I-1J-1301D01*
G01X1386926Y1015481D01*
G02X1386426I-250J311D01*
G01X1386380Y1015521D01*
G03X1385526Y1015840I-853J-982D01*
G03X1385476Y1015839I1J-1301D01*
G01X1385449Y1015838D01*
G03X1385428Y1015836I113J-1296D01*
G02X1385017Y1016236I-11J400D01*
G01Y1027804D01*
X1381586Y1031235D01*
Y1040203D01*
G03Y1042477I-634J1137D01*
G01Y1043053D01*
G02X1382166Y1043409I400J-1D01*
G01X1382199Y1043392D01*
G03X1382797Y1043243I605J1152D01*
G01X1382821D01*
G03Y1045845I-17J1301D01*
G01X1382803D01*
G03X1382199Y1045696I1J-1301D01*
G01X1382178Y1045685D01*
G02X1381586Y1046035I-192J351D01*
G01Y1046612D01*
G03Y1048886I-634J1137D01*
G01Y1049461D01*
G02X1382166Y1049817I400J-1D01*
G01X1382199Y1049800D01*
G03X1382797Y1049651I605J1152D01*
G01X1382821D01*
G03Y1052253I-17J1301D01*
G01X1382803D01*
G03X1382199Y1052104I1J-1301D01*
G01X1382178Y1052093D01*
G02X1381586Y1052443I-192J351D01*
G01Y1053020D01*
G03Y1055294I-634J1137D01*
G01Y1055870D01*
G02X1382166Y1056226I400J-1D01*
G01X1382199Y1056209D01*
G03X1382797Y1056060I605J1152D01*
G01X1382821D01*
G03Y1058662I-17J1301D01*
G01X1382803D01*
G03X1382199Y1058513I1J-1301D01*
G01X1382178Y1058502D01*
G02X1381586Y1058852I-192J351D01*
G01Y1059428D01*
G03Y1061702I-634J1137D01*
G01Y1062279D01*
G02X1382166Y1062635I400J-1D01*
G01X1382199Y1062618D01*
G03X1382797Y1062469I605J1152D01*
G01X1382821D01*
G03Y1065071I-17J1301D01*
G01X1382803D01*
G03X1382199Y1064922I1J-1301D01*
G01X1382178Y1064911D01*
G02X1381586Y1065261I-192J351D01*
G01Y1065837D01*
G03Y1068111I-634J1137D01*
G01Y1068687D01*
G02X1382166Y1069043I400J-1D01*
G01X1382199Y1069026D01*
G03X1382797Y1068877I605J1152D01*
G01X1382821D01*
G03Y1071479I-17J1301D01*
G01X1382803D01*
G03X1382199Y1071330I1J-1301D01*
G01X1382178Y1071319D01*
G02X1381586Y1071669I-192J351D01*
G01Y1072246D01*
G03Y1074520I-634J1137D01*
G01Y1075095D01*
G02X1382174Y1075448I400J0D01*
G03X1382803Y1075286I629J1140D01*
G03X1384103Y1076548I0J1301D01*
G01X1384104Y1076571D01*
Y1076587D01*
G03X1383839Y1077374I-1301J0D01*
G01X1383825Y1077393D01*
X1383820Y1077399D01*
G02X1384132Y1078048I313J249D01*
G01X1385175D01*
G02X1385487Y1077399I-1J-400D01*
G01X1385482Y1077393D01*
X1385468Y1077374D01*
G03X1385203Y1076587I1036J-787D01*
G01Y1076571D01*
X1385204Y1076548D01*
G03X1387804I1300J39D01*
G01X1387805Y1076571D01*
Y1076587D01*
G03X1387540Y1077374I-1301J0D01*
G01X1387526Y1077393D01*
X1387521Y1077399D01*
G02X1387833Y1078048I313J249D01*
G01X1392575D01*
G02X1392887Y1077399I-1J-400D01*
G03X1392603Y1076587I1017J-811D01*
G03X1395205I1301J0D01*
G03X1394921Y1077399I-1301J1D01*
G02X1395233Y1078048I313J249D01*
G01X1396275D01*
G02X1396587Y1077399I-1J-400D01*
G01X1396582Y1077393D01*
X1396568Y1077374D01*
G03X1396303Y1076587I1036J-787D01*
G01Y1076571D01*
X1396304Y1076548D01*
G03X1398904I1300J39D01*
G01X1398905Y1076571D01*
Y1076587D01*
G03X1398640Y1077374I-1301J0D01*
G01X1398626Y1077393D01*
X1398621Y1077399D01*
G02X1398933Y1078048I313J249D01*
G01X1399975D01*
G02X1400287Y1077399I-1J-400D01*
G01X1400282Y1077393D01*
X1400268Y1077374D01*
G03X1400003Y1076587I1036J-787D01*
G01Y1076571D01*
X1400004Y1076548D01*
G03X1401304Y1075286I1300J39D01*
G01Y1075285D01*
G03X1401860Y1075410I-1J1302D01*
G02X1402357Y1075224I144J-373D01*
G03X1402364Y1075210I2666J1324D01*
G03X1402497Y1074980I2641J1374D01*
G02X1402394Y1074440I-337J-216D01*
G03X1401852Y1073383I760J-1057D01*
G03X1403153Y1072082I1301J0D01*
G03X1404448Y1073254I0J1301D01*
G02X1404851Y1073614I398J-40D01*
G03X1404911Y1073612I129J2974D01*
G03X1405003Y1073610I111J2974D01*
G03X1405095Y1073612I-19J2976D01*
G03X1405155Y1073614I-69J2976D01*
G02X1405558Y1073254I5J-400D01*
G03X1406853Y1072082I1295J129D01*
G03X1408154Y1073383I0J1301D01*
G03X1407913Y1074138I-1301J1D01*
G02X1408143Y1074751I330J226D01*
G03X1408920Y1075017I-1290J5037D01*
G03X1409455Y1075287I-2071J4770D01*
G03X1412054Y1079700I-2602J4504D01*
G01Y1079830D01*
Y1079882D01*
G03X1410951Y1082995I-5201J-91D01*
G03X1412054Y1086068I-4099J3206D01*
G01Y1086079D01*
Y1086200D01*
G03X1410951Y1089404I-5202J1D01*
G03X1412054Y1092517I-4098J3204D01*
G01Y1092681D01*
G03X1412053Y1092761I-2976J3D01*
G01Y1092782D01*
G03X1410737Y1096070I-5200J-174D01*
G01X1410686Y1096127D01*
Y1097721D01*
G03X1411856Y1099017I-133J1296D01*
G03X1410554Y1100319I-1302J0D01*
G01X1410543D01*
X1410460Y1100318D01*
X1410002Y1100776D01*
X1410031Y1100888D01*
G03X1410204Y1102130I-5028J1333D01*
G01Y1102294D01*
G03X1410203Y1102374I-2976J3D01*
G01Y1102392D01*
X1410202Y1102413D01*
G03X1410013Y1103624I-5199J-191D01*
G01X1410012Y1103627D01*
G02X1410434Y1104130I386J105D01*
G03X1410553Y1104125I114J1296D01*
G03Y1106727I0J1301D01*
G03X1410434Y1106722I-5J-1301D01*
G02X1410008Y1107213I-37J398D01*
G03X1410204Y1108539I-5005J1417D01*
G01Y1108669D01*
Y1108721D01*
G03X1410008Y1110047I-5201J-91D01*
G02X1410434Y1110538I389J93D01*
G03X1410553Y1110533I114J1296D01*
G03Y1113135I0J1301D01*
G03X1410434Y1113130I-5J-1301D01*
G02X1410012Y1113634I-36J398D01*
G03X1410203Y1114877I-5009J1406D01*
G01Y1114886D01*
G03X1410204Y1114966I-2975J77D01*
G01Y1115078D01*
Y1115130D01*
G03X1410008Y1116456I-5201J-91D01*
G02X1410434Y1116947I389J93D01*
G03X1410553Y1116942I114J1296D01*
G03Y1119544I0J1301D01*
G03X1409720Y1119242I0J-1300D01*
G02X1409067Y1119552I-253J310D01*
G01Y1120249D01*
X1408007Y1121309D01*
Y1122778D01*
X1408020Y1122812D01*
G03X1408356Y1124649I-4866J1839D01*
G01Y1124707D01*
G03X1408355Y1124782I-2977J-2D01*
G01Y1124783D01*
X1408354Y1124807D01*
G03X1408020Y1126491I-5200J-156D01*
G01X1408007Y1126526D01*
Y1129189D01*
X1408020Y1129223D01*
G03Y1132897I-4867J1837D01*
G01X1408007Y1132931D01*
Y1135577D01*
X1408021Y1135613D01*
G03X1408350Y1136847I-4866J1958D01*
G03X1408378Y1137257I-2948J407D01*
G03X1408375Y1137400I-2976J9D01*
G03X1408374Y1137422I-2974J-124D01*
G01X1408350Y1137854D01*
X1408316Y1138473D01*
G03X1408163Y1139267I-2972J-161D01*
G01X1408159Y1139279D01*
Y1139280D01*
G03X1408032Y1139612I-5001J-1723D01*
G03X1408007Y1139672I-4894J-2004D01*
G01Y1151861D01*
X1408146Y1151885D01*
G03X1408907Y1152243I-233J1484D01*
G02X1409419I256J-308D01*
G03X1410413Y1151867I994J1126D01*
G03Y1154871I0J1502D01*
G03X1409419Y1154495I0J-1502D01*
G02X1408907I-256J308D01*
G03X1408172Y1154848I-993J-1126D01*
G01X1408007Y1154877D01*
Y1160061D01*
X1408172Y1160090D01*
G03X1408985Y1160516I-257J1480D01*
G02X1409541I278J-287D01*
G03X1410613Y1160067I1071J1053D01*
G03Y1163071I0J1502D01*
G03X1409541Y1162622I-1J-1502D01*
G02X1408985I-278J287D01*
G03X1408146Y1163053I-1071J-1053D01*
G01X1408007Y1163077D01*
Y1167829D01*
X1407915Y1168051D01*
G02X1408187Y1168592I370J153D01*
G01X1408231Y1168601D01*
G03X1408985Y1169016I-317J1468D01*
G02X1409541I278J-287D01*
G03X1410613Y1168567I1071J1053D01*
G03Y1171571I0J1502D01*
G03X1409541Y1171122I-1J-1502D01*
G02X1408985I-278J287D01*
G03X1407913Y1171571I-1071J-1053D01*
G03X1407328Y1171452I1J-1502D01*
G02X1406784Y1171825I-144J373D01*
G01Y1177621D01*
G03X1405878Y1179807I-3092J-1D01*
G01X1401085Y1184599D01*
X1400994Y1184819D01*
X1351942Y1233844D01*
X1337284Y1239792D01*
X1278552Y1297702D01*
X1277995Y1299254D01*
Y1308876D01*
X1279182Y1310063D01*
G37*
G36*
G01X1282792Y1499348D02*
X1379124D01*
Y1437663D01*
X1376928Y1435466D01*
X1370250D01*
G03X1368498Y1433715I0J-1752D01*
G03X1368500Y1433640I1752J9D01*
G02X1368100Y1433224I-399J-16D01*
G01X1367620D01*
G03X1367458Y1433216I5J-1752D01*
G02X1367138Y1433897I-37J398D01*
G01X1376936Y1443696D01*
G03X1377362Y1444722I-1025J1027D01*
G01Y1462892D01*
G03X1376936Y1463918I-1451J-1D01*
G01X1364954Y1475900D01*
G03X1363928Y1476326I-1027J-1025D01*
G01X1304849D01*
X1282510Y1498665D01*
G02X1282792Y1499348I282J283D01*
G37*
G36*
G01X1854855Y70296D02*
G02X1855058Y70303I107J-169D01*
G01X1855366Y70134D01*
G02X1855470Y69959I-96J-175D01*
G01Y54252D01*
G02X1849606Y48388I-5864J0D01*
G01X1803945D01*
G03X1794061Y38504I0J-9884D01*
G01Y5140D01*
X1794070D01*
Y3937D01*
G02X1792134Y2001I-1936J0D01*
G01X1529929D01*
G02X1527993Y3937I0J1936D01*
G01Y5140D01*
X1528002D01*
Y38504D01*
G03X1518118Y48388I-9884J0D01*
G01X1305191D01*
G02X1304995Y48549I0J200D01*
G02X1305115Y48773I196J39D01*
G01X1308972Y50371D01*
G02X1309024Y50384I74J-186D01*
G01X1518118D01*
G02X1529998Y38504I0J-11880D01*
G01Y15466D01*
X1529977Y15423D01*
G03X1528452Y12480I2077J-2943D01*
G03X1529199Y10283I3604J0D01*
G03X1529920Y9558I2889J2152D01*
G01X1529998Y9402D01*
Y4000D01*
X1792064D01*
Y9351D01*
X1792147Y9512D01*
G03X1792960Y14545I-2105J2922D01*
G03X1792128Y15392I-2951J-2067D01*
G01X1792064Y15517D01*
Y38504D01*
G02X1803945Y50384I11881J-1D01*
G01X1849606D01*
G03X1853474Y54252I0J3868D01*
G01Y69371D01*
X1853577Y69544D01*
G03X1854855Y70296I-9879J18250D01*
G37*
G36*
G01X1313170Y278382D02*
X1327268D01*
X1330459Y275191D01*
Y264780D01*
X1329008Y263329D01*
X1314197D01*
X1312686Y264840D01*
Y277898D01*
X1313170Y278382D01*
G37*
G36*
G01X1309545Y882619D02*
X1309730Y883219D01*
X1310760D01*
X1310945Y882619D01*
Y882444D01*
X1309545D01*
Y882619D01*
G37*
G36*
G01X1313197D02*
X1313382Y883219D01*
X1314412D01*
X1314597Y882619D01*
Y882445D01*
X1313197D01*
Y882619D01*
G37*
G36*
G01X1309545D02*
X1309730Y883219D01*
X1310760D01*
X1310945Y882619D01*
Y882444D01*
X1309545D01*
Y882619D01*
G37*
G36*
G01X1313197D02*
X1313382Y883219D01*
X1314412D01*
X1314597Y882619D01*
Y882445D01*
X1313197D01*
Y882619D01*
G37*
G36*
G01X1314597Y877817D02*
X1314412Y877217D01*
X1313382D01*
X1313197Y877817D01*
Y877992D01*
X1314597D01*
Y877817D01*
G37*
G36*
G01D02*
X1314412Y877217D01*
X1313382D01*
X1313197Y877817D01*
Y877992D01*
X1314597D01*
Y877817D01*
G37*
G36*
G01X1312804Y881023D02*
X1312619Y880423D01*
X1311589D01*
X1311404Y881023D01*
Y881197D01*
X1312804D01*
Y881023D01*
G37*
G36*
G01D02*
X1312619Y880423D01*
X1311589D01*
X1311404Y881023D01*
Y881197D01*
X1312804D01*
Y881023D01*
G37*
G36*
G01X1311404Y879415D02*
X1311589Y880015D01*
X1312619D01*
X1312804Y879415D01*
Y879241D01*
X1311404D01*
Y879415D01*
G37*
G36*
G01X1309656Y877632D02*
X1309229Y878092D01*
X1309744Y878984D01*
X1310356Y878844D01*
X1310507Y878757D01*
X1309807Y877545D01*
X1309656Y877632D01*
G37*
G36*
G01X1311404Y879415D02*
X1311589Y880015D01*
X1312619D01*
X1312804Y879415D01*
Y879241D01*
X1311404D01*
Y879415D01*
G37*
G36*
G01X1309656Y877632D02*
X1309229Y878092D01*
X1309744Y878984D01*
X1310356Y878844D01*
X1310507Y878757D01*
X1309807Y877545D01*
X1309656Y877632D01*
G37*
G36*
G01X1314597Y884227D02*
X1314412Y883627D01*
X1313382D01*
X1313197Y884227D01*
Y884401D01*
X1314597D01*
Y884227D01*
G37*
G36*
G01D02*
X1314412Y883627D01*
X1313382D01*
X1313197Y884227D01*
Y884401D01*
X1314597D01*
Y884227D01*
G37*
G36*
G01X1312794Y893839D02*
X1312609Y893239D01*
X1311579D01*
X1311394Y893839D01*
Y894014D01*
X1312794D01*
Y893839D01*
G37*
G36*
G01D02*
X1312609Y893239D01*
X1311579D01*
X1311394Y893839D01*
Y894014D01*
X1312794D01*
Y893839D01*
G37*
G36*
G01X1311394Y892233D02*
X1311579Y892833D01*
X1312609D01*
X1312794Y892233D01*
Y892058D01*
X1311394D01*
Y892233D01*
G37*
G36*
G01D02*
X1311579Y892833D01*
X1312609D01*
X1312794Y892233D01*
Y892058D01*
X1311394D01*
Y892233D01*
G37*
G36*
G01X1309544Y895435D02*
X1309729Y896035D01*
X1310759D01*
X1310944Y895435D01*
Y895261D01*
X1309544D01*
Y895435D01*
G37*
G36*
G01X1313197Y895437D02*
X1313382Y896037D01*
X1314412D01*
X1314597Y895437D01*
Y895262D01*
X1313197D01*
Y895437D01*
G37*
G36*
G01X1309544Y895435D02*
X1309729Y896035D01*
X1310759D01*
X1310944Y895435D01*
Y895261D01*
X1309544D01*
Y895435D01*
G37*
G36*
G01X1313197Y895437D02*
X1313382Y896037D01*
X1314412D01*
X1314597Y895437D01*
Y895262D01*
X1313197D01*
Y895437D01*
G37*
G36*
G01X1314597Y890635D02*
X1314412Y890035D01*
X1313382D01*
X1313197Y890635D01*
Y890810D01*
X1314597D01*
Y890635D01*
G37*
G36*
G01D02*
X1314412Y890035D01*
X1313382D01*
X1313197Y890635D01*
Y890810D01*
X1314597D01*
Y890635D01*
G37*
G36*
G01X1312804Y887431D02*
X1312619Y886831D01*
X1311589D01*
X1311404Y887431D01*
Y887605D01*
X1312804D01*
Y887431D01*
G37*
G36*
G01D02*
X1312619Y886831D01*
X1311589D01*
X1311404Y887431D01*
Y887605D01*
X1312804D01*
Y887431D01*
G37*
G36*
G01X1311404Y885823D02*
X1311589Y886423D01*
X1312619D01*
X1312804Y885823D01*
Y885649D01*
X1311404D01*
Y885823D01*
G37*
G36*
G01D02*
X1311589Y886423D01*
X1312619D01*
X1312804Y885823D01*
Y885649D01*
X1311404D01*
Y885823D01*
G37*
G36*
G01X1313197Y889029D02*
X1313382Y889629D01*
X1314412D01*
X1314597Y889029D01*
Y888854D01*
X1313197D01*
Y889029D01*
G37*
G36*
G01X1309478Y889027D02*
X1309663Y889627D01*
X1310693D01*
X1310878Y889027D01*
Y888852D01*
X1309478D01*
Y889027D01*
G37*
G36*
G01X1313197Y889029D02*
X1313382Y889629D01*
X1314412D01*
X1314597Y889029D01*
Y888854D01*
X1313197D01*
Y889029D01*
G37*
G36*
G01X1309478Y889027D02*
X1309663Y889627D01*
X1310693D01*
X1310878Y889027D01*
Y888852D01*
X1309478D01*
Y889027D01*
G37*
G36*
G01X1312771Y900251D02*
X1312586Y899651D01*
X1311556D01*
X1311371Y900251D01*
Y900425D01*
X1312771D01*
Y900251D01*
G37*
G36*
G01D02*
X1312586Y899651D01*
X1311556D01*
X1311371Y900251D01*
Y900425D01*
X1312771D01*
Y900251D01*
G37*
G36*
G01X1309656Y916084D02*
X1309229Y916544D01*
X1309744Y917436D01*
X1310356Y917296D01*
X1310507Y917209D01*
X1309807Y915997D01*
X1309656Y916084D01*
G37*
G36*
G01D02*
X1309229Y916544D01*
X1309744Y917436D01*
X1310356Y917296D01*
X1310507Y917209D01*
X1309807Y915997D01*
X1309656Y916084D01*
G37*
G36*
G01X1314644Y916269D02*
X1314459Y915669D01*
X1313429D01*
X1313244Y916269D01*
Y916444D01*
X1314644D01*
Y916269D01*
G37*
G36*
G01D02*
X1314459Y915669D01*
X1313429D01*
X1313244Y916269D01*
Y916444D01*
X1314644D01*
Y916269D01*
G37*
G36*
G01X1311371Y905049D02*
X1311556Y905649D01*
X1312586D01*
X1312771Y905049D01*
Y904875D01*
X1311371D01*
Y905049D01*
G37*
G36*
G01D02*
X1311556Y905649D01*
X1312586D01*
X1312771Y905049D01*
Y904875D01*
X1311371D01*
Y905049D01*
G37*
G36*
G01X1313221Y901845D02*
X1313406Y902445D01*
X1314436D01*
X1314621Y901845D01*
Y901671D01*
X1313221D01*
Y901845D01*
G37*
G36*
G01X1309521D02*
X1309706Y902445D01*
X1310736D01*
X1310921Y901845D01*
Y901671D01*
X1309521D01*
Y901845D01*
G37*
G36*
G01X1313221D02*
X1313406Y902445D01*
X1314436D01*
X1314621Y901845D01*
Y901671D01*
X1313221D01*
Y901845D01*
G37*
G36*
G01X1309521D02*
X1309706Y902445D01*
X1310736D01*
X1310921Y901845D01*
Y901671D01*
X1309521D01*
Y901845D01*
G37*
G36*
G01X1310890Y903453D02*
X1310705Y902853D01*
X1309675D01*
X1309490Y903453D01*
Y903628D01*
X1310890D01*
Y903453D01*
G37*
G36*
G01X1314621Y903455D02*
X1314436Y902855D01*
X1313406D01*
X1313221Y903455D01*
Y903629D01*
X1314621D01*
Y903455D01*
G37*
G36*
G01X1310890Y903453D02*
X1310705Y902853D01*
X1309675D01*
X1309490Y903453D01*
Y903628D01*
X1310890D01*
Y903453D01*
G37*
G36*
G01X1314621Y903455D02*
X1314436Y902855D01*
X1313406D01*
X1313221Y903455D01*
Y903629D01*
X1314621D01*
Y903455D01*
G37*
G36*
G01X1312631Y911636D02*
X1313058Y911176D01*
X1312543Y910284D01*
X1311931Y910424D01*
X1311780Y910511D01*
X1312480Y911723D01*
X1312631Y911636D01*
G37*
G36*
G01X1310921Y909861D02*
X1310736Y909261D01*
X1309706D01*
X1309521Y909861D01*
Y910036D01*
X1310921D01*
Y909861D01*
G37*
G36*
G01X1312631Y911636D02*
X1313058Y911176D01*
X1312543Y910284D01*
X1311931Y910424D01*
X1311780Y910511D01*
X1312480Y911723D01*
X1312631Y911636D01*
G37*
G36*
G01X1310921Y909861D02*
X1310736Y909261D01*
X1309706D01*
X1309521Y909861D01*
Y910036D01*
X1310921D01*
Y909861D01*
G37*
G36*
G01X1313353Y909668D02*
X1312926Y910128D01*
X1313441Y911020D01*
X1314053Y910880D01*
X1314204Y910793D01*
X1313504Y909581D01*
X1313353Y909668D01*
G37*
G36*
G01X1309497Y908255D02*
X1309682Y908855D01*
X1310712D01*
X1310897Y908255D01*
Y908080D01*
X1309497D01*
Y908255D01*
G37*
G36*
G01X1313353Y909668D02*
X1312926Y910128D01*
X1313441Y911020D01*
X1314053Y910880D01*
X1314204Y910793D01*
X1313504Y909581D01*
X1313353Y909668D01*
G37*
G36*
G01X1309497Y908255D02*
X1309682Y908855D01*
X1310712D01*
X1310897Y908255D01*
Y908080D01*
X1309497D01*
Y908255D01*
G37*
G36*
G01X1307671Y911457D02*
X1307856Y912057D01*
X1308886D01*
X1309071Y911457D01*
Y911283D01*
X1307671D01*
Y911457D01*
G37*
G36*
G01X1313197Y914663D02*
X1313382Y915263D01*
X1314412D01*
X1314597Y914663D01*
Y914488D01*
X1313197D01*
Y914663D01*
G37*
G36*
G01X1311507Y912882D02*
X1311080Y913342D01*
X1311595Y914234D01*
X1312207Y914094D01*
X1312358Y914007D01*
X1311658Y912795D01*
X1311507Y912882D01*
G37*
G36*
G01X1307671Y911457D02*
X1307856Y912057D01*
X1308886D01*
X1309071Y911457D01*
Y911283D01*
X1307671D01*
Y911457D01*
G37*
G36*
G01X1313197Y914663D02*
X1313382Y915263D01*
X1314412D01*
X1314597Y914663D01*
Y914488D01*
X1313197D01*
Y914663D01*
G37*
G36*
G01X1311507Y912882D02*
X1311080Y913342D01*
X1311595Y914234D01*
X1312207Y914094D01*
X1312358Y914007D01*
X1311658Y912795D01*
X1311507Y912882D01*
G37*
G36*
G01X1314489Y908448D02*
X1314916Y907988D01*
X1314401Y907096D01*
X1313789Y907236D01*
X1313638Y907323D01*
X1314338Y908535D01*
X1314489Y908448D01*
G37*
G36*
G01X1312771Y906659D02*
X1312586Y906059D01*
X1311556D01*
X1311371Y906659D01*
Y906833D01*
X1312771D01*
Y906659D01*
G37*
G36*
G01X1314489Y908448D02*
X1314916Y907988D01*
X1314401Y907096D01*
X1313789Y907236D01*
X1313638Y907323D01*
X1314338Y908535D01*
X1314489Y908448D01*
G37*
G36*
G01X1312771Y906659D02*
X1312586Y906059D01*
X1311556D01*
X1311371Y906659D01*
Y906833D01*
X1312771D01*
Y906659D01*
G37*
G36*
G01X1309544Y927481D02*
X1309729Y928081D01*
X1310759D01*
X1310944Y927481D01*
Y927306D01*
X1309544D01*
Y927481D01*
G37*
G36*
G01X1313222Y927479D02*
X1313407Y928079D01*
X1314437D01*
X1314622Y927479D01*
Y927305D01*
X1313222D01*
Y927479D01*
G37*
G36*
G01X1309544Y927481D02*
X1309729Y928081D01*
X1310759D01*
X1310944Y927481D01*
Y927306D01*
X1309544D01*
Y927481D01*
G37*
G36*
G01X1313222Y927479D02*
X1313407Y928079D01*
X1314437D01*
X1314622Y927479D01*
Y927305D01*
X1313222D01*
Y927479D01*
G37*
G36*
G01X1311348Y924277D02*
X1311533Y924877D01*
X1312563D01*
X1312748Y924277D01*
Y924102D01*
X1311348D01*
Y924277D01*
G37*
G36*
G01X1307319Y924127D02*
X1307397Y924750D01*
X1308412Y924929D01*
X1308698Y924370D01*
X1308728Y924199D01*
X1307350Y923955D01*
X1307319Y924127D01*
G37*
G36*
G01X1311348Y924277D02*
X1311533Y924877D01*
X1312563D01*
X1312748Y924277D01*
Y924102D01*
X1311348D01*
Y924277D01*
G37*
G36*
G01X1307319Y924127D02*
X1307397Y924750D01*
X1308412Y924929D01*
X1308698Y924370D01*
X1308728Y924199D01*
X1307350Y923955D01*
X1307319Y924127D01*
G37*
G36*
G01X1312748Y925883D02*
X1312563Y925283D01*
X1311533D01*
X1311348Y925883D01*
Y926058D01*
X1312748D01*
Y925883D01*
G37*
G36*
G01D02*
X1312563Y925283D01*
X1311533D01*
X1311348Y925883D01*
Y926058D01*
X1312748D01*
Y925883D01*
G37*
G36*
G01X1310934Y922679D02*
X1310749Y922079D01*
X1309719D01*
X1309534Y922679D01*
Y922854D01*
X1310934D01*
Y922679D01*
G37*
G36*
G01X1314642D02*
X1314457Y922079D01*
X1313427D01*
X1313242Y922679D01*
Y922854D01*
X1314642D01*
Y922679D01*
G37*
G36*
G01X1310934D02*
X1310749Y922079D01*
X1309719D01*
X1309534Y922679D01*
Y922854D01*
X1310934D01*
Y922679D01*
G37*
G36*
G01X1314642D02*
X1314457Y922079D01*
X1313427D01*
X1313242Y922679D01*
Y922854D01*
X1314642D01*
Y922679D01*
G37*
G36*
G01X1314517Y934130D02*
X1314944Y933670D01*
X1314429Y932778D01*
X1313817Y932918D01*
X1313666Y933005D01*
X1314366Y934217D01*
X1314517Y934130D01*
G37*
G36*
G01X1312804Y932291D02*
X1312619Y931691D01*
X1311589D01*
X1311404Y932291D01*
Y932466D01*
X1312804D01*
Y932291D01*
G37*
G36*
G01X1309095Y932293D02*
X1308910Y931693D01*
X1307880D01*
X1307695Y932293D01*
Y932467D01*
X1309095D01*
Y932293D01*
G37*
G36*
G01X1314517Y934130D02*
X1314944Y933670D01*
X1314429Y932778D01*
X1313817Y932918D01*
X1313666Y933005D01*
X1314366Y934217D01*
X1314517Y934130D01*
G37*
G36*
G01X1312804Y932291D02*
X1312619Y931691D01*
X1311589D01*
X1311404Y932291D01*
Y932466D01*
X1312804D01*
Y932291D01*
G37*
G36*
G01X1309095Y932293D02*
X1308910Y931693D01*
X1307880D01*
X1307695Y932293D01*
Y932467D01*
X1309095D01*
Y932293D01*
G37*
G36*
G01X1311338Y930685D02*
X1311523Y931285D01*
X1312553D01*
X1312738Y930685D01*
Y930510D01*
X1311338D01*
Y930685D01*
G37*
G36*
G01D02*
X1311523Y931285D01*
X1312553D01*
X1312738Y930685D01*
Y930510D01*
X1311338D01*
Y930685D01*
G37*
G36*
G01X1314655Y929087D02*
X1314470Y928487D01*
X1313440D01*
X1313255Y929087D01*
Y929262D01*
X1314655D01*
Y929087D01*
G37*
G36*
G01X1310921D02*
X1310736Y928487D01*
X1309706D01*
X1309521Y929087D01*
Y929262D01*
X1310921D01*
Y929087D01*
G37*
G36*
G01X1314655D02*
X1314470Y928487D01*
X1313440D01*
X1313255Y929087D01*
Y929262D01*
X1314655D01*
Y929087D01*
G37*
G36*
G01X1310921D02*
X1310736Y928487D01*
X1309706D01*
X1309521Y929087D01*
Y929262D01*
X1310921D01*
Y929087D01*
G37*
G36*
G01X1309498Y921073D02*
X1309683Y921673D01*
X1310713D01*
X1310898Y921073D01*
Y920898D01*
X1309498D01*
Y921073D01*
G37*
G36*
G01X1313200Y921071D02*
X1313385Y921671D01*
X1314415D01*
X1314600Y921071D01*
Y920897D01*
X1313200D01*
Y921071D01*
G37*
G36*
G01X1309498Y921073D02*
X1309683Y921673D01*
X1310713D01*
X1310898Y921073D01*
Y920898D01*
X1309498D01*
Y921073D01*
G37*
G36*
G01X1313200Y921071D02*
X1313385Y921671D01*
X1314415D01*
X1314600Y921071D01*
Y920897D01*
X1313200D01*
Y921071D01*
G37*
G36*
G01X1311394Y917867D02*
X1311579Y918467D01*
X1312609D01*
X1312794Y917867D01*
Y917692D01*
X1311394D01*
Y917867D01*
G37*
G36*
G01D02*
X1311579Y918467D01*
X1312609D01*
X1312794Y917867D01*
Y917692D01*
X1311394D01*
Y917867D01*
G37*
G36*
G01X1312792Y919475D02*
X1312607Y918875D01*
X1311577D01*
X1311392Y919475D01*
Y919650D01*
X1312792D01*
Y919475D01*
G37*
G36*
G01D02*
X1312607Y918875D01*
X1311577D01*
X1311392Y919475D01*
Y919650D01*
X1312792D01*
Y919475D01*
G37*
G36*
G01X1310789Y940490D02*
X1311216Y940030D01*
X1310701Y939138D01*
X1310089Y939278D01*
X1309938Y939365D01*
X1310638Y940577D01*
X1310789Y940490D01*
G37*
G36*
G01X1314654Y941903D02*
X1314469Y941303D01*
X1313439D01*
X1313254Y941903D01*
Y942078D01*
X1314654D01*
Y941903D01*
G37*
G36*
G01X1310789Y940490D02*
X1311216Y940030D01*
X1310701Y939138D01*
X1310089Y939278D01*
X1309938Y939365D01*
X1310638Y940577D01*
X1310789Y940490D01*
G37*
G36*
G01X1314654Y941903D02*
X1314469Y941303D01*
X1313439D01*
X1313254Y941903D01*
Y942078D01*
X1314654D01*
Y941903D01*
G37*
G36*
G01X1310888Y935495D02*
X1310703Y934895D01*
X1309673D01*
X1309488Y935495D01*
Y935670D01*
X1310888D01*
Y935495D01*
G37*
G36*
G01X1312657Y937314D02*
X1313084Y936854D01*
X1312569Y935962D01*
X1311957Y936102D01*
X1311806Y936189D01*
X1312506Y937401D01*
X1312657Y937314D01*
G37*
G36*
G01X1310888Y935495D02*
X1310703Y934895D01*
X1309673D01*
X1309488Y935495D01*
Y935670D01*
X1310888D01*
Y935495D01*
G37*
G36*
G01X1312657Y937314D02*
X1313084Y936854D01*
X1312569Y935962D01*
X1311957Y936102D01*
X1311806Y936189D01*
X1312506Y937401D01*
X1312657Y937314D01*
G37*
G36*
G01X1313192Y946705D02*
X1313377Y947305D01*
X1314407D01*
X1314592Y946705D01*
Y946531D01*
X1313192D01*
Y946705D01*
G37*
G36*
G01X1309491D02*
X1309676Y947305D01*
X1310706D01*
X1310891Y946705D01*
Y946531D01*
X1309491D01*
Y946705D01*
G37*
G36*
G01X1313192D02*
X1313377Y947305D01*
X1314407D01*
X1314592Y946705D01*
Y946531D01*
X1313192D01*
Y946705D01*
G37*
G36*
G01X1309491D02*
X1309676Y947305D01*
X1310706D01*
X1310891Y946705D01*
Y946531D01*
X1309491D01*
Y946705D01*
G37*
G36*
G01X1314654Y948313D02*
X1314469Y947713D01*
X1313439D01*
X1313254Y948313D01*
Y948487D01*
X1314654D01*
Y948313D01*
G37*
G36*
G01D02*
X1314469Y947713D01*
X1313439D01*
X1313254Y948313D01*
Y948487D01*
X1314654D01*
Y948313D01*
G37*
G36*
G01X1312789Y945107D02*
X1312604Y944507D01*
X1311574D01*
X1311389Y945107D01*
Y945282D01*
X1312789D01*
Y945107D01*
G37*
G36*
G01D02*
X1312604Y944507D01*
X1311574D01*
X1311389Y945107D01*
Y945282D01*
X1312789D01*
Y945107D01*
G37*
G36*
G01X1309657Y941720D02*
X1309230Y942180D01*
X1309745Y943072D01*
X1310357Y942932D01*
X1310508Y942845D01*
X1309808Y941633D01*
X1309657Y941720D01*
G37*
G36*
G01X1311337Y943501D02*
X1311522Y944101D01*
X1312552D01*
X1312737Y943501D01*
Y943326D01*
X1311337D01*
Y943501D01*
G37*
G36*
G01X1309657Y941720D02*
X1309230Y942180D01*
X1309745Y943072D01*
X1310357Y942932D01*
X1310508Y942845D01*
X1309808Y941633D01*
X1309657Y941720D01*
G37*
G36*
G01X1311337Y943501D02*
X1311522Y944101D01*
X1312552D01*
X1312737Y943501D01*
Y943326D01*
X1311337D01*
Y943501D01*
G37*
G36*
G01X1313188Y940297D02*
X1313373Y940897D01*
X1314403D01*
X1314588Y940297D01*
Y940122D01*
X1313188D01*
Y940297D01*
G37*
G36*
G01D02*
X1313373Y940897D01*
X1314403D01*
X1314588Y940297D01*
Y940122D01*
X1313188D01*
Y940297D01*
G37*
G36*
G01X1309487Y933889D02*
X1309672Y934489D01*
X1310702D01*
X1310887Y933889D01*
Y933714D01*
X1309487D01*
Y933889D01*
G37*
G36*
G01X1313324Y935254D02*
X1312897Y935714D01*
X1313412Y936606D01*
X1314024Y936466D01*
X1314175Y936379D01*
X1313475Y935167D01*
X1313324Y935254D01*
G37*
G36*
G01X1309487Y933889D02*
X1309672Y934489D01*
X1310702D01*
X1310887Y933889D01*
Y933714D01*
X1309487D01*
Y933889D01*
G37*
G36*
G01X1313324Y935254D02*
X1312897Y935714D01*
X1313412Y936606D01*
X1314024Y936466D01*
X1314175Y936379D01*
X1313475Y935167D01*
X1313324Y935254D01*
G37*
G36*
G01X1307670Y962725D02*
X1307855Y963325D01*
X1308885D01*
X1309070Y962725D01*
Y962551D01*
X1307670D01*
Y962725D01*
G37*
G36*
G01X1311370D02*
X1311555Y963325D01*
X1312585D01*
X1312770Y962725D01*
Y962551D01*
X1311370D01*
Y962725D01*
G37*
G36*
G01X1307670D02*
X1307855Y963325D01*
X1308885D01*
X1309070Y962725D01*
Y962551D01*
X1307670D01*
Y962725D01*
G37*
G36*
G01X1311370D02*
X1311555Y963325D01*
X1312585D01*
X1312770Y962725D01*
Y962551D01*
X1311370D01*
Y962725D01*
G37*
G36*
G01X1309487Y959523D02*
X1309672Y960123D01*
X1310702D01*
X1310887Y959523D01*
Y959348D01*
X1309487D01*
Y959523D01*
G37*
G36*
G01X1313187D02*
X1313372Y960123D01*
X1314402D01*
X1314587Y959523D01*
Y959348D01*
X1313187D01*
Y959523D01*
G37*
G36*
G01X1309487D02*
X1309672Y960123D01*
X1310702D01*
X1310887Y959523D01*
Y959348D01*
X1309487D01*
Y959523D01*
G37*
G36*
G01X1313187D02*
X1313372Y960123D01*
X1314402D01*
X1314587Y959523D01*
Y959348D01*
X1313187D01*
Y959523D01*
G37*
G36*
G01X1310920Y961131D02*
X1310735Y960531D01*
X1309705D01*
X1309520Y961131D01*
Y961305D01*
X1310920D01*
Y961131D01*
G37*
G36*
G01X1314620D02*
X1314435Y960531D01*
X1313405D01*
X1313220Y961131D01*
Y961305D01*
X1314620D01*
Y961131D01*
G37*
G36*
G01X1310920D02*
X1310735Y960531D01*
X1309705D01*
X1309520Y961131D01*
Y961305D01*
X1310920D01*
Y961131D01*
G37*
G36*
G01X1314620D02*
X1314435Y960531D01*
X1313405D01*
X1313220Y961131D01*
Y961305D01*
X1314620D01*
Y961131D01*
G37*
G36*
G01X1309104Y957925D02*
X1308919Y957325D01*
X1307889D01*
X1307704Y957925D01*
Y958100D01*
X1309104D01*
Y957925D01*
G37*
G36*
G01X1312804D02*
X1312619Y957325D01*
X1311589D01*
X1311404Y957925D01*
Y958100D01*
X1312804D01*
Y957925D01*
G37*
G36*
G01X1309104D02*
X1308919Y957325D01*
X1307889D01*
X1307704Y957925D01*
Y958100D01*
X1309104D01*
Y957925D01*
G37*
G36*
G01X1312804D02*
X1312619Y957325D01*
X1311589D01*
X1311404Y957925D01*
Y958100D01*
X1312804D01*
Y957925D01*
G37*
G36*
G01X1311337Y949909D02*
X1311522Y950509D01*
X1312552D01*
X1312737Y949909D01*
Y949735D01*
X1311337D01*
Y949909D01*
G37*
G36*
G01D02*
X1311522Y950509D01*
X1312552D01*
X1312737Y949909D01*
Y949735D01*
X1311337D01*
Y949909D01*
G37*
G36*
G01X1314597Y954721D02*
X1314412Y954121D01*
X1313382D01*
X1313197Y954721D01*
Y954895D01*
X1314597D01*
Y954721D01*
G37*
G36*
G01X1310887D02*
X1310702Y954121D01*
X1309672D01*
X1309487Y954721D01*
Y954895D01*
X1310887D01*
Y954721D01*
G37*
G36*
G01X1314597D02*
X1314412Y954121D01*
X1313382D01*
X1313197Y954721D01*
Y954895D01*
X1314597D01*
Y954721D01*
G37*
G36*
G01X1310887D02*
X1310702Y954121D01*
X1309672D01*
X1309487Y954721D01*
Y954895D01*
X1310887D01*
Y954721D01*
G37*
G36*
G01X1313252Y953113D02*
X1313437Y953713D01*
X1314467D01*
X1314652Y953113D01*
Y952939D01*
X1313252D01*
Y953113D01*
G37*
G36*
G01D02*
X1313437Y953713D01*
X1314467D01*
X1314652Y953113D01*
Y952939D01*
X1313252D01*
Y953113D01*
G37*
G36*
G01X1311404Y956319D02*
X1311589Y956919D01*
X1312619D01*
X1312804Y956319D01*
Y956144D01*
X1311404D01*
Y956319D01*
G37*
G36*
G01X1307704D02*
X1307889Y956919D01*
X1308919D01*
X1309104Y956319D01*
Y956144D01*
X1307704D01*
Y956319D01*
G37*
G36*
G01X1311404D02*
X1311589Y956919D01*
X1312619D01*
X1312804Y956319D01*
Y956144D01*
X1311404D01*
Y956319D01*
G37*
G36*
G01X1307704D02*
X1307889Y956919D01*
X1308919D01*
X1309104Y956319D01*
Y956144D01*
X1307704D01*
Y956319D01*
G37*
G36*
G01X1312715Y951517D02*
X1312530Y950917D01*
X1311500D01*
X1311315Y951517D01*
Y951691D01*
X1312715D01*
Y951517D01*
G37*
G36*
G01D02*
X1312530Y950917D01*
X1311500D01*
X1311315Y951517D01*
Y951691D01*
X1312715D01*
Y951517D01*
G37*
G36*
G01X1309037Y964333D02*
X1308852Y963733D01*
X1307822D01*
X1307637Y964333D01*
Y964508D01*
X1309037D01*
Y964333D01*
G37*
G36*
G01X1312737D02*
X1312552Y963733D01*
X1311522D01*
X1311337Y964333D01*
Y964508D01*
X1312737D01*
Y964333D01*
G37*
G36*
G01X1309037D02*
X1308852Y963733D01*
X1307822D01*
X1307637Y964333D01*
Y964508D01*
X1309037D01*
Y964333D01*
G37*
G36*
G01X1312737D02*
X1312552Y963733D01*
X1311522D01*
X1311337Y964333D01*
Y964508D01*
X1312737D01*
Y964333D01*
G37*
G36*
G01X1314654Y980355D02*
X1314469Y979755D01*
X1313439D01*
X1313254Y980355D01*
Y980530D01*
X1314654D01*
Y980355D01*
G37*
G36*
G01D02*
X1314469Y979755D01*
X1313439D01*
X1313254Y980355D01*
Y980530D01*
X1314654D01*
Y980355D01*
G37*
G36*
G01X1311371Y975543D02*
X1311556Y976143D01*
X1312586D01*
X1312771Y975543D01*
Y975368D01*
X1311371D01*
Y975543D01*
G37*
G36*
G01D02*
X1311556Y976143D01*
X1312586D01*
X1312771Y975543D01*
Y975368D01*
X1311371D01*
Y975543D01*
G37*
G36*
G01X1310921Y973947D02*
X1310736Y973347D01*
X1309706D01*
X1309521Y973947D01*
Y974122D01*
X1310921D01*
Y973947D01*
G37*
G36*
G01X1314621D02*
X1314436Y973347D01*
X1313406D01*
X1313221Y973947D01*
Y974122D01*
X1314621D01*
Y973947D01*
G37*
G36*
G01X1310921D02*
X1310736Y973347D01*
X1309706D01*
X1309521Y973947D01*
Y974122D01*
X1310921D01*
Y973947D01*
G37*
G36*
G01X1314621D02*
X1314436Y973347D01*
X1313406D01*
X1313221Y973947D01*
Y974122D01*
X1314621D01*
Y973947D01*
G37*
G36*
G01X1313254Y965931D02*
X1313439Y966531D01*
X1314469D01*
X1314654Y965931D01*
Y965757D01*
X1313254D01*
Y965931D01*
G37*
G36*
G01X1309554D02*
X1309739Y966531D01*
X1310769D01*
X1310954Y965931D01*
Y965757D01*
X1309554D01*
Y965931D01*
G37*
G36*
G01X1313254D02*
X1313439Y966531D01*
X1314469D01*
X1314654Y965931D01*
Y965757D01*
X1313254D01*
Y965931D01*
G37*
G36*
G01X1309554D02*
X1309739Y966531D01*
X1310769D01*
X1310954Y965931D01*
Y965757D01*
X1309554D01*
Y965931D01*
G37*
G36*
G01X1311371Y969135D02*
X1311556Y969735D01*
X1312586D01*
X1312771Y969135D01*
Y968960D01*
X1311371D01*
Y969135D01*
G37*
G36*
G01X1307671D02*
X1307856Y969735D01*
X1308886D01*
X1309071Y969135D01*
Y968960D01*
X1307671D01*
Y969135D01*
G37*
G36*
G01X1311371D02*
X1311556Y969735D01*
X1312586D01*
X1312771Y969135D01*
Y968960D01*
X1311371D01*
Y969135D01*
G37*
G36*
G01X1307671D02*
X1307856Y969735D01*
X1308886D01*
X1309071Y969135D01*
Y968960D01*
X1307671D01*
Y969135D01*
G37*
G36*
G01X1314621Y967539D02*
X1314436Y966939D01*
X1313406D01*
X1313221Y967539D01*
Y967714D01*
X1314621D01*
Y967539D01*
G37*
G36*
G01X1310921D02*
X1310736Y966939D01*
X1309706D01*
X1309521Y967539D01*
Y967714D01*
X1310921D01*
Y967539D01*
G37*
G36*
G01X1314621D02*
X1314436Y966939D01*
X1313406D01*
X1313221Y967539D01*
Y967714D01*
X1314621D01*
Y967539D01*
G37*
G36*
G01X1310921D02*
X1310736Y966939D01*
X1309706D01*
X1309521Y967539D01*
Y967714D01*
X1310921D01*
Y967539D01*
G37*
G36*
G01X1313653Y1005289D02*
X1313838Y1005889D01*
X1314868D01*
X1315053Y1005289D01*
Y1005114D01*
X1313653D01*
Y1005289D01*
G37*
G36*
G01D02*
X1313838Y1005889D01*
X1314868D01*
X1315053Y1005289D01*
Y1005114D01*
X1313653D01*
Y1005289D01*
G37*
G36*
G01Y1011697D02*
X1313838Y1012297D01*
X1314868D01*
X1315053Y1011697D01*
Y1011522D01*
X1313653D01*
Y1011697D01*
G37*
G36*
G01X1309953D02*
X1310138Y1012297D01*
X1311168D01*
X1311353Y1011697D01*
Y1011522D01*
X1309953D01*
Y1011697D01*
G37*
G36*
G01X1313653D02*
X1313838Y1012297D01*
X1314868D01*
X1315053Y1011697D01*
Y1011522D01*
X1313653D01*
Y1011697D01*
G37*
G36*
G01X1309953D02*
X1310138Y1012297D01*
X1311168D01*
X1311353Y1011697D01*
Y1011522D01*
X1309953D01*
Y1011697D01*
G37*
G36*
G01X1308103Y1008493D02*
X1308288Y1009093D01*
X1309318D01*
X1309503Y1008493D01*
Y1008318D01*
X1308103D01*
Y1008493D01*
G37*
G36*
G01X1311803D02*
X1311988Y1009093D01*
X1313018D01*
X1313203Y1008493D01*
Y1008318D01*
X1311803D01*
Y1008493D01*
G37*
G36*
G01X1308103D02*
X1308288Y1009093D01*
X1309318D01*
X1309503Y1008493D01*
Y1008318D01*
X1308103D01*
Y1008493D01*
G37*
G36*
G01X1311803D02*
X1311988Y1009093D01*
X1313018D01*
X1313203Y1008493D01*
Y1008318D01*
X1311803D01*
Y1008493D01*
G37*
G36*
G01X1309503Y1010101D02*
X1309318Y1009501D01*
X1308288D01*
X1308103Y1010101D01*
Y1010276D01*
X1309503D01*
Y1010101D01*
G37*
G36*
G01X1313203D02*
X1313018Y1009501D01*
X1311988D01*
X1311803Y1010101D01*
Y1010276D01*
X1313203D01*
Y1010101D01*
G37*
G36*
G01X1309503D02*
X1309318Y1009501D01*
X1308288D01*
X1308103Y1010101D01*
Y1010276D01*
X1309503D01*
Y1010101D01*
G37*
G36*
G01X1313203D02*
X1313018Y1009501D01*
X1311988D01*
X1311803Y1010101D01*
Y1010276D01*
X1313203D01*
Y1010101D01*
G37*
G36*
G01X1311353Y1006897D02*
X1311168Y1006297D01*
X1310138D01*
X1309953Y1006897D01*
Y1007072D01*
X1311353D01*
Y1006897D01*
G37*
G36*
G01X1315053D02*
X1314868Y1006297D01*
X1313838D01*
X1313653Y1006897D01*
Y1007072D01*
X1315053D01*
Y1006897D01*
G37*
G36*
G01X1311353D02*
X1311168Y1006297D01*
X1310138D01*
X1309953Y1006897D01*
Y1007072D01*
X1311353D01*
Y1006897D01*
G37*
G36*
G01X1315053D02*
X1314868Y1006297D01*
X1313838D01*
X1313653Y1006897D01*
Y1007072D01*
X1315053D01*
Y1006897D01*
G37*
G36*
G01X1313203Y1029327D02*
X1313018Y1028727D01*
X1311988D01*
X1311803Y1029327D01*
Y1029502D01*
X1313203D01*
Y1029327D01*
G37*
G36*
G01X1309503D02*
X1309318Y1028727D01*
X1308288D01*
X1308103Y1029327D01*
Y1029502D01*
X1309503D01*
Y1029327D01*
G37*
G36*
G01X1313203D02*
X1313018Y1028727D01*
X1311988D01*
X1311803Y1029327D01*
Y1029502D01*
X1313203D01*
Y1029327D01*
G37*
G36*
G01X1309503D02*
X1309318Y1028727D01*
X1308288D01*
X1308103Y1029327D01*
Y1029502D01*
X1309503D01*
Y1029327D01*
G37*
G36*
G01X1315053Y1019715D02*
X1314868Y1019115D01*
X1313838D01*
X1313653Y1019715D01*
Y1019889D01*
X1315053D01*
Y1019715D01*
G37*
G36*
G01X1311353D02*
X1311168Y1019115D01*
X1310138D01*
X1309953Y1019715D01*
Y1019889D01*
X1311353D01*
Y1019715D01*
G37*
G36*
G01X1315053D02*
X1314868Y1019115D01*
X1313838D01*
X1313653Y1019715D01*
Y1019889D01*
X1315053D01*
Y1019715D01*
G37*
G36*
G01X1311353D02*
X1311168Y1019115D01*
X1310138D01*
X1309953Y1019715D01*
Y1019889D01*
X1311353D01*
Y1019715D01*
G37*
G36*
G01X1313203Y1016509D02*
X1313018Y1015909D01*
X1311988D01*
X1311803Y1016509D01*
Y1016684D01*
X1313203D01*
Y1016509D01*
G37*
G36*
G01D02*
X1313018Y1015909D01*
X1311988D01*
X1311803Y1016509D01*
Y1016684D01*
X1313203D01*
Y1016509D01*
G37*
G36*
G01X1311803Y1021309D02*
X1311988Y1021909D01*
X1313018D01*
X1313203Y1021309D01*
Y1021135D01*
X1311803D01*
Y1021309D01*
G37*
G36*
G01D02*
X1311988Y1021909D01*
X1313018D01*
X1313203Y1021309D01*
Y1021135D01*
X1311803D01*
Y1021309D01*
G37*
G36*
G01X1313653Y1018105D02*
X1313838Y1018705D01*
X1314868D01*
X1315053Y1018105D01*
Y1017931D01*
X1313653D01*
Y1018105D01*
G37*
G36*
G01X1309953D02*
X1310138Y1018705D01*
X1311168D01*
X1311353Y1018105D01*
Y1017931D01*
X1309953D01*
Y1018105D01*
G37*
G36*
G01X1313653D02*
X1313838Y1018705D01*
X1314868D01*
X1315053Y1018105D01*
Y1017931D01*
X1313653D01*
Y1018105D01*
G37*
G36*
G01X1309953D02*
X1310138Y1018705D01*
X1311168D01*
X1311353Y1018105D01*
Y1017931D01*
X1309953D01*
Y1018105D01*
G37*
G36*
G01X1313203Y1022919D02*
X1313018Y1022319D01*
X1311988D01*
X1311803Y1022919D01*
Y1023093D01*
X1313203D01*
Y1022919D01*
G37*
G36*
G01X1309503D02*
X1309318Y1022319D01*
X1308288D01*
X1308103Y1022919D01*
Y1023093D01*
X1309503D01*
Y1022919D01*
G37*
G36*
G01X1313203D02*
X1313018Y1022319D01*
X1311988D01*
X1311803Y1022919D01*
Y1023093D01*
X1313203D01*
Y1022919D01*
G37*
G36*
G01X1309503D02*
X1309318Y1022319D01*
X1308288D01*
X1308103Y1022919D01*
Y1023093D01*
X1309503D01*
Y1022919D01*
G37*
G36*
G01X1311803Y1027719D02*
X1311988Y1028319D01*
X1313018D01*
X1313203Y1027719D01*
Y1027544D01*
X1311803D01*
Y1027719D01*
G37*
G36*
G01X1308103D02*
X1308288Y1028319D01*
X1309318D01*
X1309503Y1027719D01*
Y1027544D01*
X1308103D01*
Y1027719D01*
G37*
G36*
G01X1311803D02*
X1311988Y1028319D01*
X1313018D01*
X1313203Y1027719D01*
Y1027544D01*
X1311803D01*
Y1027719D01*
G37*
G36*
G01X1308103D02*
X1308288Y1028319D01*
X1309318D01*
X1309503Y1027719D01*
Y1027544D01*
X1308103D01*
Y1027719D01*
G37*
G36*
G01X1313653Y1024513D02*
X1313838Y1025113D01*
X1314868D01*
X1315053Y1024513D01*
Y1024339D01*
X1313653D01*
Y1024513D01*
G37*
G36*
G01X1309953D02*
X1310138Y1025113D01*
X1311168D01*
X1311353Y1024513D01*
Y1024339D01*
X1309953D01*
Y1024513D01*
G37*
G36*
G01X1313653D02*
X1313838Y1025113D01*
X1314868D01*
X1315053Y1024513D01*
Y1024339D01*
X1313653D01*
Y1024513D01*
G37*
G36*
G01X1309953D02*
X1310138Y1025113D01*
X1311168D01*
X1311353Y1024513D01*
Y1024339D01*
X1309953D01*
Y1024513D01*
G37*
G36*
G01X1315053Y1026123D02*
X1314868Y1025523D01*
X1313838D01*
X1313653Y1026123D01*
Y1026297D01*
X1315053D01*
Y1026123D01*
G37*
G36*
G01X1311353D02*
X1311168Y1025523D01*
X1310138D01*
X1309953Y1026123D01*
Y1026297D01*
X1311353D01*
Y1026123D01*
G37*
G36*
G01X1315053D02*
X1314868Y1025523D01*
X1313838D01*
X1313653Y1026123D01*
Y1026297D01*
X1315053D01*
Y1026123D01*
G37*
G36*
G01X1311353D02*
X1311168Y1025523D01*
X1310138D01*
X1309953Y1026123D01*
Y1026297D01*
X1311353D01*
Y1026123D01*
G37*
G36*
G01Y1032531D02*
X1311168Y1031931D01*
X1310138D01*
X1309953Y1032531D01*
Y1032706D01*
X1311353D01*
Y1032531D01*
G37*
G36*
G01X1315053D02*
X1314868Y1031931D01*
X1313838D01*
X1313653Y1032531D01*
Y1032706D01*
X1315053D01*
Y1032531D01*
G37*
G36*
G01X1311353D02*
X1311168Y1031931D01*
X1310138D01*
X1309953Y1032531D01*
Y1032706D01*
X1311353D01*
Y1032531D01*
G37*
G36*
G01X1315053D02*
X1314868Y1031931D01*
X1313838D01*
X1313653Y1032531D01*
Y1032706D01*
X1315053D01*
Y1032531D01*
G37*
G36*
G01X1311803Y1034127D02*
X1311988Y1034727D01*
X1313018D01*
X1313203Y1034127D01*
Y1033952D01*
X1311803D01*
Y1034127D01*
G37*
G36*
G01D02*
X1311988Y1034727D01*
X1313018D01*
X1313203Y1034127D01*
Y1033952D01*
X1311803D01*
Y1034127D01*
G37*
G36*
G01X1313653Y1030923D02*
X1313838Y1031523D01*
X1314868D01*
X1315053Y1030923D01*
Y1030748D01*
X1313653D01*
Y1030923D01*
G37*
G36*
G01X1309953D02*
X1310138Y1031523D01*
X1311168D01*
X1311353Y1030923D01*
Y1030748D01*
X1309953D01*
Y1030923D01*
G37*
G36*
G01X1313653D02*
X1313838Y1031523D01*
X1314868D01*
X1315053Y1030923D01*
Y1030748D01*
X1313653D01*
Y1030923D01*
G37*
G36*
G01X1309953D02*
X1310138Y1031523D01*
X1311168D01*
X1311353Y1030923D01*
Y1030748D01*
X1309953D01*
Y1030923D01*
G37*
G36*
G01X1311803Y1040535D02*
X1311988Y1041135D01*
X1313018D01*
X1313203Y1040535D01*
Y1040361D01*
X1311803D01*
Y1040535D01*
G37*
G36*
G01D02*
X1311988Y1041135D01*
X1313018D01*
X1313203Y1040535D01*
Y1040361D01*
X1311803D01*
Y1040535D01*
G37*
G36*
G01X1309953Y1037331D02*
X1310138Y1037931D01*
X1311168D01*
X1311353Y1037331D01*
Y1037157D01*
X1309953D01*
Y1037331D01*
G37*
G36*
G01X1313653D02*
X1313838Y1037931D01*
X1314868D01*
X1315053Y1037331D01*
Y1037157D01*
X1313653D01*
Y1037331D01*
G37*
G36*
G01X1309953D02*
X1310138Y1037931D01*
X1311168D01*
X1311353Y1037331D01*
Y1037157D01*
X1309953D01*
Y1037331D01*
G37*
G36*
G01X1313653D02*
X1313838Y1037931D01*
X1314868D01*
X1315053Y1037331D01*
Y1037157D01*
X1313653D01*
Y1037331D01*
G37*
G36*
G01X1315053Y1038941D02*
X1314868Y1038341D01*
X1313838D01*
X1313653Y1038941D01*
Y1039115D01*
X1315053D01*
Y1038941D01*
G37*
G36*
G01X1311353D02*
X1311168Y1038341D01*
X1310138D01*
X1309953Y1038941D01*
Y1039115D01*
X1311353D01*
Y1038941D01*
G37*
G36*
G01X1315053D02*
X1314868Y1038341D01*
X1313838D01*
X1313653Y1038941D01*
Y1039115D01*
X1315053D01*
Y1038941D01*
G37*
G36*
G01X1311353D02*
X1311168Y1038341D01*
X1310138D01*
X1309953Y1038941D01*
Y1039115D01*
X1311353D01*
Y1038941D01*
G37*
G36*
G01X1313203Y1035735D02*
X1313018Y1035135D01*
X1311988D01*
X1311803Y1035735D01*
Y1035910D01*
X1313203D01*
Y1035735D01*
G37*
G36*
G01D02*
X1313018Y1035135D01*
X1311988D01*
X1311803Y1035735D01*
Y1035910D01*
X1313203D01*
Y1035735D01*
G37*
G36*
G01X1315053Y1045349D02*
X1314868Y1044749D01*
X1313838D01*
X1313653Y1045349D01*
Y1045523D01*
X1315053D01*
Y1045349D01*
G37*
G36*
G01D02*
X1314868Y1044749D01*
X1313838D01*
X1313653Y1045349D01*
Y1045523D01*
X1315053D01*
Y1045349D01*
G37*
G36*
G01X1313653Y1043739D02*
X1313838Y1044339D01*
X1314868D01*
X1315053Y1043739D01*
Y1043565D01*
X1313653D01*
Y1043739D01*
G37*
G36*
G01D02*
X1313838Y1044339D01*
X1314868D01*
X1315053Y1043739D01*
Y1043565D01*
X1313653D01*
Y1043739D01*
G37*
G36*
G01X1310785Y1042722D02*
X1310173Y1042582D01*
X1309658Y1043474D01*
X1310085Y1043934D01*
X1310236Y1044021D01*
X1310936Y1042809D01*
X1310785Y1042722D01*
G37*
G36*
G01X1313203Y1042145D02*
X1313018Y1041545D01*
X1311988D01*
X1311803Y1042145D01*
Y1042319D01*
X1313203D01*
Y1042145D01*
G37*
G36*
G01X1310785Y1042722D02*
X1310173Y1042582D01*
X1309658Y1043474D01*
X1310085Y1043934D01*
X1310236Y1044021D01*
X1310936Y1042809D01*
X1310785Y1042722D01*
G37*
G36*
G01X1313203Y1042145D02*
X1313018Y1041545D01*
X1311988D01*
X1311803Y1042145D01*
Y1042319D01*
X1313203D01*
Y1042145D01*
G37*
G36*
G01X1314485Y1055539D02*
X1313873Y1055399D01*
X1313358Y1056291D01*
X1313785Y1056751D01*
X1313936Y1056838D01*
X1314636Y1055626D01*
X1314485Y1055539D01*
G37*
G36*
G01D02*
X1313873Y1055399D01*
X1313358Y1056291D01*
X1313785Y1056751D01*
X1313936Y1056838D01*
X1314636Y1055626D01*
X1314485Y1055539D01*
G37*
G36*
G01X1312371Y1055979D02*
X1312983Y1056119D01*
X1313498Y1055227D01*
X1313071Y1054767D01*
X1312920Y1054680D01*
X1312220Y1055892D01*
X1312371Y1055979D01*
G37*
G36*
G01D02*
X1312983Y1056119D01*
X1313498Y1055227D01*
X1313071Y1054767D01*
X1312920Y1054680D01*
X1312220Y1055892D01*
X1312371Y1055979D01*
G37*
G36*
G01X1313653Y1050149D02*
X1313838Y1050749D01*
X1314868D01*
X1315053Y1050149D01*
Y1049974D01*
X1313653D01*
Y1050149D01*
G37*
G36*
G01X1310513Y1052790D02*
X1311125Y1052930D01*
X1311640Y1052038D01*
X1311213Y1051578D01*
X1311062Y1051491D01*
X1310362Y1052703D01*
X1310513Y1052790D01*
G37*
G36*
G01X1313653Y1050149D02*
X1313838Y1050749D01*
X1314868D01*
X1315053Y1050149D01*
Y1049974D01*
X1313653D01*
Y1050149D01*
G37*
G36*
G01X1310513Y1052790D02*
X1311125Y1052930D01*
X1311640Y1052038D01*
X1311213Y1051578D01*
X1311062Y1051491D01*
X1310362Y1052703D01*
X1310513Y1052790D01*
G37*
G36*
G01X1315053Y1051757D02*
X1314868Y1051157D01*
X1313838D01*
X1313653Y1051757D01*
Y1051931D01*
X1315053D01*
Y1051757D01*
G37*
G36*
G01X1312643Y1052319D02*
X1312031Y1052179D01*
X1311516Y1053071D01*
X1311943Y1053531D01*
X1312094Y1053618D01*
X1312794Y1052406D01*
X1312643Y1052319D01*
G37*
G36*
G01X1315053Y1051757D02*
X1314868Y1051157D01*
X1313838D01*
X1313653Y1051757D01*
Y1051931D01*
X1315053D01*
Y1051757D01*
G37*
G36*
G01X1312643Y1052319D02*
X1312031Y1052179D01*
X1311516Y1053071D01*
X1311943Y1053531D01*
X1312094Y1053618D01*
X1312794Y1052406D01*
X1312643Y1052319D01*
G37*
G36*
G01X1315087Y1077391D02*
X1314902Y1076791D01*
X1313872D01*
X1313687Y1077391D01*
Y1077565D01*
X1315087D01*
Y1077391D01*
G37*
G36*
G01D02*
X1314902Y1076791D01*
X1313872D01*
X1313687Y1077391D01*
Y1077565D01*
X1315087D01*
Y1077391D01*
G37*
G36*
G01X1313180Y1074187D02*
X1312995Y1073587D01*
X1311965D01*
X1311780Y1074187D01*
Y1074362D01*
X1313180D01*
Y1074187D01*
G37*
G36*
G01D02*
X1312995Y1073587D01*
X1311965D01*
X1311780Y1074187D01*
Y1074362D01*
X1313180D01*
Y1074187D01*
G37*
G36*
G01X1313687Y1075783D02*
X1313872Y1076383D01*
X1314902D01*
X1315087Y1075783D01*
Y1075609D01*
X1313687D01*
Y1075783D01*
G37*
G36*
G01D02*
X1313872Y1076383D01*
X1314902D01*
X1315087Y1075783D01*
Y1075609D01*
X1313687D01*
Y1075783D01*
G37*
G36*
G01X1314489Y1068349D02*
X1313877Y1068209D01*
X1313362Y1069101D01*
X1313789Y1069561D01*
X1313940Y1069648D01*
X1314640Y1068436D01*
X1314489Y1068349D01*
G37*
G36*
G01D02*
X1313877Y1068209D01*
X1313362Y1069101D01*
X1313789Y1069561D01*
X1313940Y1069648D01*
X1314640Y1068436D01*
X1314489Y1068349D01*
G37*
G36*
G01X1312371Y1068796D02*
X1312983Y1068936D01*
X1313498Y1068044D01*
X1313071Y1067584D01*
X1312920Y1067497D01*
X1312220Y1068709D01*
X1312371Y1068796D01*
G37*
G36*
G01D02*
X1312983Y1068936D01*
X1313498Y1068044D01*
X1313071Y1067584D01*
X1312920Y1067497D01*
X1312220Y1068709D01*
X1312371Y1068796D01*
G37*
G36*
G01X1313686Y1088600D02*
X1313871Y1089200D01*
X1314901D01*
X1315086Y1088600D01*
Y1088426D01*
X1313686D01*
Y1088600D01*
G37*
G36*
G01D02*
X1313871Y1089200D01*
X1314901D01*
X1315086Y1088600D01*
Y1088426D01*
X1313686D01*
Y1088600D01*
G37*
G36*
G01X1314467Y1081201D02*
X1313855Y1081061D01*
X1313340Y1081953D01*
X1313767Y1082413D01*
X1313918Y1082500D01*
X1314618Y1081288D01*
X1314467Y1081201D01*
G37*
G36*
G01D02*
X1313855Y1081061D01*
X1313340Y1081953D01*
X1313767Y1082413D01*
X1313918Y1082500D01*
X1314618Y1081288D01*
X1314467Y1081201D01*
G37*
G36*
G01X1314485Y1100399D02*
X1313873Y1100259D01*
X1313358Y1101151D01*
X1313785Y1101611D01*
X1313936Y1101698D01*
X1314636Y1100486D01*
X1314485Y1100399D01*
G37*
G36*
G01D02*
X1313873Y1100259D01*
X1313358Y1101151D01*
X1313785Y1101611D01*
X1313936Y1101698D01*
X1314636Y1100486D01*
X1314485Y1100399D01*
G37*
G36*
G01X1379750Y889105D02*
X1381292D01*
G03X1382371Y888531I1079J727D01*
G03X1382849Y888622I0J1301D01*
G01X1382972Y888670D01*
X1383420Y888222D01*
G02X1383392Y887630I-283J-283D01*
G03X1382919Y886627I827J-1003D01*
G03X1383593Y885487I1301J0D01*
G01X1383697Y885430D01*
Y884851D01*
G02X1383079Y884515I-400J0D01*
G03X1382371Y884725I-709J-1092D01*
G03X1381069Y883423I0J-1302D01*
G03X1382131Y882143I1302J0D01*
G01X1382222Y882126D01*
X1383023Y880738D01*
X1382992Y880652D01*
G03X1382918Y880219I1228J-433D01*
G03X1383593Y879078I1302J0D01*
G01X1383697Y879021D01*
Y878441D01*
G02X1383079Y878105I-400J0D01*
G03X1382371Y878315I-709J-1091D01*
G03Y875713I0J-1301D01*
G03X1383079Y875923I-1J1301D01*
G02X1383697Y875587I218J-336D01*
G01Y875007D01*
X1383593Y874950D01*
G03Y872670I627J-1140D01*
G01X1383697Y872613D01*
Y872033D01*
G02X1383079Y871697I-400J0D01*
G03X1382371Y871907I-709J-1091D01*
G03X1381070Y870606I0J-1301D01*
G03X1381504Y869636I1301J0D01*
G02X1381521Y869055I-266J-299D01*
G01X1381058Y868592D01*
X1380941Y868633D01*
G03X1380521Y868702I-418J-1232D01*
G03X1379220Y867401I0J-1301D01*
G03X1379289Y866981I1301J-2D01*
G01X1379330Y866864D01*
X1376880Y864414D01*
G02X1376215Y864579I-283J283D01*
G03X1374971Y865498I-1244J-382D01*
G03X1373670Y864197I0J-1301D01*
G03X1374589Y862953I1301J0D01*
G02X1374754Y862288I-118J-382D01*
G01X1374487Y862021D01*
G02X1373949Y861996I-283J283D01*
G03X1373120Y862294I-829J-1004D01*
G03X1371819Y860993I0J-1301D01*
G03X1371893Y860561I1301J1D01*
G01X1371923Y860474D01*
X1371121Y859085D01*
X1371031Y859068D01*
G03X1369970Y857789I240J-1279D01*
G03X1372572I1301J0D01*
G03X1372498Y858221I-1301J-1D01*
G01X1372468Y858308D01*
X1373270Y859697D01*
X1373360Y859714D01*
G03X1373372Y859717I-309J1262D01*
G01X1373391Y859720D01*
X1373610D01*
Y856283D01*
G02X1373189Y855883I-400J-1D01*
G03X1373121Y855885I-72J-1299D01*
G03Y853283I0J-1301D01*
G03X1373189Y853285I-4J1301D01*
G02X1373610Y852885I21J-399D01*
G01Y852645D01*
X1371576D01*
X1371554Y852650D01*
G03X1371271Y852681I-282J-1270D01*
G03X1370988Y852650I-1J-1301D01*
G01X1370966Y852645D01*
X1367876D01*
X1367854Y852650D01*
G03X1367571Y852681I-282J-1270D01*
G03X1367288Y852650I-1J-1301D01*
G01X1367266Y852645D01*
X1364176D01*
X1364154Y852650D01*
G03X1363871Y852681I-282J-1270D01*
G03X1363588Y852650I-1J-1301D01*
G01X1363566Y852645D01*
X1360476D01*
X1360454Y852650D01*
G03X1360171Y852681I-282J-1270D01*
G03X1359888Y852650I-1J-1301D01*
G01X1359866Y852645D01*
X1356776D01*
X1356754Y852650D01*
G03X1356471Y852681I-282J-1270D01*
G03X1356188Y852650I-1J-1301D01*
G01X1356166Y852645D01*
X1353076D01*
X1353054Y852650D01*
G03X1352771Y852681I-282J-1270D01*
G03X1352488Y852650I-1J-1301D01*
G01X1352466Y852645D01*
X1349376D01*
X1349354Y852650D01*
G03X1349071Y852681I-282J-1270D01*
G03X1348788Y852650I-1J-1301D01*
G01X1348766Y852645D01*
X1345676D01*
X1345654Y852650D01*
G03X1345371Y852681I-282J-1270D01*
G03X1345088Y852650I-1J-1301D01*
G01X1345066Y852645D01*
X1341976D01*
X1341954Y852650D01*
G03X1341671Y852681I-282J-1270D01*
G03X1341388Y852650I-1J-1301D01*
G01X1341366Y852645D01*
X1338276D01*
X1338254Y852650D01*
G03X1337971Y852681I-282J-1270D01*
G03X1337688Y852650I-1J-1301D01*
G01X1337666Y852645D01*
X1334576D01*
X1334554Y852650D01*
G03X1334271Y852681I-282J-1270D01*
G03X1333988Y852650I-1J-1301D01*
G01X1333966Y852645D01*
X1331557D01*
X1329976Y854226D01*
X1329997Y854331D01*
G03X1330022Y854584I-1276J254D01*
G03X1328721Y855885I-1301J0D01*
G03X1327426Y854713I0J-1301D01*
G02X1327010Y854353I-398J39D01*
G03X1326869Y854356I-134J-2973D01*
G03X1326731Y854353I-4J-2976D01*
G02X1326315Y854713I-18J400D01*
G03X1325020Y855885I-1295J-129D01*
G03X1324972Y855884I3J-1301D01*
G02X1324557Y856284I-15J400D01*
G01Y861345D01*
X1324862Y861650D01*
X1327039D01*
G02X1327434Y861190I0J-400D01*
G03X1327419Y860993I1286J-197D01*
G03X1327493Y860561I1301J1D01*
G01X1327523Y860474D01*
X1326721Y859085D01*
X1326631Y859068D01*
G03X1325570Y857789I240J-1279D01*
G03X1328172I1301J0D01*
G03X1328098Y858221I-1301J-1D01*
G01X1328068Y858308D01*
X1328870Y859697D01*
X1328960Y859714D01*
G03X1330021Y860993I-240J1279D01*
G03X1330006Y861190I-1301J0D01*
G02X1330401Y861650I395J60D01*
G01X1331552D01*
X1333107Y863205D01*
X1333427D01*
X1333480Y863164D01*
G03X1334271Y862896I791J1033D01*
G03X1335113Y863205I0J1302D01*
G01X1337129D01*
G03X1338813I842J993D01*
G01X1340829D01*
G03X1342513I842J993D01*
G01X1344529D01*
G03X1346213I842J993D01*
G01X1348229D01*
G03X1349913I842J993D01*
G01X1351929D01*
G03X1353613I842J993D01*
G01X1355629D01*
G03X1356471Y862896I842J993D01*
G03X1357772Y864197I0J1301D01*
G03X1357722Y864554I-1301J0D01*
G01X1357690Y864668D01*
X1360135Y867113D01*
G02X1360794Y866964I282J-283D01*
G03X1362020Y866100I1226J438D01*
G03X1363321Y867401I0J1301D01*
G03X1362260Y868680I-1301J0D01*
G01X1362170Y868697D01*
X1361368Y870087D01*
X1361398Y870174D01*
G03X1361472Y870606I-1227J433D01*
G03X1361077Y871540I-1302J0D01*
G01Y874665D01*
X1362487Y876075D01*
X1362971D01*
G03X1364771I900J938D01*
G01X1366671D01*
G03X1368471I900J938D01*
G01X1370371D01*
G03X1371271Y875713I900J938D01*
G03X1372572Y877014I0J1301D01*
G03X1372571Y877076I-1301J10D01*
G01X1372566Y877164D01*
X1372587Y877185D01*
Y878340D01*
X1373164Y878917D01*
X1373236Y878923D01*
G03X1374422Y880219I-115J1296D01*
G03X1374068Y881111I-1301J0D01*
G02X1374072Y881390I145J137D01*
G01X1374448Y881766D01*
G02X1375078Y881683I283J-283D01*
G01X1375623Y880738D01*
X1375592Y880652D01*
G03X1375518Y880219I1228J-433D01*
G03X1378122I1302J0D01*
G03X1377059Y881499I-1302J0D01*
G01X1376968Y881516D01*
X1376168Y882903D01*
X1376199Y882990D01*
G03X1376273Y883423I-1228J433D01*
G03X1375401Y884652I-1302J0D01*
G01X1375267Y884699D01*
Y888355D01*
X1375612Y888700D01*
G03X1376050Y889105I-641J1132D01*
G01X1377592D01*
G03X1379750I1079J727D01*
G37*
G36*
G01X1316921Y882619D02*
X1317106Y883219D01*
X1318136D01*
X1318321Y882619D01*
Y882444D01*
X1316921D01*
Y882619D01*
G37*
G36*
G01X1320621D02*
X1320806Y883219D01*
X1321836D01*
X1322021Y882619D01*
Y882444D01*
X1320621D01*
Y882619D01*
G37*
G36*
G01X1324453Y884033D02*
X1324026Y884493D01*
X1324541Y885385D01*
X1325153Y885245D01*
X1325304Y885158D01*
X1324604Y883946D01*
X1324453Y884033D01*
G37*
G36*
G01X1316921Y882619D02*
X1317106Y883219D01*
X1318136D01*
X1318321Y882619D01*
Y882444D01*
X1316921D01*
Y882619D01*
G37*
G36*
G01X1320621D02*
X1320806Y883219D01*
X1321836D01*
X1322021Y882619D01*
Y882444D01*
X1320621D01*
Y882619D01*
G37*
G36*
G01X1324453Y884033D02*
X1324026Y884493D01*
X1324541Y885385D01*
X1325153Y885245D01*
X1325304Y885158D01*
X1324604Y883946D01*
X1324453Y884033D01*
G37*
G36*
G01X1318321Y877819D02*
X1318136Y877219D01*
X1317106D01*
X1316921Y877819D01*
Y877993D01*
X1318321D01*
Y877819D01*
G37*
G36*
G01X1322045Y877817D02*
X1321860Y877217D01*
X1320830D01*
X1320645Y877817D01*
Y877992D01*
X1322045D01*
Y877817D01*
G37*
G36*
G01X1325754D02*
X1325569Y877217D01*
X1324539D01*
X1324354Y877817D01*
Y877992D01*
X1325754D01*
Y877817D01*
G37*
G36*
G01X1318321Y877819D02*
X1318136Y877219D01*
X1317106D01*
X1316921Y877819D01*
Y877993D01*
X1318321D01*
Y877819D01*
G37*
G36*
G01X1322045Y877817D02*
X1321860Y877217D01*
X1320830D01*
X1320645Y877817D01*
Y877992D01*
X1322045D01*
Y877817D01*
G37*
G36*
G01X1325754D02*
X1325569Y877217D01*
X1324539D01*
X1324354Y877817D01*
Y877992D01*
X1325754D01*
Y877817D01*
G37*
G36*
G01X1329289Y882813D02*
X1329716Y882353D01*
X1329201Y881461D01*
X1328589Y881601D01*
X1328438Y881688D01*
X1329138Y882900D01*
X1329289Y882813D01*
G37*
G36*
G01D02*
X1329716Y882353D01*
X1329201Y881461D01*
X1328589Y881601D01*
X1328438Y881688D01*
X1329138Y882900D01*
X1329289Y882813D01*
G37*
G36*
G01X1316471Y881023D02*
X1316286Y880423D01*
X1315256D01*
X1315071Y881023D01*
Y881198D01*
X1316471D01*
Y881023D01*
G37*
G36*
G01X1320171D02*
X1319986Y880423D01*
X1318956D01*
X1318771Y881023D01*
Y881198D01*
X1320171D01*
Y881023D01*
G37*
G36*
G01X1323847D02*
X1323662Y880423D01*
X1322632D01*
X1322447Y881023D01*
Y881198D01*
X1323847D01*
Y881023D01*
G37*
G36*
G01X1316471D02*
X1316286Y880423D01*
X1315256D01*
X1315071Y881023D01*
Y881198D01*
X1316471D01*
Y881023D01*
G37*
G36*
G01X1320171D02*
X1319986Y880423D01*
X1318956D01*
X1318771Y881023D01*
Y881198D01*
X1320171D01*
Y881023D01*
G37*
G36*
G01X1323847D02*
X1323662Y880423D01*
X1322632D01*
X1322447Y881023D01*
Y881198D01*
X1323847D01*
Y881023D01*
G37*
G36*
G01X1315071Y879415D02*
X1315256Y880015D01*
X1316286D01*
X1316471Y879415D01*
Y879240D01*
X1315071D01*
Y879415D01*
G37*
G36*
G01X1328152Y884033D02*
X1327725Y884493D01*
X1328240Y885385D01*
X1328852Y885245D01*
X1329003Y885158D01*
X1328303Y883946D01*
X1328152Y884033D01*
G37*
G36*
G01X1322438Y879415D02*
X1322623Y880015D01*
X1323653D01*
X1323838Y879415D01*
Y879241D01*
X1322438D01*
Y879415D01*
G37*
G36*
G01X1318771D02*
X1318956Y880015D01*
X1319986D01*
X1320171Y879415D01*
Y879240D01*
X1318771D01*
Y879415D01*
G37*
G36*
G01X1315071D02*
X1315256Y880015D01*
X1316286D01*
X1316471Y879415D01*
Y879240D01*
X1315071D01*
Y879415D01*
G37*
G36*
G01X1328152Y884033D02*
X1327725Y884493D01*
X1328240Y885385D01*
X1328852Y885245D01*
X1329003Y885158D01*
X1328303Y883946D01*
X1328152Y884033D01*
G37*
G36*
G01X1322438Y879415D02*
X1322623Y880015D01*
X1323653D01*
X1323838Y879415D01*
Y879241D01*
X1322438D01*
Y879415D01*
G37*
G36*
G01X1318771D02*
X1318956Y880015D01*
X1319986D01*
X1320171Y879415D01*
Y879240D01*
X1318771D01*
Y879415D01*
G37*
G36*
G01X1326273Y880779D02*
X1325846Y881239D01*
X1326361Y882131D01*
X1326973Y881991D01*
X1327124Y881904D01*
X1326424Y880692D01*
X1326273Y880779D01*
G37*
G36*
G01X1318321Y884227D02*
X1318136Y883627D01*
X1317106D01*
X1316921Y884227D01*
Y884402D01*
X1318321D01*
Y884227D01*
G37*
G36*
G01X1322021D02*
X1321836Y883627D01*
X1320806D01*
X1320621Y884227D01*
Y884402D01*
X1322021D01*
Y884227D01*
G37*
G36*
G01X1318321D02*
X1318136Y883627D01*
X1317106D01*
X1316921Y884227D01*
Y884402D01*
X1318321D01*
Y884227D01*
G37*
G36*
G01X1322021D02*
X1321836Y883627D01*
X1320806D01*
X1320621Y884227D01*
Y884402D01*
X1322021D01*
Y884227D01*
G37*
G36*
G01X1316447Y893841D02*
X1316262Y893241D01*
X1315232D01*
X1315047Y893841D01*
Y894015D01*
X1316447D01*
Y893841D01*
G37*
G36*
G01X1318206Y895658D02*
X1318633Y895198D01*
X1318118Y894306D01*
X1317506Y894446D01*
X1317355Y894533D01*
X1318055Y895745D01*
X1318206Y895658D01*
G37*
G36*
G01X1320034Y898827D02*
X1320461Y898367D01*
X1319946Y897475D01*
X1319334Y897615D01*
X1319183Y897702D01*
X1319883Y898914D01*
X1320034Y898827D01*
G37*
G36*
G01X1323847Y900249D02*
X1323662Y899649D01*
X1322632D01*
X1322447Y900249D01*
Y900424D01*
X1323847D01*
Y900249D01*
G37*
G36*
G01X1327537D02*
X1327352Y899649D01*
X1326322D01*
X1326137Y900249D01*
Y900423D01*
X1327537D01*
Y900249D01*
G37*
G36*
G01X1331237D02*
X1331052Y899649D01*
X1330022D01*
X1329837Y900249D01*
Y900423D01*
X1331237D01*
Y900249D01*
G37*
G36*
G01X1316447Y893841D02*
X1316262Y893241D01*
X1315232D01*
X1315047Y893841D01*
Y894015D01*
X1316447D01*
Y893841D01*
G37*
G36*
G01X1318206Y895658D02*
X1318633Y895198D01*
X1318118Y894306D01*
X1317506Y894446D01*
X1317355Y894533D01*
X1318055Y895745D01*
X1318206Y895658D01*
G37*
G36*
G01X1320034Y898827D02*
X1320461Y898367D01*
X1319946Y897475D01*
X1319334Y897615D01*
X1319183Y897702D01*
X1319883Y898914D01*
X1320034Y898827D01*
G37*
G36*
G01X1323847Y900249D02*
X1323662Y899649D01*
X1322632D01*
X1322447Y900249D01*
Y900424D01*
X1323847D01*
Y900249D01*
G37*
G36*
G01X1327537D02*
X1327352Y899649D01*
X1326322D01*
X1326137Y900249D01*
Y900423D01*
X1327537D01*
Y900249D01*
G37*
G36*
G01X1331237D02*
X1331052Y899649D01*
X1330022D01*
X1329837Y900249D01*
Y900423D01*
X1331237D01*
Y900249D01*
G37*
G36*
G01X1315047Y892231D02*
X1315232Y892831D01*
X1316262D01*
X1316447Y892231D01*
Y892057D01*
X1315047D01*
Y892231D01*
G37*
G36*
G01X1318885Y893617D02*
X1318458Y894077D01*
X1318973Y894969D01*
X1319585Y894829D01*
X1319736Y894742D01*
X1319036Y893530D01*
X1318885Y893617D01*
G37*
G36*
G01X1320750Y896847D02*
X1320323Y897307D01*
X1320838Y898199D01*
X1321450Y898059D01*
X1321601Y897972D01*
X1320901Y896760D01*
X1320750Y896847D01*
G37*
G36*
G01X1322447Y898641D02*
X1322632Y899241D01*
X1323662D01*
X1323847Y898641D01*
Y898466D01*
X1322447D01*
Y898641D01*
G37*
G36*
G01X1326137D02*
X1326322Y899241D01*
X1327352D01*
X1327537Y898641D01*
Y898467D01*
X1326137D01*
Y898641D01*
G37*
G36*
G01X1329837D02*
X1330022Y899241D01*
X1331052D01*
X1331237Y898641D01*
Y898467D01*
X1329837D01*
Y898641D01*
G37*
G36*
G01X1315047Y892231D02*
X1315232Y892831D01*
X1316262D01*
X1316447Y892231D01*
Y892057D01*
X1315047D01*
Y892231D01*
G37*
G36*
G01X1318885Y893617D02*
X1318458Y894077D01*
X1318973Y894969D01*
X1319585Y894829D01*
X1319736Y894742D01*
X1319036Y893530D01*
X1318885Y893617D01*
G37*
G36*
G01X1320750Y896847D02*
X1320323Y897307D01*
X1320838Y898199D01*
X1321450Y898059D01*
X1321601Y897972D01*
X1320901Y896760D01*
X1320750Y896847D01*
G37*
G36*
G01X1322447Y898641D02*
X1322632Y899241D01*
X1323662D01*
X1323847Y898641D01*
Y898466D01*
X1322447D01*
Y898641D01*
G37*
G36*
G01X1326137D02*
X1326322Y899241D01*
X1327352D01*
X1327537Y898641D01*
Y898467D01*
X1326137D01*
Y898641D01*
G37*
G36*
G01X1329837D02*
X1330022Y899241D01*
X1331052D01*
X1331237Y898641D01*
Y898467D01*
X1329837D01*
Y898641D01*
G37*
G36*
G01X1317056Y896858D02*
X1316629Y897318D01*
X1317144Y898210D01*
X1317756Y898070D01*
X1317907Y897983D01*
X1317207Y896771D01*
X1317056Y896858D01*
G37*
G36*
G01X1318908Y900065D02*
X1318481Y900525D01*
X1318996Y901417D01*
X1319608Y901277D01*
X1319759Y901190D01*
X1319059Y899978D01*
X1318908Y900065D01*
G37*
G36*
G01X1317056Y896858D02*
X1316629Y897318D01*
X1317144Y898210D01*
X1317756Y898070D01*
X1317907Y897983D01*
X1317207Y896771D01*
X1317056Y896858D01*
G37*
G36*
G01X1318908Y900065D02*
X1318481Y900525D01*
X1318996Y901417D01*
X1319608Y901277D01*
X1319759Y901190D01*
X1319059Y899978D01*
X1318908Y900065D01*
G37*
G36*
G01X1318344Y890637D02*
X1318159Y890037D01*
X1317129D01*
X1316944Y890637D01*
Y890811D01*
X1318344D01*
Y890637D01*
G37*
G36*
G01X1320063Y892466D02*
X1320490Y892006D01*
X1319975Y891114D01*
X1319363Y891254D01*
X1319212Y891341D01*
X1319912Y892553D01*
X1320063Y892466D01*
G37*
G36*
G01X1321906Y895659D02*
X1322333Y895199D01*
X1321818Y894307D01*
X1321206Y894447D01*
X1321055Y894534D01*
X1321755Y895746D01*
X1321906Y895659D01*
G37*
G36*
G01X1325754Y897043D02*
X1325569Y896443D01*
X1324539D01*
X1324354Y897043D01*
Y897218D01*
X1325754D01*
Y897043D01*
G37*
G36*
G01X1329454D02*
X1329269Y896443D01*
X1328239D01*
X1328054Y897043D01*
Y897218D01*
X1329454D01*
Y897043D01*
G37*
G36*
G01X1318344Y890637D02*
X1318159Y890037D01*
X1317129D01*
X1316944Y890637D01*
Y890811D01*
X1318344D01*
Y890637D01*
G37*
G36*
G01X1320063Y892466D02*
X1320490Y892006D01*
X1319975Y891114D01*
X1319363Y891254D01*
X1319212Y891341D01*
X1319912Y892553D01*
X1320063Y892466D01*
G37*
G36*
G01X1321906Y895659D02*
X1322333Y895199D01*
X1321818Y894307D01*
X1321206Y894447D01*
X1321055Y894534D01*
X1321755Y895746D01*
X1321906Y895659D01*
G37*
G36*
G01X1325754Y897043D02*
X1325569Y896443D01*
X1324539D01*
X1324354Y897043D01*
Y897218D01*
X1325754D01*
Y897043D01*
G37*
G36*
G01X1329454D02*
X1329269Y896443D01*
X1328239D01*
X1328054Y897043D01*
Y897218D01*
X1329454D01*
Y897043D01*
G37*
G36*
G01X1326306Y887245D02*
X1325879Y887705D01*
X1326394Y888597D01*
X1327006Y888457D01*
X1327157Y888370D01*
X1326457Y887158D01*
X1326306Y887245D01*
G37*
G36*
G01X1328054Y889029D02*
X1328239Y889629D01*
X1329269D01*
X1329454Y889029D01*
Y888854D01*
X1328054D01*
Y889029D01*
G37*
G36*
G01X1326306Y887245D02*
X1325879Y887705D01*
X1326394Y888597D01*
X1327006Y888457D01*
X1327157Y888370D01*
X1326457Y887158D01*
X1326306Y887245D01*
G37*
G36*
G01X1328054Y889029D02*
X1328239Y889629D01*
X1329269D01*
X1329454Y889029D01*
Y888854D01*
X1328054D01*
Y889029D01*
G37*
G36*
G01X1327439Y886017D02*
X1327866Y885557D01*
X1327351Y884665D01*
X1326739Y884805D01*
X1326588Y884892D01*
X1327288Y886104D01*
X1327439Y886017D01*
G37*
G36*
G01D02*
X1327866Y885557D01*
X1327351Y884665D01*
X1326739Y884805D01*
X1326588Y884892D01*
X1327288Y886104D01*
X1327439Y886017D01*
G37*
G36*
G01X1331237Y887431D02*
X1331052Y886831D01*
X1330022D01*
X1329837Y887431D01*
Y887605D01*
X1331237D01*
Y887431D01*
G37*
G36*
G01D02*
X1331052Y886831D01*
X1330022D01*
X1329837Y887431D01*
Y887605D01*
X1331237D01*
Y887431D01*
G37*
G36*
G01Y893839D02*
X1331052Y893239D01*
X1330022D01*
X1329837Y893839D01*
Y894014D01*
X1331237D01*
Y893839D01*
G37*
G36*
G01X1327537D02*
X1327352Y893239D01*
X1326322D01*
X1326137Y893839D01*
Y894014D01*
X1327537D01*
Y893839D01*
G37*
G36*
G01X1323739Y892426D02*
X1324166Y891966D01*
X1323651Y891074D01*
X1323039Y891214D01*
X1322888Y891301D01*
X1323588Y892513D01*
X1323739Y892426D01*
G37*
G36*
G01X1321885Y889214D02*
X1322312Y888754D01*
X1321797Y887862D01*
X1321185Y888002D01*
X1321034Y888089D01*
X1321734Y889301D01*
X1321885Y889214D01*
G37*
G36*
G01X1331237Y893839D02*
X1331052Y893239D01*
X1330022D01*
X1329837Y893839D01*
Y894014D01*
X1331237D01*
Y893839D01*
G37*
G36*
G01X1327537D02*
X1327352Y893239D01*
X1326322D01*
X1326137Y893839D01*
Y894014D01*
X1327537D01*
Y893839D01*
G37*
G36*
G01X1323739Y892426D02*
X1324166Y891966D01*
X1323651Y891074D01*
X1323039Y891214D01*
X1322888Y891301D01*
X1323588Y892513D01*
X1323739Y892426D01*
G37*
G36*
G01X1321885Y889214D02*
X1322312Y888754D01*
X1321797Y887862D01*
X1321185Y888002D01*
X1321034Y888089D01*
X1321734Y889301D01*
X1321885Y889214D01*
G37*
G36*
G01X1316471Y887431D02*
X1316286Y886831D01*
X1315256D01*
X1315071Y887431D01*
Y887606D01*
X1316471D01*
Y887431D01*
G37*
G36*
G01X1320204D02*
X1320019Y886831D01*
X1318989D01*
X1318804Y887431D01*
Y887605D01*
X1320204D01*
Y887431D01*
G37*
G36*
G01X1316471D02*
X1316286Y886831D01*
X1315256D01*
X1315071Y887431D01*
Y887606D01*
X1316471D01*
Y887431D01*
G37*
G36*
G01X1320204D02*
X1320019Y886831D01*
X1318989D01*
X1318804Y887431D01*
Y887605D01*
X1320204D01*
Y887431D01*
G37*
G36*
G01X1329837Y892233D02*
X1330022Y892833D01*
X1331052D01*
X1331237Y892233D01*
Y892058D01*
X1329837D01*
Y892233D01*
G37*
G36*
G01X1326137D02*
X1326322Y892833D01*
X1327352D01*
X1327537Y892233D01*
Y892058D01*
X1326137D01*
Y892233D01*
G37*
G36*
G01X1324457Y890452D02*
X1324030Y890912D01*
X1324545Y891804D01*
X1325157Y891664D01*
X1325308Y891577D01*
X1324608Y890365D01*
X1324457Y890452D01*
G37*
G36*
G01X1322611Y887253D02*
X1322184Y887713D01*
X1322699Y888605D01*
X1323311Y888465D01*
X1323462Y888378D01*
X1322762Y887166D01*
X1322611Y887253D01*
G37*
G36*
G01X1329837Y892233D02*
X1330022Y892833D01*
X1331052D01*
X1331237Y892233D01*
Y892058D01*
X1329837D01*
Y892233D01*
G37*
G36*
G01X1326137D02*
X1326322Y892833D01*
X1327352D01*
X1327537Y892233D01*
Y892058D01*
X1326137D01*
Y892233D01*
G37*
G36*
G01X1324457Y890452D02*
X1324030Y890912D01*
X1324545Y891804D01*
X1325157Y891664D01*
X1325308Y891577D01*
X1324608Y890365D01*
X1324457Y890452D01*
G37*
G36*
G01X1322611Y887253D02*
X1322184Y887713D01*
X1322699Y888605D01*
X1323311Y888465D01*
X1323462Y888378D01*
X1322762Y887166D01*
X1322611Y887253D01*
G37*
G36*
G01X1315071Y885823D02*
X1315256Y886423D01*
X1316286D01*
X1316471Y885823D01*
Y885648D01*
X1315071D01*
Y885823D01*
G37*
G36*
G01X1318771D02*
X1318956Y886423D01*
X1319986D01*
X1320171Y885823D01*
Y885648D01*
X1318771D01*
Y885823D01*
G37*
G36*
G01X1315071D02*
X1315256Y886423D01*
X1316286D01*
X1316471Y885823D01*
Y885648D01*
X1315071D01*
Y885823D01*
G37*
G36*
G01X1318771D02*
X1318956Y886423D01*
X1319986D01*
X1320171Y885823D01*
Y885648D01*
X1318771D01*
Y885823D01*
G37*
G36*
G01X1316897Y889027D02*
X1317082Y889627D01*
X1318112D01*
X1318297Y889027D01*
Y888853D01*
X1316897D01*
Y889027D01*
G37*
G36*
G01X1328054Y895437D02*
X1328239Y896037D01*
X1329269D01*
X1329454Y895437D01*
Y895262D01*
X1328054D01*
Y895437D01*
G37*
G36*
G01X1324354D02*
X1324539Y896037D01*
X1325569D01*
X1325754Y895437D01*
Y895262D01*
X1324354D01*
Y895437D01*
G37*
G36*
G01X1322585Y893618D02*
X1322158Y894078D01*
X1322673Y894970D01*
X1323285Y894830D01*
X1323436Y894743D01*
X1322736Y893531D01*
X1322585Y893618D01*
G37*
G36*
G01X1320728Y890402D02*
X1320301Y890862D01*
X1320816Y891754D01*
X1321428Y891614D01*
X1321579Y891527D01*
X1320879Y890315D01*
X1320728Y890402D01*
G37*
G36*
G01X1316897Y889027D02*
X1317082Y889627D01*
X1318112D01*
X1318297Y889027D01*
Y888853D01*
X1316897D01*
Y889027D01*
G37*
G36*
G01X1328054Y895437D02*
X1328239Y896037D01*
X1329269D01*
X1329454Y895437D01*
Y895262D01*
X1328054D01*
Y895437D01*
G37*
G36*
G01X1324354D02*
X1324539Y896037D01*
X1325569D01*
X1325754Y895437D01*
Y895262D01*
X1324354D01*
Y895437D01*
G37*
G36*
G01X1322585Y893618D02*
X1322158Y894078D01*
X1322673Y894970D01*
X1323285Y894830D01*
X1323436Y894743D01*
X1322736Y893531D01*
X1322585Y893618D01*
G37*
G36*
G01X1320728Y890402D02*
X1320301Y890862D01*
X1320816Y891754D01*
X1321428Y891614D01*
X1321579Y891527D01*
X1320879Y890315D01*
X1320728Y890402D01*
G37*
G36*
G01X1329454Y890635D02*
X1329269Y890035D01*
X1328239D01*
X1328054Y890635D01*
Y890810D01*
X1329454D01*
Y890635D01*
G37*
G36*
G01X1325581Y889206D02*
X1326008Y888746D01*
X1325493Y887854D01*
X1324881Y887994D01*
X1324730Y888081D01*
X1325430Y889293D01*
X1325581Y889206D01*
G37*
G36*
G01X1329454Y890635D02*
X1329269Y890035D01*
X1328239D01*
X1328054Y890635D01*
Y890810D01*
X1329454D01*
Y890635D01*
G37*
G36*
G01X1325581Y889206D02*
X1326008Y888746D01*
X1325493Y887854D01*
X1324881Y887994D01*
X1324730Y888081D01*
X1325430Y889293D01*
X1325581Y889206D01*
G37*
G36*
G01X1323739Y886017D02*
X1324166Y885557D01*
X1323651Y884665D01*
X1323039Y884805D01*
X1322888Y884892D01*
X1323588Y886104D01*
X1323739Y886017D01*
G37*
G36*
G01D02*
X1324166Y885557D01*
X1323651Y884665D01*
X1323039Y884805D01*
X1322888Y884892D01*
X1323588Y886104D01*
X1323739Y886017D01*
G37*
G36*
G01X1316471Y900251D02*
X1316286Y899651D01*
X1315256D01*
X1315071Y900251D01*
Y900425D01*
X1316471D01*
Y900251D01*
G37*
G36*
G01D02*
X1316286Y899651D01*
X1315256D01*
X1315071Y900251D01*
Y900425D01*
X1316471D01*
Y900251D01*
G37*
G36*
G01X1320597Y901845D02*
X1320782Y902445D01*
X1321812D01*
X1321997Y901845D01*
Y901671D01*
X1320597D01*
Y901845D01*
G37*
G36*
G01X1324354D02*
X1324539Y902445D01*
X1325569D01*
X1325754Y901845D01*
Y901671D01*
X1324354D01*
Y901845D01*
G37*
G36*
G01X1328054D02*
X1328239Y902445D01*
X1329269D01*
X1329454Y901845D01*
Y901671D01*
X1328054D01*
Y901845D01*
G37*
G36*
G01X1320597D02*
X1320782Y902445D01*
X1321812D01*
X1321997Y901845D01*
Y901671D01*
X1320597D01*
Y901845D01*
G37*
G36*
G01X1324354D02*
X1324539Y902445D01*
X1325569D01*
X1325754Y901845D01*
Y901671D01*
X1324354D01*
Y901845D01*
G37*
G36*
G01X1328054D02*
X1328239Y902445D01*
X1329269D01*
X1329454Y901845D01*
Y901671D01*
X1328054D01*
Y901845D01*
G37*
G36*
G01X1318321Y916271D02*
X1318136Y915671D01*
X1317106D01*
X1316921Y916271D01*
Y916446D01*
X1318321D01*
Y916271D01*
G37*
G36*
G01X1322021D02*
X1321836Y915671D01*
X1320806D01*
X1320621Y916271D01*
Y916445D01*
X1322021D01*
Y916271D01*
G37*
G36*
G01X1323739Y918060D02*
X1324166Y917600D01*
X1323651Y916708D01*
X1323039Y916848D01*
X1322888Y916935D01*
X1323588Y918147D01*
X1323739Y918060D01*
G37*
G36*
G01X1318321Y916271D02*
X1318136Y915671D01*
X1317106D01*
X1316921Y916271D01*
Y916446D01*
X1318321D01*
Y916271D01*
G37*
G36*
G01X1322021D02*
X1321836Y915671D01*
X1320806D01*
X1320621Y916271D01*
Y916445D01*
X1322021D01*
Y916271D01*
G37*
G36*
G01X1323739Y918060D02*
X1324166Y917600D01*
X1323651Y916708D01*
X1323039Y916848D01*
X1322888Y916935D01*
X1323588Y918147D01*
X1323739Y918060D01*
G37*
G36*
G01X1315207Y906472D02*
X1314780Y906932D01*
X1315295Y907824D01*
X1315907Y907684D01*
X1316058Y907597D01*
X1315358Y906385D01*
X1315207Y906472D01*
G37*
G36*
G01X1316954Y908255D02*
X1317139Y908855D01*
X1318169D01*
X1318354Y908255D01*
Y908080D01*
X1316954D01*
Y908255D01*
G37*
G36*
G01X1328054Y908253D02*
X1328239Y908853D01*
X1329269D01*
X1329454Y908253D01*
Y908079D01*
X1328054D01*
Y908253D01*
G37*
G36*
G01X1320621D02*
X1320806Y908853D01*
X1321836D01*
X1322021Y908253D01*
Y908079D01*
X1320621D01*
Y908253D01*
G37*
G36*
G01X1324354D02*
X1324539Y908853D01*
X1325569D01*
X1325754Y908253D01*
Y908079D01*
X1324354D01*
Y908253D01*
G37*
G36*
G01X1315207Y906472D02*
X1314780Y906932D01*
X1315295Y907824D01*
X1315907Y907684D01*
X1316058Y907597D01*
X1315358Y906385D01*
X1315207Y906472D01*
G37*
G36*
G01X1316954Y908255D02*
X1317139Y908855D01*
X1318169D01*
X1318354Y908255D01*
Y908080D01*
X1316954D01*
Y908255D01*
G37*
G36*
G01X1328054Y908253D02*
X1328239Y908853D01*
X1329269D01*
X1329454Y908253D01*
Y908079D01*
X1328054D01*
Y908253D01*
G37*
G36*
G01X1320621D02*
X1320806Y908853D01*
X1321836D01*
X1322021Y908253D01*
Y908079D01*
X1320621D01*
Y908253D01*
G37*
G36*
G01X1324354D02*
X1324539Y908853D01*
X1325569D01*
X1325754Y908253D01*
Y908079D01*
X1324354D01*
Y908253D01*
G37*
G36*
G01X1317052Y903260D02*
X1316625Y903720D01*
X1317140Y904612D01*
X1317752Y904472D01*
X1317903Y904385D01*
X1317203Y903173D01*
X1317052Y903260D01*
G37*
G36*
G01X1329847Y905049D02*
X1330032Y905649D01*
X1331062D01*
X1331247Y905049D01*
Y904875D01*
X1329847D01*
Y905049D01*
G37*
G36*
G01X1326137D02*
X1326322Y905649D01*
X1327352D01*
X1327537Y905049D01*
Y904875D01*
X1326137D01*
Y905049D01*
G37*
G36*
G01X1322432D02*
X1322617Y905649D01*
X1323647D01*
X1323832Y905049D01*
Y904875D01*
X1322432D01*
Y905049D01*
G37*
G36*
G01X1318810Y905051D02*
X1318995Y905651D01*
X1320025D01*
X1320210Y905051D01*
Y904876D01*
X1318810D01*
Y905051D01*
G37*
G36*
G01X1317052Y903260D02*
X1316625Y903720D01*
X1317140Y904612D01*
X1317752Y904472D01*
X1317903Y904385D01*
X1317203Y903173D01*
X1317052Y903260D01*
G37*
G36*
G01X1329847Y905049D02*
X1330032Y905649D01*
X1331062D01*
X1331247Y905049D01*
Y904875D01*
X1329847D01*
Y905049D01*
G37*
G36*
G01X1326137D02*
X1326322Y905649D01*
X1327352D01*
X1327537Y905049D01*
Y904875D01*
X1326137D01*
Y905049D01*
G37*
G36*
G01X1322432D02*
X1322617Y905649D01*
X1323647D01*
X1323832Y905049D01*
Y904875D01*
X1322432D01*
Y905049D01*
G37*
G36*
G01X1318810Y905051D02*
X1318995Y905651D01*
X1320025D01*
X1320210Y905051D01*
Y904876D01*
X1318810D01*
Y905051D01*
G37*
G36*
G01X1316339Y905243D02*
X1316766Y904783D01*
X1316251Y903891D01*
X1315639Y904031D01*
X1315488Y904118D01*
X1316188Y905330D01*
X1316339Y905243D01*
G37*
G36*
G01X1320131Y906657D02*
X1319946Y906057D01*
X1318916D01*
X1318731Y906657D01*
Y906831D01*
X1320131D01*
Y906657D01*
G37*
G36*
G01X1323847D02*
X1323662Y906057D01*
X1322632D01*
X1322447Y906657D01*
Y906832D01*
X1323847D01*
Y906657D01*
G37*
G36*
G01X1327537D02*
X1327352Y906057D01*
X1326322D01*
X1326137Y906657D01*
Y906831D01*
X1327537D01*
Y906657D01*
G37*
G36*
G01X1331247D02*
X1331062Y906057D01*
X1330032D01*
X1329847Y906657D01*
Y906831D01*
X1331247D01*
Y906657D01*
G37*
G36*
G01X1316339Y905243D02*
X1316766Y904783D01*
X1316251Y903891D01*
X1315639Y904031D01*
X1315488Y904118D01*
X1316188Y905330D01*
X1316339Y905243D01*
G37*
G36*
G01X1320131Y906657D02*
X1319946Y906057D01*
X1318916D01*
X1318731Y906657D01*
Y906831D01*
X1320131D01*
Y906657D01*
G37*
G36*
G01X1323847D02*
X1323662Y906057D01*
X1322632D01*
X1322447Y906657D01*
Y906832D01*
X1323847D01*
Y906657D01*
G37*
G36*
G01X1327537D02*
X1327352Y906057D01*
X1326322D01*
X1326137Y906657D01*
Y906831D01*
X1327537D01*
Y906657D01*
G37*
G36*
G01X1331247D02*
X1331062Y906057D01*
X1330032D01*
X1329847Y906657D01*
Y906831D01*
X1331247D01*
Y906657D01*
G37*
G36*
G01X1318189Y902039D02*
X1318616Y901579D01*
X1318101Y900687D01*
X1317489Y900827D01*
X1317338Y900914D01*
X1318038Y902126D01*
X1318189Y902039D01*
G37*
G36*
G01X1329454Y903453D02*
X1329269Y902853D01*
X1328239D01*
X1328054Y903453D01*
Y903627D01*
X1329454D01*
Y903453D01*
G37*
G36*
G01X1325754D02*
X1325569Y902853D01*
X1324539D01*
X1324354Y903453D01*
Y903627D01*
X1325754D01*
Y903453D01*
G37*
G36*
G01X1321997D02*
X1321812Y902853D01*
X1320782D01*
X1320597Y903453D01*
Y903627D01*
X1321997D01*
Y903453D01*
G37*
G36*
G01X1318189Y902039D02*
X1318616Y901579D01*
X1318101Y900687D01*
X1317489Y900827D01*
X1317338Y900914D01*
X1318038Y902126D01*
X1318189Y902039D01*
G37*
G36*
G01X1329454Y903453D02*
X1329269Y902853D01*
X1328239D01*
X1328054Y903453D01*
Y903627D01*
X1329454D01*
Y903453D01*
G37*
G36*
G01X1325754D02*
X1325569Y902853D01*
X1324539D01*
X1324354Y903453D01*
Y903627D01*
X1325754D01*
Y903453D01*
G37*
G36*
G01X1321997D02*
X1321812Y902853D01*
X1320782D01*
X1320597Y903453D01*
Y903627D01*
X1321997D01*
Y903453D01*
G37*
G36*
G01X1316471Y913067D02*
X1316286Y912467D01*
X1315256D01*
X1315071Y913067D01*
Y913241D01*
X1316471D01*
Y913067D01*
G37*
G36*
G01X1323847D02*
X1323662Y912467D01*
X1322632D01*
X1322447Y913067D01*
Y913241D01*
X1323847D01*
Y913067D01*
G37*
G36*
G01X1320171D02*
X1319986Y912467D01*
X1318956D01*
X1318771Y913067D01*
Y913241D01*
X1320171D01*
Y913067D01*
G37*
G36*
G01X1329306Y914884D02*
X1329733Y914424D01*
X1329218Y913532D01*
X1328606Y913672D01*
X1328455Y913759D01*
X1329155Y914971D01*
X1329306Y914884D01*
G37*
G36*
G01X1327537Y913065D02*
X1327352Y912465D01*
X1326322D01*
X1326137Y913065D01*
Y913240D01*
X1327537D01*
Y913065D01*
G37*
G36*
G01X1316471Y913067D02*
X1316286Y912467D01*
X1315256D01*
X1315071Y913067D01*
Y913241D01*
X1316471D01*
Y913067D01*
G37*
G36*
G01X1323847D02*
X1323662Y912467D01*
X1322632D01*
X1322447Y913067D01*
Y913241D01*
X1323847D01*
Y913067D01*
G37*
G36*
G01X1320171D02*
X1319986Y912467D01*
X1318956D01*
X1318771Y913067D01*
Y913241D01*
X1320171D01*
Y913067D01*
G37*
G36*
G01X1329306Y914884D02*
X1329733Y914424D01*
X1329218Y913532D01*
X1328606Y913672D01*
X1328455Y913759D01*
X1329155Y914971D01*
X1329306Y914884D01*
G37*
G36*
G01X1327537Y913065D02*
X1327352Y912465D01*
X1326322D01*
X1326137Y913065D01*
Y913240D01*
X1327537D01*
Y913065D01*
G37*
G36*
G01X1315071Y911457D02*
X1315256Y912057D01*
X1316286D01*
X1316471Y911457D01*
Y911283D01*
X1315071D01*
Y911457D01*
G37*
G36*
G01X1329985Y912844D02*
X1329558Y913304D01*
X1330073Y914196D01*
X1330685Y914056D01*
X1330836Y913969D01*
X1330136Y912757D01*
X1329985Y912844D01*
G37*
G36*
G01X1326137Y911459D02*
X1326322Y912059D01*
X1327352D01*
X1327537Y911459D01*
Y911284D01*
X1326137D01*
Y911459D01*
G37*
G36*
G01X1322447Y911457D02*
X1322632Y912057D01*
X1323662D01*
X1323847Y911457D01*
Y911283D01*
X1322447D01*
Y911457D01*
G37*
G36*
G01X1318771D02*
X1318956Y912057D01*
X1319986D01*
X1320171Y911457D01*
Y911283D01*
X1318771D01*
Y911457D01*
G37*
G36*
G01X1315071D02*
X1315256Y912057D01*
X1316286D01*
X1316471Y911457D01*
Y911283D01*
X1315071D01*
Y911457D01*
G37*
G36*
G01X1329985Y912844D02*
X1329558Y913304D01*
X1330073Y914196D01*
X1330685Y914056D01*
X1330836Y913969D01*
X1330136Y912757D01*
X1329985Y912844D01*
G37*
G36*
G01X1326137Y911459D02*
X1326322Y912059D01*
X1327352D01*
X1327537Y911459D01*
Y911284D01*
X1326137D01*
Y911459D01*
G37*
G36*
G01X1322447Y911457D02*
X1322632Y912057D01*
X1323662D01*
X1323847Y911457D01*
Y911283D01*
X1322447D01*
Y911457D01*
G37*
G36*
G01X1318771D02*
X1318956Y912057D01*
X1319986D01*
X1320171Y911457D01*
Y911283D01*
X1318771D01*
Y911457D01*
G37*
G36*
G01X1316921Y914661D02*
X1317106Y915261D01*
X1318136D01*
X1318321Y914661D01*
Y914487D01*
X1316921D01*
Y914661D01*
G37*
G36*
G01X1328157Y916086D02*
X1327730Y916546D01*
X1328245Y917438D01*
X1328857Y917298D01*
X1329008Y917211D01*
X1328308Y915999D01*
X1328157Y916086D01*
G37*
G36*
G01X1324354Y914663D02*
X1324539Y915263D01*
X1325569D01*
X1325754Y914663D01*
Y914488D01*
X1324354D01*
Y914663D01*
G37*
G36*
G01X1320621Y914661D02*
X1320806Y915261D01*
X1321836D01*
X1322021Y914661D01*
Y914487D01*
X1320621D01*
Y914661D01*
G37*
G36*
G01X1316921D02*
X1317106Y915261D01*
X1318136D01*
X1318321Y914661D01*
Y914487D01*
X1316921D01*
Y914661D01*
G37*
G36*
G01X1328157Y916086D02*
X1327730Y916546D01*
X1328245Y917438D01*
X1328857Y917298D01*
X1329008Y917211D01*
X1328308Y915999D01*
X1328157Y916086D01*
G37*
G36*
G01X1324354Y914663D02*
X1324539Y915263D01*
X1325569D01*
X1325754Y914663D01*
Y914488D01*
X1324354D01*
Y914663D01*
G37*
G36*
G01X1320621Y914661D02*
X1320806Y915261D01*
X1321836D01*
X1322021Y914661D01*
Y914487D01*
X1320621D01*
Y914661D01*
G37*
G36*
G01X1318321Y909863D02*
X1318136Y909263D01*
X1317106D01*
X1316921Y909863D01*
Y910037D01*
X1318321D01*
Y909863D01*
G37*
G36*
G01X1329454Y909861D02*
X1329269Y909261D01*
X1328239D01*
X1328054Y909861D01*
Y910035D01*
X1329454D01*
Y909861D01*
G37*
G36*
G01X1325754D02*
X1325569Y909261D01*
X1324539D01*
X1324354Y909861D01*
Y910035D01*
X1325754D01*
Y909861D01*
G37*
G36*
G01X1322052D02*
X1321867Y909261D01*
X1320837D01*
X1320652Y909861D01*
Y910036D01*
X1322052D01*
Y909861D01*
G37*
G36*
G01X1318321Y909863D02*
X1318136Y909263D01*
X1317106D01*
X1316921Y909863D01*
Y910037D01*
X1318321D01*
Y909863D01*
G37*
G36*
G01X1329454Y909861D02*
X1329269Y909261D01*
X1328239D01*
X1328054Y909861D01*
Y910035D01*
X1329454D01*
Y909861D01*
G37*
G36*
G01X1325754D02*
X1325569Y909261D01*
X1324539D01*
X1324354Y909861D01*
Y910035D01*
X1325754D01*
Y909861D01*
G37*
G36*
G01X1322052D02*
X1321867Y909261D01*
X1320837D01*
X1320652Y909861D01*
Y910036D01*
X1322052D01*
Y909861D01*
G37*
G36*
G01X1317053Y928894D02*
X1316626Y929354D01*
X1317141Y930246D01*
X1317753Y930106D01*
X1317904Y930019D01*
X1317204Y928807D01*
X1317053Y928894D01*
G37*
G36*
G01X1318771Y930683D02*
X1318956Y931283D01*
X1319986D01*
X1320171Y930683D01*
Y930509D01*
X1318771D01*
Y930683D01*
G37*
G36*
G01X1322471D02*
X1322656Y931283D01*
X1323686D01*
X1323871Y930683D01*
Y930509D01*
X1322471D01*
Y930683D01*
G37*
G36*
G01X1326147D02*
X1326332Y931283D01*
X1327362D01*
X1327547Y930683D01*
Y930509D01*
X1326147D01*
Y930683D01*
G37*
G36*
G01X1329837Y930685D02*
X1330022Y931285D01*
X1331052D01*
X1331237Y930685D01*
Y930510D01*
X1329837D01*
Y930685D01*
G37*
G36*
G01X1317053Y928894D02*
X1316626Y929354D01*
X1317141Y930246D01*
X1317753Y930106D01*
X1317904Y930019D01*
X1317204Y928807D01*
X1317053Y928894D01*
G37*
G36*
G01X1318771Y930683D02*
X1318956Y931283D01*
X1319986D01*
X1320171Y930683D01*
Y930509D01*
X1318771D01*
Y930683D01*
G37*
G36*
G01X1322471D02*
X1322656Y931283D01*
X1323686D01*
X1323871Y930683D01*
Y930509D01*
X1322471D01*
Y930683D01*
G37*
G36*
G01X1326147D02*
X1326332Y931283D01*
X1327362D01*
X1327547Y930683D01*
Y930509D01*
X1326147D01*
Y930683D01*
G37*
G36*
G01X1329837Y930685D02*
X1330022Y931285D01*
X1331052D01*
X1331237Y930685D01*
Y930510D01*
X1329837D01*
Y930685D01*
G37*
G36*
G01X1315050Y924275D02*
X1315235Y924875D01*
X1316265D01*
X1316450Y924275D01*
Y924101D01*
X1315050D01*
Y924275D01*
G37*
G36*
G01X1328054Y927479D02*
X1328239Y928079D01*
X1329269D01*
X1329454Y927479D01*
Y927305D01*
X1328054D01*
Y927479D01*
G37*
G36*
G01X1324354D02*
X1324539Y928079D01*
X1325569D01*
X1325754Y927479D01*
Y927305D01*
X1324354D01*
Y927479D01*
G37*
G36*
G01X1320621D02*
X1320806Y928079D01*
X1321836D01*
X1322021Y927479D01*
Y927305D01*
X1320621D01*
Y927479D01*
G37*
G36*
G01X1318878Y925649D02*
X1318451Y926109D01*
X1318966Y927001D01*
X1319578Y926861D01*
X1319729Y926774D01*
X1319029Y925562D01*
X1318878Y925649D01*
G37*
G36*
G01X1315050Y924275D02*
X1315235Y924875D01*
X1316265D01*
X1316450Y924275D01*
Y924101D01*
X1315050D01*
Y924275D01*
G37*
G36*
G01X1328054Y927479D02*
X1328239Y928079D01*
X1329269D01*
X1329454Y927479D01*
Y927305D01*
X1328054D01*
Y927479D01*
G37*
G36*
G01X1324354D02*
X1324539Y928079D01*
X1325569D01*
X1325754Y927479D01*
Y927305D01*
X1324354D01*
Y927479D01*
G37*
G36*
G01X1320621D02*
X1320806Y928079D01*
X1321836D01*
X1322021Y927479D01*
Y927305D01*
X1320621D01*
Y927479D01*
G37*
G36*
G01X1318878Y925649D02*
X1318451Y926109D01*
X1318966Y927001D01*
X1319578Y926861D01*
X1319729Y926774D01*
X1319029Y925562D01*
X1318878Y925649D01*
G37*
G36*
G01X1316492Y925883D02*
X1316307Y925283D01*
X1315277D01*
X1315092Y925883D01*
Y926058D01*
X1316492D01*
Y925883D01*
G37*
G36*
G01X1318186Y927666D02*
X1318613Y927206D01*
X1318098Y926314D01*
X1317486Y926454D01*
X1317335Y926541D01*
X1318035Y927753D01*
X1318186Y927666D01*
G37*
G36*
G01X1322052Y929087D02*
X1321867Y928487D01*
X1320837D01*
X1320652Y929087D01*
Y929262D01*
X1322052D01*
Y929087D01*
G37*
G36*
G01X1325721D02*
X1325536Y928487D01*
X1324506D01*
X1324321Y929087D01*
Y929262D01*
X1325721D01*
Y929087D01*
G37*
G36*
G01X1329454D02*
X1329269Y928487D01*
X1328239D01*
X1328054Y929087D01*
Y929261D01*
X1329454D01*
Y929087D01*
G37*
G36*
G01X1316492Y925883D02*
X1316307Y925283D01*
X1315277D01*
X1315092Y925883D01*
Y926058D01*
X1316492D01*
Y925883D01*
G37*
G36*
G01X1318186Y927666D02*
X1318613Y927206D01*
X1318098Y926314D01*
X1317486Y926454D01*
X1317335Y926541D01*
X1318035Y927753D01*
X1318186Y927666D01*
G37*
G36*
G01X1322052Y929087D02*
X1321867Y928487D01*
X1320837D01*
X1320652Y929087D01*
Y929262D01*
X1322052D01*
Y929087D01*
G37*
G36*
G01X1325721D02*
X1325536Y928487D01*
X1324506D01*
X1324321Y929087D01*
Y929262D01*
X1325721D01*
Y929087D01*
G37*
G36*
G01X1329454D02*
X1329269Y928487D01*
X1328239D01*
X1328054Y929087D01*
Y929261D01*
X1329454D01*
Y929087D01*
G37*
G36*
G01X1318344Y922679D02*
X1318159Y922079D01*
X1317129D01*
X1316944Y922679D01*
Y922853D01*
X1318344D01*
Y922679D01*
G37*
G36*
G01X1320056Y924498D02*
X1320483Y924038D01*
X1319968Y923146D01*
X1319356Y923286D01*
X1319205Y923373D01*
X1319905Y924585D01*
X1320056Y924498D01*
G37*
G36*
G01X1323847Y925883D02*
X1323662Y925283D01*
X1322632D01*
X1322447Y925883D01*
Y926058D01*
X1323847D01*
Y925883D01*
G37*
G36*
G01X1327537D02*
X1327352Y925283D01*
X1326322D01*
X1326137Y925883D01*
Y926057D01*
X1327537D01*
Y925883D01*
G37*
G36*
G01X1331247D02*
X1331062Y925283D01*
X1330032D01*
X1329847Y925883D01*
Y926057D01*
X1331247D01*
Y925883D01*
G37*
G36*
G01X1318344Y922679D02*
X1318159Y922079D01*
X1317129D01*
X1316944Y922679D01*
Y922853D01*
X1318344D01*
Y922679D01*
G37*
G36*
G01X1320056Y924498D02*
X1320483Y924038D01*
X1319968Y923146D01*
X1319356Y923286D01*
X1319205Y923373D01*
X1319905Y924585D01*
X1320056Y924498D01*
G37*
G36*
G01X1323847Y925883D02*
X1323662Y925283D01*
X1322632D01*
X1322447Y925883D01*
Y926058D01*
X1323847D01*
Y925883D01*
G37*
G36*
G01X1327537D02*
X1327352Y925283D01*
X1326322D01*
X1326137Y925883D01*
Y926057D01*
X1327537D01*
Y925883D01*
G37*
G36*
G01X1331247D02*
X1331062Y925283D01*
X1330032D01*
X1329847Y925883D01*
Y926057D01*
X1331247D01*
Y925883D01*
G37*
G36*
G01X1315203Y932098D02*
X1314776Y932558D01*
X1315291Y933450D01*
X1315903Y933310D01*
X1316054Y933223D01*
X1315354Y932011D01*
X1315203Y932098D01*
G37*
G36*
G01D02*
X1314776Y932558D01*
X1315291Y933450D01*
X1315903Y933310D01*
X1316054Y933223D01*
X1315354Y932011D01*
X1315203Y932098D01*
G37*
G36*
G01X1316339Y930878D02*
X1316766Y930418D01*
X1316251Y929526D01*
X1315639Y929666D01*
X1315488Y929753D01*
X1316188Y930965D01*
X1316339Y930878D01*
G37*
G36*
G01X1323871Y932291D02*
X1323686Y931691D01*
X1322656D01*
X1322471Y932291D01*
Y932466D01*
X1323871D01*
Y932291D01*
G37*
G36*
G01X1320204D02*
X1320019Y931691D01*
X1318989D01*
X1318804Y932291D01*
Y932466D01*
X1320204D01*
Y932291D01*
G37*
G36*
G01X1331237D02*
X1331052Y931691D01*
X1330022D01*
X1329837Y932291D01*
Y932465D01*
X1331237D01*
Y932291D01*
G37*
G36*
G01X1327547D02*
X1327362Y931691D01*
X1326332D01*
X1326147Y932291D01*
Y932466D01*
X1327547D01*
Y932291D01*
G37*
G36*
G01X1316339Y930878D02*
X1316766Y930418D01*
X1316251Y929526D01*
X1315639Y929666D01*
X1315488Y929753D01*
X1316188Y930965D01*
X1316339Y930878D01*
G37*
G36*
G01X1323871Y932291D02*
X1323686Y931691D01*
X1322656D01*
X1322471Y932291D01*
Y932466D01*
X1323871D01*
Y932291D01*
G37*
G36*
G01X1320204D02*
X1320019Y931691D01*
X1318989D01*
X1318804Y932291D01*
Y932466D01*
X1320204D01*
Y932291D01*
G37*
G36*
G01X1331237D02*
X1331052Y931691D01*
X1330022D01*
X1329837Y932291D01*
Y932465D01*
X1331237D01*
Y932291D01*
G37*
G36*
G01X1327547D02*
X1327362Y931691D01*
X1326332D01*
X1326147Y932291D01*
Y932466D01*
X1327547D01*
Y932291D01*
G37*
G36*
G01X1316897Y921073D02*
X1317082Y921673D01*
X1318112D01*
X1318297Y921073D01*
Y920898D01*
X1316897D01*
Y921073D01*
G37*
G36*
G01X1320761Y922501D02*
X1320334Y922961D01*
X1320849Y923853D01*
X1321461Y923713D01*
X1321612Y923626D01*
X1320912Y922414D01*
X1320761Y922501D01*
G37*
G36*
G01X1322432Y924275D02*
X1322617Y924875D01*
X1323647D01*
X1323832Y924275D01*
Y924101D01*
X1322432D01*
Y924275D01*
G37*
G36*
G01X1326137D02*
X1326322Y924875D01*
X1327352D01*
X1327537Y924275D01*
Y924101D01*
X1326137D01*
Y924275D01*
G37*
G36*
G01X1329847D02*
X1330032Y924875D01*
X1331062D01*
X1331247Y924275D01*
Y924101D01*
X1329847D01*
Y924275D01*
G37*
G36*
G01X1316897Y921073D02*
X1317082Y921673D01*
X1318112D01*
X1318297Y921073D01*
Y920898D01*
X1316897D01*
Y921073D01*
G37*
G36*
G01X1320761Y922501D02*
X1320334Y922961D01*
X1320849Y923853D01*
X1321461Y923713D01*
X1321612Y923626D01*
X1320912Y922414D01*
X1320761Y922501D01*
G37*
G36*
G01X1322432Y924275D02*
X1322617Y924875D01*
X1323647D01*
X1323832Y924275D01*
Y924101D01*
X1322432D01*
Y924275D01*
G37*
G36*
G01X1326137D02*
X1326322Y924875D01*
X1327352D01*
X1327537Y924275D01*
Y924101D01*
X1326137D01*
Y924275D01*
G37*
G36*
G01X1329847D02*
X1330032Y924875D01*
X1331062D01*
X1331247Y924275D01*
Y924101D01*
X1329847D01*
Y924275D01*
G37*
G36*
G01X1315047Y917867D02*
X1315232Y918467D01*
X1316262D01*
X1316447Y917867D01*
Y917693D01*
X1315047D01*
Y917867D01*
G37*
G36*
G01X1318740D02*
X1318925Y918467D01*
X1319955D01*
X1320140Y917867D01*
Y917692D01*
X1318740D01*
Y917867D01*
G37*
G36*
G01X1324354Y921071D02*
X1324539Y921671D01*
X1325569D01*
X1325754Y921071D01*
Y920897D01*
X1324354D01*
Y921071D01*
G37*
G36*
G01X1322606Y919288D02*
X1322179Y919748D01*
X1322694Y920640D01*
X1323306Y920500D01*
X1323457Y920413D01*
X1322757Y919201D01*
X1322606Y919288D01*
G37*
G36*
G01X1328054Y921071D02*
X1328239Y921671D01*
X1329269D01*
X1329454Y921071D01*
Y920897D01*
X1328054D01*
Y921071D01*
G37*
G36*
G01X1315047Y917867D02*
X1315232Y918467D01*
X1316262D01*
X1316447Y917867D01*
Y917693D01*
X1315047D01*
Y917867D01*
G37*
G36*
G01X1318740D02*
X1318925Y918467D01*
X1319955D01*
X1320140Y917867D01*
Y917692D01*
X1318740D01*
Y917867D01*
G37*
G36*
G01X1324354Y921071D02*
X1324539Y921671D01*
X1325569D01*
X1325754Y921071D01*
Y920897D01*
X1324354D01*
Y921071D01*
G37*
G36*
G01X1322606Y919288D02*
X1322179Y919748D01*
X1322694Y920640D01*
X1323306Y920500D01*
X1323457Y920413D01*
X1322757Y919201D01*
X1322606Y919288D01*
G37*
G36*
G01X1328054Y921071D02*
X1328239Y921671D01*
X1329269D01*
X1329454Y921071D01*
Y920897D01*
X1328054D01*
Y921071D01*
G37*
G36*
G01X1316494Y919475D02*
X1316309Y918875D01*
X1315279D01*
X1315094Y919475D01*
Y919649D01*
X1316494D01*
Y919475D01*
G37*
G36*
G01X1321881Y921250D02*
X1322308Y920790D01*
X1321793Y919898D01*
X1321181Y920038D01*
X1321030Y920125D01*
X1321730Y921337D01*
X1321881Y921250D01*
G37*
G36*
G01X1325754Y922679D02*
X1325569Y922079D01*
X1324539D01*
X1324354Y922679D01*
Y922853D01*
X1325754D01*
Y922679D01*
G37*
G36*
G01X1329454D02*
X1329269Y922079D01*
X1328239D01*
X1328054Y922679D01*
Y922853D01*
X1329454D01*
Y922679D01*
G37*
G36*
G01X1320202Y919475D02*
X1320017Y918875D01*
X1318987D01*
X1318802Y919475D01*
Y919650D01*
X1320202D01*
Y919475D01*
G37*
G36*
G01X1316494D02*
X1316309Y918875D01*
X1315279D01*
X1315094Y919475D01*
Y919649D01*
X1316494D01*
Y919475D01*
G37*
G36*
G01X1321881Y921250D02*
X1322308Y920790D01*
X1321793Y919898D01*
X1321181Y920038D01*
X1321030Y920125D01*
X1321730Y921337D01*
X1321881Y921250D01*
G37*
G36*
G01X1325754Y922679D02*
X1325569Y922079D01*
X1324539D01*
X1324354Y922679D01*
Y922853D01*
X1325754D01*
Y922679D01*
G37*
G36*
G01X1329454D02*
X1329269Y922079D01*
X1328239D01*
X1328054Y922679D01*
Y922853D01*
X1329454D01*
Y922679D01*
G37*
G36*
G01X1320202Y919475D02*
X1320017Y918875D01*
X1318987D01*
X1318802Y919475D01*
Y919650D01*
X1320202D01*
Y919475D01*
G37*
G36*
G01X1327537Y919473D02*
X1327352Y918873D01*
X1326322D01*
X1326137Y919473D01*
Y919648D01*
X1327537D01*
Y919473D01*
G37*
G36*
G01X1331237D02*
X1331052Y918873D01*
X1330022D01*
X1329837Y919473D01*
Y919648D01*
X1331237D01*
Y919473D01*
G37*
G36*
G01X1327537D02*
X1327352Y918873D01*
X1326322D01*
X1326137Y919473D01*
Y919648D01*
X1327537D01*
Y919473D01*
G37*
G36*
G01X1331237D02*
X1331052Y918873D01*
X1330022D01*
X1329837Y919473D01*
Y919648D01*
X1331237D01*
Y919473D01*
G37*
G36*
G01X1329837Y917867D02*
X1330022Y918467D01*
X1331052D01*
X1331237Y917867D01*
Y917692D01*
X1329837D01*
Y917867D01*
G37*
G36*
G01D02*
X1330022Y918467D01*
X1331052D01*
X1331237Y917867D01*
Y917692D01*
X1329837D01*
Y917867D01*
G37*
G36*
G01X1318354Y941903D02*
X1318169Y941303D01*
X1317139D01*
X1316954Y941903D01*
Y942078D01*
X1318354D01*
Y941903D01*
G37*
G36*
G01X1322054D02*
X1321869Y941303D01*
X1320839D01*
X1320654Y941903D01*
Y942078D01*
X1322054D01*
Y941903D01*
G37*
G36*
G01X1325754D02*
X1325569Y941303D01*
X1324539D01*
X1324354Y941903D01*
Y942078D01*
X1325754D01*
Y941903D01*
G37*
G36*
G01X1329454D02*
X1329269Y941303D01*
X1328239D01*
X1328054Y941903D01*
Y942078D01*
X1329454D01*
Y941903D01*
G37*
G36*
G01X1318354D02*
X1318169Y941303D01*
X1317139D01*
X1316954Y941903D01*
Y942078D01*
X1318354D01*
Y941903D01*
G37*
G36*
G01X1322054D02*
X1321869Y941303D01*
X1320839D01*
X1320654Y941903D01*
Y942078D01*
X1322054D01*
Y941903D01*
G37*
G36*
G01X1325754D02*
X1325569Y941303D01*
X1324539D01*
X1324354Y941903D01*
Y942078D01*
X1325754D01*
Y941903D01*
G37*
G36*
G01X1329454D02*
X1329269Y941303D01*
X1328239D01*
X1328054Y941903D01*
Y942078D01*
X1329454D01*
Y941903D01*
G37*
G36*
G01X1316505Y938699D02*
X1316320Y938099D01*
X1315290D01*
X1315105Y938699D01*
Y938874D01*
X1316505D01*
Y938699D01*
G37*
G36*
G01X1320195Y938701D02*
X1320010Y938101D01*
X1318980D01*
X1318795Y938701D01*
Y938875D01*
X1320195D01*
Y938701D01*
G37*
G36*
G01X1323847D02*
X1323662Y938101D01*
X1322632D01*
X1322447Y938701D01*
Y938875D01*
X1323847D01*
Y938701D01*
G37*
G36*
G01X1327537Y938699D02*
X1327352Y938099D01*
X1326322D01*
X1326137Y938699D01*
Y938874D01*
X1327537D01*
Y938699D01*
G37*
G36*
G01X1331237D02*
X1331052Y938099D01*
X1330022D01*
X1329837Y938699D01*
Y938874D01*
X1331237D01*
Y938699D01*
G37*
G36*
G01X1316505D02*
X1316320Y938099D01*
X1315290D01*
X1315105Y938699D01*
Y938874D01*
X1316505D01*
Y938699D01*
G37*
G36*
G01X1320195Y938701D02*
X1320010Y938101D01*
X1318980D01*
X1318795Y938701D01*
Y938875D01*
X1320195D01*
Y938701D01*
G37*
G36*
G01X1323847D02*
X1323662Y938101D01*
X1322632D01*
X1322447Y938701D01*
Y938875D01*
X1323847D01*
Y938701D01*
G37*
G36*
G01X1327537Y938699D02*
X1327352Y938099D01*
X1326322D01*
X1326137Y938699D01*
Y938874D01*
X1327537D01*
Y938699D01*
G37*
G36*
G01X1331237D02*
X1331052Y938099D01*
X1330022D01*
X1329837Y938699D01*
Y938874D01*
X1331237D01*
Y938699D01*
G37*
G36*
G01X1316871Y946705D02*
X1317056Y947305D01*
X1318086D01*
X1318271Y946705D01*
Y946531D01*
X1316871D01*
Y946705D01*
G37*
G36*
G01X1328054D02*
X1328239Y947305D01*
X1329269D01*
X1329454Y946705D01*
Y946531D01*
X1328054D01*
Y946705D01*
G37*
G36*
G01X1324354D02*
X1324539Y947305D01*
X1325569D01*
X1325754Y946705D01*
Y946531D01*
X1324354D01*
Y946705D01*
G37*
G36*
G01X1320642D02*
X1320827Y947305D01*
X1321857D01*
X1322042Y946705D01*
Y946531D01*
X1320642D01*
Y946705D01*
G37*
G36*
G01X1316871D02*
X1317056Y947305D01*
X1318086D01*
X1318271Y946705D01*
Y946531D01*
X1316871D01*
Y946705D01*
G37*
G36*
G01X1328054D02*
X1328239Y947305D01*
X1329269D01*
X1329454Y946705D01*
Y946531D01*
X1328054D01*
Y946705D01*
G37*
G36*
G01X1324354D02*
X1324539Y947305D01*
X1325569D01*
X1325754Y946705D01*
Y946531D01*
X1324354D01*
Y946705D01*
G37*
G36*
G01X1320642D02*
X1320827Y947305D01*
X1321857D01*
X1322042Y946705D01*
Y946531D01*
X1320642D01*
Y946705D01*
G37*
G36*
G01X1318321Y948313D02*
X1318136Y947713D01*
X1317106D01*
X1316921Y948313D01*
Y948488D01*
X1318321D01*
Y948313D01*
G37*
G36*
G01X1322021D02*
X1321836Y947713D01*
X1320806D01*
X1320621Y948313D01*
Y948488D01*
X1322021D01*
Y948313D01*
G37*
G36*
G01X1325754D02*
X1325569Y947713D01*
X1324539D01*
X1324354Y948313D01*
Y948487D01*
X1325754D01*
Y948313D01*
G37*
G36*
G01X1329454D02*
X1329269Y947713D01*
X1328239D01*
X1328054Y948313D01*
Y948487D01*
X1329454D01*
Y948313D01*
G37*
G36*
G01X1318321D02*
X1318136Y947713D01*
X1317106D01*
X1316921Y948313D01*
Y948488D01*
X1318321D01*
Y948313D01*
G37*
G36*
G01X1322021D02*
X1321836Y947713D01*
X1320806D01*
X1320621Y948313D01*
Y948488D01*
X1322021D01*
Y948313D01*
G37*
G36*
G01X1325754D02*
X1325569Y947713D01*
X1324539D01*
X1324354Y948313D01*
Y948487D01*
X1325754D01*
Y948313D01*
G37*
G36*
G01X1329454D02*
X1329269Y947713D01*
X1328239D01*
X1328054Y948313D01*
Y948487D01*
X1329454D01*
Y948313D01*
G37*
G36*
G01X1316500Y945107D02*
X1316315Y944507D01*
X1315285D01*
X1315100Y945107D01*
Y945282D01*
X1316500D01*
Y945107D01*
G37*
G36*
G01X1320209Y945109D02*
X1320024Y944509D01*
X1318994D01*
X1318809Y945109D01*
Y945283D01*
X1320209D01*
Y945109D01*
G37*
G36*
G01X1323829Y945107D02*
X1323644Y944507D01*
X1322614D01*
X1322429Y945107D01*
Y945282D01*
X1323829D01*
Y945107D01*
G37*
G36*
G01X1327537D02*
X1327352Y944507D01*
X1326322D01*
X1326137Y945107D01*
Y945282D01*
X1327537D01*
Y945107D01*
G37*
G36*
G01X1331247D02*
X1331062Y944507D01*
X1330032D01*
X1329847Y945107D01*
Y945282D01*
X1331247D01*
Y945107D01*
G37*
G36*
G01X1316500D02*
X1316315Y944507D01*
X1315285D01*
X1315100Y945107D01*
Y945282D01*
X1316500D01*
Y945107D01*
G37*
G36*
G01X1320209Y945109D02*
X1320024Y944509D01*
X1318994D01*
X1318809Y945109D01*
Y945283D01*
X1320209D01*
Y945109D01*
G37*
G36*
G01X1323829Y945107D02*
X1323644Y944507D01*
X1322614D01*
X1322429Y945107D01*
Y945282D01*
X1323829D01*
Y945107D01*
G37*
G36*
G01X1327537D02*
X1327352Y944507D01*
X1326322D01*
X1326137Y945107D01*
Y945282D01*
X1327537D01*
Y945107D01*
G37*
G36*
G01X1331247D02*
X1331062Y944507D01*
X1330032D01*
X1329847Y945107D01*
Y945282D01*
X1331247D01*
Y945107D01*
G37*
G36*
G01X1315037Y943501D02*
X1315222Y944101D01*
X1316252D01*
X1316437Y943501D01*
Y943326D01*
X1315037D01*
Y943501D01*
G37*
G36*
G01X1318737D02*
X1318922Y944101D01*
X1319952D01*
X1320137Y943501D01*
Y943326D01*
X1318737D01*
Y943501D01*
G37*
G36*
G01X1322437D02*
X1322622Y944101D01*
X1323652D01*
X1323837Y943501D01*
Y943326D01*
X1322437D01*
Y943501D01*
G37*
G36*
G01X1326137D02*
X1326322Y944101D01*
X1327352D01*
X1327537Y943501D01*
Y943326D01*
X1326137D01*
Y943501D01*
G37*
G36*
G01X1329847D02*
X1330032Y944101D01*
X1331062D01*
X1331247Y943501D01*
Y943326D01*
X1329847D01*
Y943501D01*
G37*
G36*
G01X1315037D02*
X1315222Y944101D01*
X1316252D01*
X1316437Y943501D01*
Y943326D01*
X1315037D01*
Y943501D01*
G37*
G36*
G01X1318737D02*
X1318922Y944101D01*
X1319952D01*
X1320137Y943501D01*
Y943326D01*
X1318737D01*
Y943501D01*
G37*
G36*
G01X1322437D02*
X1322622Y944101D01*
X1323652D01*
X1323837Y943501D01*
Y943326D01*
X1322437D01*
Y943501D01*
G37*
G36*
G01X1326137D02*
X1326322Y944101D01*
X1327352D01*
X1327537Y943501D01*
Y943326D01*
X1326137D01*
Y943501D01*
G37*
G36*
G01X1329847D02*
X1330032Y944101D01*
X1331062D01*
X1331247Y943501D01*
Y943326D01*
X1329847D01*
Y943501D01*
G37*
G36*
G01X1316888Y940297D02*
X1317073Y940897D01*
X1318103D01*
X1318288Y940297D01*
Y940122D01*
X1316888D01*
Y940297D01*
G37*
G36*
G01X1328054D02*
X1328239Y940897D01*
X1329269D01*
X1329454Y940297D01*
Y940122D01*
X1328054D01*
Y940297D01*
G37*
G36*
G01X1324354D02*
X1324539Y940897D01*
X1325569D01*
X1325754Y940297D01*
Y940122D01*
X1324354D01*
Y940297D01*
G37*
G36*
G01X1320621Y940295D02*
X1320806Y940895D01*
X1321836D01*
X1322021Y940295D01*
Y940121D01*
X1320621D01*
Y940295D01*
G37*
G36*
G01X1316888Y940297D02*
X1317073Y940897D01*
X1318103D01*
X1318288Y940297D01*
Y940122D01*
X1316888D01*
Y940297D01*
G37*
G36*
G01X1328054D02*
X1328239Y940897D01*
X1329269D01*
X1329454Y940297D01*
Y940122D01*
X1328054D01*
Y940297D01*
G37*
G36*
G01X1324354D02*
X1324539Y940897D01*
X1325569D01*
X1325754Y940297D01*
Y940122D01*
X1324354D01*
Y940297D01*
G37*
G36*
G01X1320621Y940295D02*
X1320806Y940895D01*
X1321836D01*
X1322021Y940295D01*
Y940121D01*
X1320621D01*
Y940295D01*
G37*
G36*
G01X1318344Y935497D02*
X1318159Y934897D01*
X1317129D01*
X1316944Y935497D01*
Y935671D01*
X1318344D01*
Y935497D01*
G37*
G36*
G01X1329454Y935495D02*
X1329269Y934895D01*
X1328239D01*
X1328054Y935495D01*
Y935669D01*
X1329454D01*
Y935495D01*
G37*
G36*
G01X1325754D02*
X1325569Y934895D01*
X1324539D01*
X1324354Y935495D01*
Y935669D01*
X1325754D01*
Y935495D01*
G37*
G36*
G01X1322041D02*
X1321856Y934895D01*
X1320826D01*
X1320641Y935495D01*
Y935670D01*
X1322041D01*
Y935495D01*
G37*
G36*
G01X1318344Y935497D02*
X1318159Y934897D01*
X1317129D01*
X1316944Y935497D01*
Y935671D01*
X1318344D01*
Y935497D01*
G37*
G36*
G01X1329454Y935495D02*
X1329269Y934895D01*
X1328239D01*
X1328054Y935495D01*
Y935669D01*
X1329454D01*
Y935495D01*
G37*
G36*
G01X1325754D02*
X1325569Y934895D01*
X1324539D01*
X1324354Y935495D01*
Y935669D01*
X1325754D01*
Y935495D01*
G37*
G36*
G01X1322041D02*
X1321856Y934895D01*
X1320826D01*
X1320641Y935495D01*
Y935670D01*
X1322041D01*
Y935495D01*
G37*
G36*
G01X1316897Y933887D02*
X1317082Y934487D01*
X1318112D01*
X1318297Y933887D01*
Y933713D01*
X1316897D01*
Y933887D01*
G37*
G36*
G01X1328054Y933889D02*
X1328239Y934489D01*
X1329269D01*
X1329454Y933889D01*
Y933714D01*
X1328054D01*
Y933889D01*
G37*
G36*
G01X1324321Y933887D02*
X1324506Y934487D01*
X1325536D01*
X1325721Y933887D01*
Y933713D01*
X1324321D01*
Y933887D01*
G37*
G36*
G01X1320597Y933889D02*
X1320782Y934489D01*
X1321812D01*
X1321997Y933889D01*
Y933714D01*
X1320597D01*
Y933889D01*
G37*
G36*
G01X1316897Y933887D02*
X1317082Y934487D01*
X1318112D01*
X1318297Y933887D01*
Y933713D01*
X1316897D01*
Y933887D01*
G37*
G36*
G01X1328054Y933889D02*
X1328239Y934489D01*
X1329269D01*
X1329454Y933889D01*
Y933714D01*
X1328054D01*
Y933889D01*
G37*
G36*
G01X1324321Y933887D02*
X1324506Y934487D01*
X1325536D01*
X1325721Y933887D01*
Y933713D01*
X1324321D01*
Y933887D01*
G37*
G36*
G01X1320597Y933889D02*
X1320782Y934489D01*
X1321812D01*
X1321997Y933889D01*
Y933714D01*
X1320597D01*
Y933889D01*
G37*
G36*
G01X1315071Y937091D02*
X1315256Y937691D01*
X1316286D01*
X1316471Y937091D01*
Y936917D01*
X1315071D01*
Y937091D01*
G37*
G36*
G01X1322447D02*
X1322632Y937691D01*
X1323662D01*
X1323847Y937091D01*
Y936917D01*
X1322447D01*
Y937091D01*
G37*
G36*
G01X1318794Y937093D02*
X1318979Y937693D01*
X1320009D01*
X1320194Y937093D01*
Y936918D01*
X1318794D01*
Y937093D01*
G37*
G36*
G01X1329837D02*
X1330022Y937693D01*
X1331052D01*
X1331237Y937093D01*
Y936918D01*
X1329837D01*
Y937093D01*
G37*
G36*
G01X1326137D02*
X1326322Y937693D01*
X1327352D01*
X1327537Y937093D01*
Y936918D01*
X1326137D01*
Y937093D01*
G37*
G36*
G01X1315071Y937091D02*
X1315256Y937691D01*
X1316286D01*
X1316471Y937091D01*
Y936917D01*
X1315071D01*
Y937091D01*
G37*
G36*
G01X1322447D02*
X1322632Y937691D01*
X1323662D01*
X1323847Y937091D01*
Y936917D01*
X1322447D01*
Y937091D01*
G37*
G36*
G01X1318794Y937093D02*
X1318979Y937693D01*
X1320009D01*
X1320194Y937093D01*
Y936918D01*
X1318794D01*
Y937093D01*
G37*
G36*
G01X1329837D02*
X1330022Y937693D01*
X1331052D01*
X1331237Y937093D01*
Y936918D01*
X1329837D01*
Y937093D01*
G37*
G36*
G01X1326137D02*
X1326322Y937693D01*
X1327352D01*
X1327537Y937093D01*
Y936918D01*
X1326137D01*
Y937093D01*
G37*
G36*
G01X1315070Y962725D02*
X1315255Y963325D01*
X1316285D01*
X1316470Y962725D01*
Y962551D01*
X1315070D01*
Y962725D01*
G37*
G36*
G01X1318770D02*
X1318955Y963325D01*
X1319985D01*
X1320170Y962725D01*
Y962551D01*
X1318770D01*
Y962725D01*
G37*
G36*
G01X1322437Y962727D02*
X1322622Y963327D01*
X1323652D01*
X1323837Y962727D01*
Y962552D01*
X1322437D01*
Y962727D01*
G37*
G36*
G01X1326137D02*
X1326322Y963327D01*
X1327352D01*
X1327537Y962727D01*
Y962552D01*
X1326137D01*
Y962727D01*
G37*
G36*
G01X1329847D02*
X1330032Y963327D01*
X1331062D01*
X1331247Y962727D01*
Y962552D01*
X1329847D01*
Y962727D01*
G37*
G36*
G01X1315070Y962725D02*
X1315255Y963325D01*
X1316285D01*
X1316470Y962725D01*
Y962551D01*
X1315070D01*
Y962725D01*
G37*
G36*
G01X1318770D02*
X1318955Y963325D01*
X1319985D01*
X1320170Y962725D01*
Y962551D01*
X1318770D01*
Y962725D01*
G37*
G36*
G01X1322437Y962727D02*
X1322622Y963327D01*
X1323652D01*
X1323837Y962727D01*
Y962552D01*
X1322437D01*
Y962727D01*
G37*
G36*
G01X1326137D02*
X1326322Y963327D01*
X1327352D01*
X1327537Y962727D01*
Y962552D01*
X1326137D01*
Y962727D01*
G37*
G36*
G01X1329847D02*
X1330032Y963327D01*
X1331062D01*
X1331247Y962727D01*
Y962552D01*
X1329847D01*
Y962727D01*
G37*
G36*
G01X1316887Y959523D02*
X1317072Y960123D01*
X1318102D01*
X1318287Y959523D01*
Y959348D01*
X1316887D01*
Y959523D01*
G37*
G36*
G01X1320597D02*
X1320782Y960123D01*
X1321812D01*
X1321997Y959523D01*
Y959348D01*
X1320597D01*
Y959523D01*
G37*
G36*
G01X1324310Y959521D02*
X1324495Y960121D01*
X1325525D01*
X1325710Y959521D01*
Y959347D01*
X1324310D01*
Y959521D01*
G37*
G36*
G01X1328007D02*
X1328192Y960121D01*
X1329222D01*
X1329407Y959521D01*
Y959347D01*
X1328007D01*
Y959521D01*
G37*
G36*
G01X1316887Y959523D02*
X1317072Y960123D01*
X1318102D01*
X1318287Y959523D01*
Y959348D01*
X1316887D01*
Y959523D01*
G37*
G36*
G01X1320597D02*
X1320782Y960123D01*
X1321812D01*
X1321997Y959523D01*
Y959348D01*
X1320597D01*
Y959523D01*
G37*
G36*
G01X1324310Y959521D02*
X1324495Y960121D01*
X1325525D01*
X1325710Y959521D01*
Y959347D01*
X1324310D01*
Y959521D01*
G37*
G36*
G01X1328007D02*
X1328192Y960121D01*
X1329222D01*
X1329407Y959521D01*
Y959347D01*
X1328007D01*
Y959521D01*
G37*
G36*
G01X1318320Y961131D02*
X1318135Y960531D01*
X1317105D01*
X1316920Y961131D01*
Y961305D01*
X1318320D01*
Y961131D01*
G37*
G36*
G01X1322044Y961129D02*
X1321859Y960529D01*
X1320829D01*
X1320644Y961129D01*
Y961304D01*
X1322044D01*
Y961129D01*
G37*
G36*
G01X1325754D02*
X1325569Y960529D01*
X1324539D01*
X1324354Y961129D01*
Y961304D01*
X1325754D01*
Y961129D01*
G37*
G36*
G01X1329454D02*
X1329269Y960529D01*
X1328239D01*
X1328054Y961129D01*
Y961304D01*
X1329454D01*
Y961129D01*
G37*
G36*
G01X1318320Y961131D02*
X1318135Y960531D01*
X1317105D01*
X1316920Y961131D01*
Y961305D01*
X1318320D01*
Y961131D01*
G37*
G36*
G01X1322044Y961129D02*
X1321859Y960529D01*
X1320829D01*
X1320644Y961129D01*
Y961304D01*
X1322044D01*
Y961129D01*
G37*
G36*
G01X1325754D02*
X1325569Y960529D01*
X1324539D01*
X1324354Y961129D01*
Y961304D01*
X1325754D01*
Y961129D01*
G37*
G36*
G01X1329454D02*
X1329269Y960529D01*
X1328239D01*
X1328054Y961129D01*
Y961304D01*
X1329454D01*
Y961129D01*
G37*
G36*
G01X1316504Y957925D02*
X1316319Y957325D01*
X1315289D01*
X1315104Y957925D01*
Y958100D01*
X1316504D01*
Y957925D01*
G37*
G36*
G01X1320204D02*
X1320019Y957325D01*
X1318989D01*
X1318804Y957925D01*
Y958100D01*
X1320204D01*
Y957925D01*
G37*
G36*
G01X1323847Y957927D02*
X1323662Y957327D01*
X1322632D01*
X1322447Y957927D01*
Y958101D01*
X1323847D01*
Y957927D01*
G37*
G36*
G01X1327584D02*
X1327399Y957327D01*
X1326369D01*
X1326184Y957927D01*
Y958101D01*
X1327584D01*
Y957927D01*
G37*
G36*
G01X1331284D02*
X1331099Y957327D01*
X1330069D01*
X1329884Y957927D01*
Y958101D01*
X1331284D01*
Y957927D01*
G37*
G36*
G01X1316504Y957925D02*
X1316319Y957325D01*
X1315289D01*
X1315104Y957925D01*
Y958100D01*
X1316504D01*
Y957925D01*
G37*
G36*
G01X1320204D02*
X1320019Y957325D01*
X1318989D01*
X1318804Y957925D01*
Y958100D01*
X1320204D01*
Y957925D01*
G37*
G36*
G01X1323847Y957927D02*
X1323662Y957327D01*
X1322632D01*
X1322447Y957927D01*
Y958101D01*
X1323847D01*
Y957927D01*
G37*
G36*
G01X1327584D02*
X1327399Y957327D01*
X1326369D01*
X1326184Y957927D01*
Y958101D01*
X1327584D01*
Y957927D01*
G37*
G36*
G01X1331284D02*
X1331099Y957327D01*
X1330069D01*
X1329884Y957927D01*
Y958101D01*
X1331284D01*
Y957927D01*
G37*
G36*
G01X1315047Y949909D02*
X1315232Y950509D01*
X1316262D01*
X1316447Y949909D01*
Y949735D01*
X1315047D01*
Y949909D01*
G37*
G36*
G01X1322447D02*
X1322632Y950509D01*
X1323662D01*
X1323847Y949909D01*
Y949734D01*
X1322447D01*
Y949909D01*
G37*
G36*
G01X1326137D02*
X1326322Y950509D01*
X1327352D01*
X1327537Y949909D01*
Y949735D01*
X1326137D01*
Y949909D01*
G37*
G36*
G01X1318771D02*
X1318956Y950509D01*
X1319986D01*
X1320171Y949909D01*
Y949734D01*
X1318771D01*
Y949909D01*
G37*
G36*
G01X1329837D02*
X1330022Y950509D01*
X1331052D01*
X1331237Y949909D01*
Y949735D01*
X1329837D01*
Y949909D01*
G37*
G36*
G01X1315047D02*
X1315232Y950509D01*
X1316262D01*
X1316447Y949909D01*
Y949735D01*
X1315047D01*
Y949909D01*
G37*
G36*
G01X1322447D02*
X1322632Y950509D01*
X1323662D01*
X1323847Y949909D01*
Y949734D01*
X1322447D01*
Y949909D01*
G37*
G36*
G01X1326137D02*
X1326322Y950509D01*
X1327352D01*
X1327537Y949909D01*
Y949735D01*
X1326137D01*
Y949909D01*
G37*
G36*
G01X1318771D02*
X1318956Y950509D01*
X1319986D01*
X1320171Y949909D01*
Y949734D01*
X1318771D01*
Y949909D01*
G37*
G36*
G01X1329837D02*
X1330022Y950509D01*
X1331052D01*
X1331237Y949909D01*
Y949735D01*
X1329837D01*
Y949909D01*
G37*
G36*
G01X1318297Y954721D02*
X1318112Y954121D01*
X1317082D01*
X1316897Y954721D01*
Y954896D01*
X1318297D01*
Y954721D01*
G37*
G36*
G01X1329419Y954723D02*
X1329234Y954123D01*
X1328204D01*
X1328019Y954723D01*
Y954897D01*
X1329419D01*
Y954723D01*
G37*
G36*
G01X1325719D02*
X1325534Y954123D01*
X1324504D01*
X1324319Y954723D01*
Y954897D01*
X1325719D01*
Y954723D01*
G37*
G36*
G01X1322021Y954721D02*
X1321836Y954121D01*
X1320806D01*
X1320621Y954721D01*
Y954895D01*
X1322021D01*
Y954721D01*
G37*
G36*
G01X1318297D02*
X1318112Y954121D01*
X1317082D01*
X1316897Y954721D01*
Y954896D01*
X1318297D01*
Y954721D01*
G37*
G36*
G01X1329419Y954723D02*
X1329234Y954123D01*
X1328204D01*
X1328019Y954723D01*
Y954897D01*
X1329419D01*
Y954723D01*
G37*
G36*
G01X1325719D02*
X1325534Y954123D01*
X1324504D01*
X1324319Y954723D01*
Y954897D01*
X1325719D01*
Y954723D01*
G37*
G36*
G01X1322021Y954721D02*
X1321836Y954121D01*
X1320806D01*
X1320621Y954721D01*
Y954895D01*
X1322021D01*
Y954721D01*
G37*
G36*
G01X1316897Y953113D02*
X1317082Y953713D01*
X1318112D01*
X1318297Y953113D01*
Y952938D01*
X1316897D01*
Y953113D01*
G37*
G36*
G01X1328054D02*
X1328239Y953713D01*
X1329269D01*
X1329454Y953113D01*
Y952939D01*
X1328054D01*
Y953113D01*
G37*
G36*
G01X1324354D02*
X1324539Y953713D01*
X1325569D01*
X1325754Y953113D01*
Y952939D01*
X1324354D01*
Y953113D01*
G37*
G36*
G01X1320621D02*
X1320806Y953713D01*
X1321836D01*
X1322021Y953113D01*
Y952939D01*
X1320621D01*
Y953113D01*
G37*
G36*
G01X1316897D02*
X1317082Y953713D01*
X1318112D01*
X1318297Y953113D01*
Y952938D01*
X1316897D01*
Y953113D01*
G37*
G36*
G01X1328054D02*
X1328239Y953713D01*
X1329269D01*
X1329454Y953113D01*
Y952939D01*
X1328054D01*
Y953113D01*
G37*
G36*
G01X1324354D02*
X1324539Y953713D01*
X1325569D01*
X1325754Y953113D01*
Y952939D01*
X1324354D01*
Y953113D01*
G37*
G36*
G01X1320621D02*
X1320806Y953713D01*
X1321836D01*
X1322021Y953113D01*
Y952939D01*
X1320621D01*
Y953113D01*
G37*
G36*
G01X1315071Y956317D02*
X1315256Y956917D01*
X1316286D01*
X1316471Y956317D01*
Y956143D01*
X1315071D01*
Y956317D01*
G37*
G36*
G01X1329837Y956319D02*
X1330022Y956919D01*
X1331052D01*
X1331237Y956319D01*
Y956144D01*
X1329837D01*
Y956319D01*
G37*
G36*
G01X1326137D02*
X1326322Y956919D01*
X1327352D01*
X1327537Y956319D01*
Y956144D01*
X1326137D01*
Y956319D01*
G37*
G36*
G01X1322447Y956317D02*
X1322632Y956917D01*
X1323662D01*
X1323847Y956317D01*
Y956143D01*
X1322447D01*
Y956317D01*
G37*
G36*
G01X1318804Y956319D02*
X1318989Y956919D01*
X1320019D01*
X1320204Y956319D01*
Y956144D01*
X1318804D01*
Y956319D01*
G37*
G36*
G01X1315071Y956317D02*
X1315256Y956917D01*
X1316286D01*
X1316471Y956317D01*
Y956143D01*
X1315071D01*
Y956317D01*
G37*
G36*
G01X1329837Y956319D02*
X1330022Y956919D01*
X1331052D01*
X1331237Y956319D01*
Y956144D01*
X1329837D01*
Y956319D01*
G37*
G36*
G01X1326137D02*
X1326322Y956919D01*
X1327352D01*
X1327537Y956319D01*
Y956144D01*
X1326137D01*
Y956319D01*
G37*
G36*
G01X1322447Y956317D02*
X1322632Y956917D01*
X1323662D01*
X1323847Y956317D01*
Y956143D01*
X1322447D01*
Y956317D01*
G37*
G36*
G01X1318804Y956319D02*
X1318989Y956919D01*
X1320019D01*
X1320204Y956319D01*
Y956144D01*
X1318804D01*
Y956319D01*
G37*
G36*
G01X1316437Y951517D02*
X1316252Y950917D01*
X1315222D01*
X1315037Y951517D01*
Y951691D01*
X1316437D01*
Y951517D01*
G37*
G36*
G01X1331237D02*
X1331052Y950917D01*
X1330022D01*
X1329837Y951517D01*
Y951691D01*
X1331237D01*
Y951517D01*
G37*
G36*
G01X1327537D02*
X1327352Y950917D01*
X1326322D01*
X1326137Y951517D01*
Y951691D01*
X1327537D01*
Y951517D01*
G37*
G36*
G01X1323838D02*
X1323653Y950917D01*
X1322623D01*
X1322438Y951517D01*
Y951691D01*
X1323838D01*
Y951517D01*
G37*
G36*
G01X1320204D02*
X1320019Y950917D01*
X1318989D01*
X1318804Y951517D01*
Y951691D01*
X1320204D01*
Y951517D01*
G37*
G36*
G01X1316437D02*
X1316252Y950917D01*
X1315222D01*
X1315037Y951517D01*
Y951691D01*
X1316437D01*
Y951517D01*
G37*
G36*
G01X1331237D02*
X1331052Y950917D01*
X1330022D01*
X1329837Y951517D01*
Y951691D01*
X1331237D01*
Y951517D01*
G37*
G36*
G01X1327537D02*
X1327352Y950917D01*
X1326322D01*
X1326137Y951517D01*
Y951691D01*
X1327537D01*
Y951517D01*
G37*
G36*
G01X1323838D02*
X1323653Y950917D01*
X1322623D01*
X1322438Y951517D01*
Y951691D01*
X1323838D01*
Y951517D01*
G37*
G36*
G01X1320204D02*
X1320019Y950917D01*
X1318989D01*
X1318804Y951517D01*
Y951691D01*
X1320204D01*
Y951517D01*
G37*
G36*
G01X1316437Y964333D02*
X1316252Y963733D01*
X1315222D01*
X1315037Y964333D01*
Y964508D01*
X1316437D01*
Y964333D01*
G37*
G36*
G01X1320137D02*
X1319952Y963733D01*
X1318922D01*
X1318737Y964333D01*
Y964508D01*
X1320137D01*
Y964333D01*
G37*
G36*
G01X1323837D02*
X1323652Y963733D01*
X1322622D01*
X1322437Y964333D01*
Y964508D01*
X1323837D01*
Y964333D01*
G37*
G36*
G01X1327537D02*
X1327352Y963733D01*
X1326322D01*
X1326137Y964333D01*
Y964508D01*
X1327537D01*
Y964333D01*
G37*
G36*
G01X1331247D02*
X1331062Y963733D01*
X1330032D01*
X1329847Y964333D01*
Y964508D01*
X1331247D01*
Y964333D01*
G37*
G36*
G01X1316437D02*
X1316252Y963733D01*
X1315222D01*
X1315037Y964333D01*
Y964508D01*
X1316437D01*
Y964333D01*
G37*
G36*
G01X1320137D02*
X1319952Y963733D01*
X1318922D01*
X1318737Y964333D01*
Y964508D01*
X1320137D01*
Y964333D01*
G37*
G36*
G01X1323837D02*
X1323652Y963733D01*
X1322622D01*
X1322437Y964333D01*
Y964508D01*
X1323837D01*
Y964333D01*
G37*
G36*
G01X1327537D02*
X1327352Y963733D01*
X1326322D01*
X1326137Y964333D01*
Y964508D01*
X1327537D01*
Y964333D01*
G37*
G36*
G01X1331247D02*
X1331062Y963733D01*
X1330032D01*
X1329847Y964333D01*
Y964508D01*
X1331247D01*
Y964333D01*
G37*
G36*
G01X1317761Y977714D02*
X1317149Y977574D01*
X1316634Y978466D01*
X1317061Y978926D01*
X1317212Y979013D01*
X1317912Y977801D01*
X1317761Y977714D01*
G37*
G36*
G01X1320171Y977151D02*
X1319986Y976551D01*
X1318956D01*
X1318771Y977151D01*
Y977326D01*
X1320171D01*
Y977151D01*
G37*
G36*
G01X1323847D02*
X1323662Y976551D01*
X1322632D01*
X1322447Y977151D01*
Y977326D01*
X1323847D01*
Y977151D01*
G37*
G36*
G01X1327547D02*
X1327362Y976551D01*
X1326332D01*
X1326147Y977151D01*
Y977325D01*
X1327547D01*
Y977151D01*
G37*
G36*
G01X1331247D02*
X1331062Y976551D01*
X1330032D01*
X1329847Y977151D01*
Y977326D01*
X1331247D01*
Y977151D01*
G37*
G36*
G01X1317761Y977714D02*
X1317149Y977574D01*
X1316634Y978466D01*
X1317061Y978926D01*
X1317212Y979013D01*
X1317912Y977801D01*
X1317761Y977714D01*
G37*
G36*
G01X1320171Y977151D02*
X1319986Y976551D01*
X1318956D01*
X1318771Y977151D01*
Y977326D01*
X1320171D01*
Y977151D01*
G37*
G36*
G01X1323847D02*
X1323662Y976551D01*
X1322632D01*
X1322447Y977151D01*
Y977326D01*
X1323847D01*
Y977151D01*
G37*
G36*
G01X1327547D02*
X1327362Y976551D01*
X1326332D01*
X1326147Y977151D01*
Y977325D01*
X1327547D01*
Y977151D01*
G37*
G36*
G01X1331247D02*
X1331062Y976551D01*
X1330032D01*
X1329847Y977151D01*
Y977326D01*
X1331247D01*
Y977151D01*
G37*
G36*
G01X1315071Y975543D02*
X1315256Y976143D01*
X1316286D01*
X1316471Y975543D01*
Y975368D01*
X1315071D01*
Y975543D01*
G37*
G36*
G01X1318771D02*
X1318956Y976143D01*
X1319986D01*
X1320171Y975543D01*
Y975368D01*
X1318771D01*
Y975543D01*
G37*
G36*
G01X1322447D02*
X1322632Y976143D01*
X1323662D01*
X1323847Y975543D01*
Y975368D01*
X1322447D01*
Y975543D01*
G37*
G36*
G01X1326147D02*
X1326332Y976143D01*
X1327362D01*
X1327547Y975543D01*
Y975369D01*
X1326147D01*
Y975543D01*
G37*
G36*
G01X1329894D02*
X1330079Y976143D01*
X1331109D01*
X1331294Y975543D01*
Y975368D01*
X1329894D01*
Y975543D01*
G37*
G36*
G01X1315071D02*
X1315256Y976143D01*
X1316286D01*
X1316471Y975543D01*
Y975368D01*
X1315071D01*
Y975543D01*
G37*
G36*
G01X1318771D02*
X1318956Y976143D01*
X1319986D01*
X1320171Y975543D01*
Y975368D01*
X1318771D01*
Y975543D01*
G37*
G36*
G01X1322447D02*
X1322632Y976143D01*
X1323662D01*
X1323847Y975543D01*
Y975368D01*
X1322447D01*
Y975543D01*
G37*
G36*
G01X1326147D02*
X1326332Y976143D01*
X1327362D01*
X1327547Y975543D01*
Y975369D01*
X1326147D01*
Y975543D01*
G37*
G36*
G01X1329894D02*
X1330079Y976143D01*
X1331109D01*
X1331294Y975543D01*
Y975368D01*
X1329894D01*
Y975543D01*
G37*
G36*
G01X1315037Y981953D02*
X1315222Y982553D01*
X1316252D01*
X1316437Y981953D01*
Y981778D01*
X1315037D01*
Y981953D01*
G37*
G36*
G01X1317506Y981346D02*
X1318118Y981486D01*
X1318633Y980594D01*
X1318206Y980134D01*
X1318055Y980047D01*
X1317355Y981259D01*
X1317506Y981346D01*
G37*
G36*
G01X1315037Y981953D02*
X1315222Y982553D01*
X1316252D01*
X1316437Y981953D01*
Y981778D01*
X1315037D01*
Y981953D01*
G37*
G36*
G01X1317506Y981346D02*
X1318118Y981486D01*
X1318633Y980594D01*
X1318206Y980134D01*
X1318055Y980047D01*
X1317355Y981259D01*
X1317506Y981346D01*
G37*
G36*
G01X1320621Y978747D02*
X1320806Y979347D01*
X1321836D01*
X1322021Y978747D01*
Y978573D01*
X1320621D01*
Y978747D01*
G37*
G36*
G01X1324354Y978749D02*
X1324539Y979349D01*
X1325569D01*
X1325754Y978749D01*
Y978574D01*
X1324354D01*
Y978749D01*
G37*
G36*
G01X1328021Y978747D02*
X1328206Y979347D01*
X1329236D01*
X1329421Y978747D01*
Y978573D01*
X1328021D01*
Y978747D01*
G37*
G36*
G01X1320621D02*
X1320806Y979347D01*
X1321836D01*
X1322021Y978747D01*
Y978573D01*
X1320621D01*
Y978747D01*
G37*
G36*
G01X1324354Y978749D02*
X1324539Y979349D01*
X1325569D01*
X1325754Y978749D01*
Y978574D01*
X1324354D01*
Y978749D01*
G37*
G36*
G01X1328021Y978747D02*
X1328206Y979347D01*
X1329236D01*
X1329421Y978747D01*
Y978573D01*
X1328021D01*
Y978747D01*
G37*
G36*
G01X1318321Y973947D02*
X1318136Y973347D01*
X1317106D01*
X1316921Y973947D01*
Y974122D01*
X1318321D01*
Y973947D01*
G37*
G36*
G01X1322021D02*
X1321836Y973347D01*
X1320806D01*
X1320621Y973947D01*
Y974122D01*
X1322021D01*
Y973947D01*
G37*
G36*
G01X1325754D02*
X1325569Y973347D01*
X1324539D01*
X1324354Y973947D01*
Y974121D01*
X1325754D01*
Y973947D01*
G37*
G36*
G01X1329397D02*
X1329212Y973347D01*
X1328182D01*
X1327997Y973947D01*
Y974122D01*
X1329397D01*
Y973947D01*
G37*
G36*
G01X1318321D02*
X1318136Y973347D01*
X1317106D01*
X1316921Y973947D01*
Y974122D01*
X1318321D01*
Y973947D01*
G37*
G36*
G01X1322021D02*
X1321836Y973347D01*
X1320806D01*
X1320621Y973947D01*
Y974122D01*
X1322021D01*
Y973947D01*
G37*
G36*
G01X1325754D02*
X1325569Y973347D01*
X1324539D01*
X1324354Y973947D01*
Y974121D01*
X1325754D01*
Y973947D01*
G37*
G36*
G01X1329397D02*
X1329212Y973347D01*
X1328182D01*
X1327997Y973947D01*
Y974122D01*
X1329397D01*
Y973947D01*
G37*
G36*
G01X1316954Y965931D02*
X1317139Y966531D01*
X1318169D01*
X1318354Y965931D01*
Y965757D01*
X1316954D01*
Y965931D01*
G37*
G36*
G01X1328054D02*
X1328239Y966531D01*
X1329269D01*
X1329454Y965931D01*
Y965757D01*
X1328054D01*
Y965931D01*
G37*
G36*
G01X1324354D02*
X1324539Y966531D01*
X1325569D01*
X1325754Y965931D01*
Y965757D01*
X1324354D01*
Y965931D01*
G37*
G36*
G01X1320654D02*
X1320839Y966531D01*
X1321869D01*
X1322054Y965931D01*
Y965757D01*
X1320654D01*
Y965931D01*
G37*
G36*
G01X1316954D02*
X1317139Y966531D01*
X1318169D01*
X1318354Y965931D01*
Y965757D01*
X1316954D01*
Y965931D01*
G37*
G36*
G01X1328054D02*
X1328239Y966531D01*
X1329269D01*
X1329454Y965931D01*
Y965757D01*
X1328054D01*
Y965931D01*
G37*
G36*
G01X1324354D02*
X1324539Y966531D01*
X1325569D01*
X1325754Y965931D01*
Y965757D01*
X1324354D01*
Y965931D01*
G37*
G36*
G01X1320654D02*
X1320839Y966531D01*
X1321869D01*
X1322054Y965931D01*
Y965757D01*
X1320654D01*
Y965931D01*
G37*
G36*
G01X1315071Y969135D02*
X1315256Y969735D01*
X1316286D01*
X1316471Y969135D01*
Y968960D01*
X1315071D01*
Y969135D01*
G37*
G36*
G01X1329837D02*
X1330022Y969735D01*
X1331052D01*
X1331237Y969135D01*
Y968961D01*
X1329837D01*
Y969135D01*
G37*
G36*
G01X1326137D02*
X1326322Y969735D01*
X1327352D01*
X1327537Y969135D01*
Y968961D01*
X1326137D01*
Y969135D01*
G37*
G36*
G01X1322447D02*
X1322632Y969735D01*
X1323662D01*
X1323847Y969135D01*
Y968960D01*
X1322447D01*
Y969135D01*
G37*
G36*
G01X1318771D02*
X1318956Y969735D01*
X1319986D01*
X1320171Y969135D01*
Y968960D01*
X1318771D01*
Y969135D01*
G37*
G36*
G01X1315071D02*
X1315256Y969735D01*
X1316286D01*
X1316471Y969135D01*
Y968960D01*
X1315071D01*
Y969135D01*
G37*
G36*
G01X1329837D02*
X1330022Y969735D01*
X1331052D01*
X1331237Y969135D01*
Y968961D01*
X1329837D01*
Y969135D01*
G37*
G36*
G01X1326137D02*
X1326322Y969735D01*
X1327352D01*
X1327537Y969135D01*
Y968961D01*
X1326137D01*
Y969135D01*
G37*
G36*
G01X1322447D02*
X1322632Y969735D01*
X1323662D01*
X1323847Y969135D01*
Y968960D01*
X1322447D01*
Y969135D01*
G37*
G36*
G01X1318771D02*
X1318956Y969735D01*
X1319986D01*
X1320171Y969135D01*
Y968960D01*
X1318771D01*
Y969135D01*
G37*
G36*
G01X1318321Y967539D02*
X1318136Y966939D01*
X1317106D01*
X1316921Y967539D01*
Y967714D01*
X1318321D01*
Y967539D01*
G37*
G36*
G01X1329454D02*
X1329269Y966939D01*
X1328239D01*
X1328054Y967539D01*
Y967713D01*
X1329454D01*
Y967539D01*
G37*
G36*
G01X1325754D02*
X1325569Y966939D01*
X1324539D01*
X1324354Y967539D01*
Y967713D01*
X1325754D01*
Y967539D01*
G37*
G36*
G01X1322021D02*
X1321836Y966939D01*
X1320806D01*
X1320621Y967539D01*
Y967714D01*
X1322021D01*
Y967539D01*
G37*
G36*
G01X1318321D02*
X1318136Y966939D01*
X1317106D01*
X1316921Y967539D01*
Y967714D01*
X1318321D01*
Y967539D01*
G37*
G36*
G01X1329454D02*
X1329269Y966939D01*
X1328239D01*
X1328054Y967539D01*
Y967713D01*
X1329454D01*
Y967539D01*
G37*
G36*
G01X1325754D02*
X1325569Y966939D01*
X1324539D01*
X1324354Y967539D01*
Y967713D01*
X1325754D01*
Y967539D01*
G37*
G36*
G01X1322021D02*
X1321836Y966939D01*
X1320806D01*
X1320621Y967539D01*
Y967714D01*
X1322021D01*
Y967539D01*
G37*
G36*
G01X1317353Y1005289D02*
X1317538Y1005889D01*
X1318568D01*
X1318753Y1005289D01*
Y1005114D01*
X1317353D01*
Y1005289D01*
G37*
G36*
G01X1328477D02*
X1328662Y1005889D01*
X1329692D01*
X1329877Y1005289D01*
Y1005114D01*
X1328477D01*
Y1005289D01*
G37*
G36*
G01X1321053D02*
X1321238Y1005889D01*
X1322268D01*
X1322453Y1005289D01*
Y1005114D01*
X1321053D01*
Y1005289D01*
G37*
G36*
G01X1324777D02*
X1324962Y1005889D01*
X1325992D01*
X1326177Y1005289D01*
Y1005115D01*
X1324777D01*
Y1005289D01*
G37*
G36*
G01X1317353D02*
X1317538Y1005889D01*
X1318568D01*
X1318753Y1005289D01*
Y1005114D01*
X1317353D01*
Y1005289D01*
G37*
G36*
G01X1328477D02*
X1328662Y1005889D01*
X1329692D01*
X1329877Y1005289D01*
Y1005114D01*
X1328477D01*
Y1005289D01*
G37*
G36*
G01X1321053D02*
X1321238Y1005889D01*
X1322268D01*
X1322453Y1005289D01*
Y1005114D01*
X1321053D01*
Y1005289D01*
G37*
G36*
G01X1324777D02*
X1324962Y1005889D01*
X1325992D01*
X1326177Y1005289D01*
Y1005115D01*
X1324777D01*
Y1005289D01*
G37*
G36*
G01X1315503Y1002083D02*
X1315688Y1002683D01*
X1316718D01*
X1316903Y1002083D01*
Y1001909D01*
X1315503D01*
Y1002083D01*
G37*
G36*
G01X1319203D02*
X1319388Y1002683D01*
X1320418D01*
X1320603Y1002083D01*
Y1001909D01*
X1319203D01*
Y1002083D01*
G37*
G36*
G01X1326603D02*
X1326788Y1002683D01*
X1327818D01*
X1328003Y1002083D01*
Y1001909D01*
X1326603D01*
Y1002083D01*
G37*
G36*
G01X1322903D02*
X1323088Y1002683D01*
X1324118D01*
X1324303Y1002083D01*
Y1001909D01*
X1322903D01*
Y1002083D01*
G37*
G36*
G01X1315503D02*
X1315688Y1002683D01*
X1316718D01*
X1316903Y1002083D01*
Y1001909D01*
X1315503D01*
Y1002083D01*
G37*
G36*
G01X1319203D02*
X1319388Y1002683D01*
X1320418D01*
X1320603Y1002083D01*
Y1001909D01*
X1319203D01*
Y1002083D01*
G37*
G36*
G01X1326603D02*
X1326788Y1002683D01*
X1327818D01*
X1328003Y1002083D01*
Y1001909D01*
X1326603D01*
Y1002083D01*
G37*
G36*
G01X1322903D02*
X1323088Y1002683D01*
X1324118D01*
X1324303Y1002083D01*
Y1001909D01*
X1322903D01*
Y1002083D01*
G37*
G36*
G01X1316903Y1003693D02*
X1316718Y1003093D01*
X1315688D01*
X1315503Y1003693D01*
Y1003867D01*
X1316903D01*
Y1003693D01*
G37*
G36*
G01X1324303D02*
X1324118Y1003093D01*
X1323088D01*
X1322903Y1003693D01*
Y1003867D01*
X1324303D01*
Y1003693D01*
G37*
G36*
G01X1320603D02*
X1320418Y1003093D01*
X1319388D01*
X1319203Y1003693D01*
Y1003867D01*
X1320603D01*
Y1003693D01*
G37*
G36*
G01X1327970Y1003691D02*
X1327785Y1003091D01*
X1326755D01*
X1326570Y1003691D01*
Y1003866D01*
X1327970D01*
Y1003691D01*
G37*
G36*
G01X1316903Y1003693D02*
X1316718Y1003093D01*
X1315688D01*
X1315503Y1003693D01*
Y1003867D01*
X1316903D01*
Y1003693D01*
G37*
G36*
G01X1324303D02*
X1324118Y1003093D01*
X1323088D01*
X1322903Y1003693D01*
Y1003867D01*
X1324303D01*
Y1003693D01*
G37*
G36*
G01X1320603D02*
X1320418Y1003093D01*
X1319388D01*
X1319203Y1003693D01*
Y1003867D01*
X1320603D01*
Y1003693D01*
G37*
G36*
G01X1327970Y1003691D02*
X1327785Y1003091D01*
X1326755D01*
X1326570Y1003691D01*
Y1003866D01*
X1327970D01*
Y1003691D01*
G37*
G36*
G01X1318753Y1000489D02*
X1318568Y999889D01*
X1317538D01*
X1317353Y1000489D01*
Y1000663D01*
X1318753D01*
Y1000489D01*
G37*
G36*
G01X1329853D02*
X1329668Y999889D01*
X1328638D01*
X1328453Y1000489D01*
Y1000663D01*
X1329853D01*
Y1000489D01*
G37*
G36*
G01X1322453D02*
X1322268Y999889D01*
X1321238D01*
X1321053Y1000489D01*
Y1000663D01*
X1322453D01*
Y1000489D01*
G37*
G36*
G01X1326153D02*
X1325968Y999889D01*
X1324938D01*
X1324753Y1000489D01*
Y1000663D01*
X1326153D01*
Y1000489D01*
G37*
G36*
G01X1318753D02*
X1318568Y999889D01*
X1317538D01*
X1317353Y1000489D01*
Y1000663D01*
X1318753D01*
Y1000489D01*
G37*
G36*
G01X1329853D02*
X1329668Y999889D01*
X1328638D01*
X1328453Y1000489D01*
Y1000663D01*
X1329853D01*
Y1000489D01*
G37*
G36*
G01X1322453D02*
X1322268Y999889D01*
X1321238D01*
X1321053Y1000489D01*
Y1000663D01*
X1322453D01*
Y1000489D01*
G37*
G36*
G01X1326153D02*
X1325968Y999889D01*
X1324938D01*
X1324753Y1000489D01*
Y1000663D01*
X1326153D01*
Y1000489D01*
G37*
G36*
G01X1317353Y1011697D02*
X1317538Y1012297D01*
X1318568D01*
X1318753Y1011697D01*
Y1011522D01*
X1317353D01*
Y1011697D01*
G37*
G36*
G01X1321053D02*
X1321238Y1012297D01*
X1322268D01*
X1322453Y1011697D01*
Y1011522D01*
X1321053D01*
Y1011697D01*
G37*
G36*
G01X1324753D02*
X1324938Y1012297D01*
X1325968D01*
X1326153Y1011697D01*
Y1011522D01*
X1324753D01*
Y1011697D01*
G37*
G36*
G01X1328453D02*
X1328638Y1012297D01*
X1329668D01*
X1329853Y1011697D01*
Y1011522D01*
X1328453D01*
Y1011697D01*
G37*
G36*
G01X1317353D02*
X1317538Y1012297D01*
X1318568D01*
X1318753Y1011697D01*
Y1011522D01*
X1317353D01*
Y1011697D01*
G37*
G36*
G01X1321053D02*
X1321238Y1012297D01*
X1322268D01*
X1322453Y1011697D01*
Y1011522D01*
X1321053D01*
Y1011697D01*
G37*
G36*
G01X1324753D02*
X1324938Y1012297D01*
X1325968D01*
X1326153Y1011697D01*
Y1011522D01*
X1324753D01*
Y1011697D01*
G37*
G36*
G01X1328453D02*
X1328638Y1012297D01*
X1329668D01*
X1329853Y1011697D01*
Y1011522D01*
X1328453D01*
Y1011697D01*
G37*
G36*
G01X1315503Y1008493D02*
X1315688Y1009093D01*
X1316718D01*
X1316903Y1008493D01*
Y1008318D01*
X1315503D01*
Y1008493D01*
G37*
G36*
G01X1326570D02*
X1326755Y1009093D01*
X1327785D01*
X1327970Y1008493D01*
Y1008319D01*
X1326570D01*
Y1008493D01*
G37*
G36*
G01X1319203D02*
X1319388Y1009093D01*
X1320418D01*
X1320603Y1008493D01*
Y1008318D01*
X1319203D01*
Y1008493D01*
G37*
G36*
G01X1322903D02*
X1323088Y1009093D01*
X1324118D01*
X1324303Y1008493D01*
Y1008318D01*
X1322903D01*
Y1008493D01*
G37*
G36*
G01X1315503D02*
X1315688Y1009093D01*
X1316718D01*
X1316903Y1008493D01*
Y1008318D01*
X1315503D01*
Y1008493D01*
G37*
G36*
G01X1326570D02*
X1326755Y1009093D01*
X1327785D01*
X1327970Y1008493D01*
Y1008319D01*
X1326570D01*
Y1008493D01*
G37*
G36*
G01X1319203D02*
X1319388Y1009093D01*
X1320418D01*
X1320603Y1008493D01*
Y1008318D01*
X1319203D01*
Y1008493D01*
G37*
G36*
G01X1322903D02*
X1323088Y1009093D01*
X1324118D01*
X1324303Y1008493D01*
Y1008318D01*
X1322903D01*
Y1008493D01*
G37*
G36*
G01X1316903Y1010101D02*
X1316718Y1009501D01*
X1315688D01*
X1315503Y1010101D01*
Y1010276D01*
X1316903D01*
Y1010101D01*
G37*
G36*
G01X1328003D02*
X1327818Y1009501D01*
X1326788D01*
X1326603Y1010101D01*
Y1010276D01*
X1328003D01*
Y1010101D01*
G37*
G36*
G01X1320603D02*
X1320418Y1009501D01*
X1319388D01*
X1319203Y1010101D01*
Y1010276D01*
X1320603D01*
Y1010101D01*
G37*
G36*
G01X1324303D02*
X1324118Y1009501D01*
X1323088D01*
X1322903Y1010101D01*
Y1010276D01*
X1324303D01*
Y1010101D01*
G37*
G36*
G01X1316903D02*
X1316718Y1009501D01*
X1315688D01*
X1315503Y1010101D01*
Y1010276D01*
X1316903D01*
Y1010101D01*
G37*
G36*
G01X1328003D02*
X1327818Y1009501D01*
X1326788D01*
X1326603Y1010101D01*
Y1010276D01*
X1328003D01*
Y1010101D01*
G37*
G36*
G01X1320603D02*
X1320418Y1009501D01*
X1319388D01*
X1319203Y1010101D01*
Y1010276D01*
X1320603D01*
Y1010101D01*
G37*
G36*
G01X1324303D02*
X1324118Y1009501D01*
X1323088D01*
X1322903Y1010101D01*
Y1010276D01*
X1324303D01*
Y1010101D01*
G37*
G36*
G01X1318753Y1006897D02*
X1318568Y1006297D01*
X1317538D01*
X1317353Y1006897D01*
Y1007072D01*
X1318753D01*
Y1006897D01*
G37*
G36*
G01X1322453D02*
X1322268Y1006297D01*
X1321238D01*
X1321053Y1006897D01*
Y1007072D01*
X1322453D01*
Y1006897D01*
G37*
G36*
G01X1329877D02*
X1329692Y1006297D01*
X1328662D01*
X1328477Y1006897D01*
Y1007072D01*
X1329877D01*
Y1006897D01*
G37*
G36*
G01X1326177D02*
X1325992Y1006297D01*
X1324962D01*
X1324777Y1006897D01*
Y1007071D01*
X1326177D01*
Y1006897D01*
G37*
G36*
G01X1318753D02*
X1318568Y1006297D01*
X1317538D01*
X1317353Y1006897D01*
Y1007072D01*
X1318753D01*
Y1006897D01*
G37*
G36*
G01X1322453D02*
X1322268Y1006297D01*
X1321238D01*
X1321053Y1006897D01*
Y1007072D01*
X1322453D01*
Y1006897D01*
G37*
G36*
G01X1329877D02*
X1329692Y1006297D01*
X1328662D01*
X1328477Y1006897D01*
Y1007072D01*
X1329877D01*
Y1006897D01*
G37*
G36*
G01X1326177D02*
X1325992Y1006297D01*
X1324962D01*
X1324777Y1006897D01*
Y1007071D01*
X1326177D01*
Y1006897D01*
G37*
G36*
G01X1316903Y1029327D02*
X1316718Y1028727D01*
X1315688D01*
X1315503Y1029327D01*
Y1029502D01*
X1316903D01*
Y1029327D01*
G37*
G36*
G01X1327970Y1029325D02*
X1327785Y1028725D01*
X1326755D01*
X1326570Y1029325D01*
Y1029500D01*
X1327970D01*
Y1029325D01*
G37*
G36*
G01X1324303Y1029327D02*
X1324118Y1028727D01*
X1323088D01*
X1322903Y1029327D01*
Y1029502D01*
X1324303D01*
Y1029327D01*
G37*
G36*
G01X1320603D02*
X1320418Y1028727D01*
X1319388D01*
X1319203Y1029327D01*
Y1029502D01*
X1320603D01*
Y1029327D01*
G37*
G36*
G01X1316903D02*
X1316718Y1028727D01*
X1315688D01*
X1315503Y1029327D01*
Y1029502D01*
X1316903D01*
Y1029327D01*
G37*
G36*
G01X1327970Y1029325D02*
X1327785Y1028725D01*
X1326755D01*
X1326570Y1029325D01*
Y1029500D01*
X1327970D01*
Y1029325D01*
G37*
G36*
G01X1324303Y1029327D02*
X1324118Y1028727D01*
X1323088D01*
X1322903Y1029327D01*
Y1029502D01*
X1324303D01*
Y1029327D01*
G37*
G36*
G01X1320603D02*
X1320418Y1028727D01*
X1319388D01*
X1319203Y1029327D01*
Y1029502D01*
X1320603D01*
Y1029327D01*
G37*
G36*
G01X1318753Y1019715D02*
X1318568Y1019115D01*
X1317538D01*
X1317353Y1019715D01*
Y1019889D01*
X1318753D01*
Y1019715D01*
G37*
G36*
G01X1329853D02*
X1329668Y1019115D01*
X1328638D01*
X1328453Y1019715D01*
Y1019889D01*
X1329853D01*
Y1019715D01*
G37*
G36*
G01X1326153D02*
X1325968Y1019115D01*
X1324938D01*
X1324753Y1019715D01*
Y1019889D01*
X1326153D01*
Y1019715D01*
G37*
G36*
G01X1322453D02*
X1322268Y1019115D01*
X1321238D01*
X1321053Y1019715D01*
Y1019889D01*
X1322453D01*
Y1019715D01*
G37*
G36*
G01X1318753D02*
X1318568Y1019115D01*
X1317538D01*
X1317353Y1019715D01*
Y1019889D01*
X1318753D01*
Y1019715D01*
G37*
G36*
G01X1329853D02*
X1329668Y1019115D01*
X1328638D01*
X1328453Y1019715D01*
Y1019889D01*
X1329853D01*
Y1019715D01*
G37*
G36*
G01X1326153D02*
X1325968Y1019115D01*
X1324938D01*
X1324753Y1019715D01*
Y1019889D01*
X1326153D01*
Y1019715D01*
G37*
G36*
G01X1322453D02*
X1322268Y1019115D01*
X1321238D01*
X1321053Y1019715D01*
Y1019889D01*
X1322453D01*
Y1019715D01*
G37*
G36*
G01X1316903Y1016509D02*
X1316718Y1015909D01*
X1315688D01*
X1315503Y1016509D01*
Y1016684D01*
X1316903D01*
Y1016509D01*
G37*
G36*
G01X1320603D02*
X1320418Y1015909D01*
X1319388D01*
X1319203Y1016509D01*
Y1016684D01*
X1320603D01*
Y1016509D01*
G37*
G36*
G01X1328003D02*
X1327818Y1015909D01*
X1326788D01*
X1326603Y1016509D01*
Y1016684D01*
X1328003D01*
Y1016509D01*
G37*
G36*
G01X1324303D02*
X1324118Y1015909D01*
X1323088D01*
X1322903Y1016509D01*
Y1016684D01*
X1324303D01*
Y1016509D01*
G37*
G36*
G01X1316903D02*
X1316718Y1015909D01*
X1315688D01*
X1315503Y1016509D01*
Y1016684D01*
X1316903D01*
Y1016509D01*
G37*
G36*
G01X1320603D02*
X1320418Y1015909D01*
X1319388D01*
X1319203Y1016509D01*
Y1016684D01*
X1320603D01*
Y1016509D01*
G37*
G36*
G01X1328003D02*
X1327818Y1015909D01*
X1326788D01*
X1326603Y1016509D01*
Y1016684D01*
X1328003D01*
Y1016509D01*
G37*
G36*
G01X1324303D02*
X1324118Y1015909D01*
X1323088D01*
X1322903Y1016509D01*
Y1016684D01*
X1324303D01*
Y1016509D01*
G37*
G36*
G01X1315503Y1021309D02*
X1315688Y1021909D01*
X1316718D01*
X1316903Y1021309D01*
Y1021135D01*
X1315503D01*
Y1021309D01*
G37*
G36*
G01X1319203D02*
X1319388Y1021909D01*
X1320418D01*
X1320603Y1021309D01*
Y1021135D01*
X1319203D01*
Y1021309D01*
G37*
G36*
G01X1322903D02*
X1323088Y1021909D01*
X1324118D01*
X1324303Y1021309D01*
Y1021135D01*
X1322903D01*
Y1021309D01*
G37*
G36*
G01X1326603D02*
X1326788Y1021909D01*
X1327818D01*
X1328003Y1021309D01*
Y1021135D01*
X1326603D01*
Y1021309D01*
G37*
G36*
G01X1315503D02*
X1315688Y1021909D01*
X1316718D01*
X1316903Y1021309D01*
Y1021135D01*
X1315503D01*
Y1021309D01*
G37*
G36*
G01X1319203D02*
X1319388Y1021909D01*
X1320418D01*
X1320603Y1021309D01*
Y1021135D01*
X1319203D01*
Y1021309D01*
G37*
G36*
G01X1322903D02*
X1323088Y1021909D01*
X1324118D01*
X1324303Y1021309D01*
Y1021135D01*
X1322903D01*
Y1021309D01*
G37*
G36*
G01X1326603D02*
X1326788Y1021909D01*
X1327818D01*
X1328003Y1021309D01*
Y1021135D01*
X1326603D01*
Y1021309D01*
G37*
G36*
G01X1317353Y1018105D02*
X1317538Y1018705D01*
X1318568D01*
X1318753Y1018105D01*
Y1017931D01*
X1317353D01*
Y1018105D01*
G37*
G36*
G01X1324753D02*
X1324938Y1018705D01*
X1325968D01*
X1326153Y1018105D01*
Y1017931D01*
X1324753D01*
Y1018105D01*
G37*
G36*
G01X1328453D02*
X1328638Y1018705D01*
X1329668D01*
X1329853Y1018105D01*
Y1017931D01*
X1328453D01*
Y1018105D01*
G37*
G36*
G01X1321053D02*
X1321238Y1018705D01*
X1322268D01*
X1322453Y1018105D01*
Y1017931D01*
X1321053D01*
Y1018105D01*
G37*
G36*
G01X1317353D02*
X1317538Y1018705D01*
X1318568D01*
X1318753Y1018105D01*
Y1017931D01*
X1317353D01*
Y1018105D01*
G37*
G36*
G01X1324753D02*
X1324938Y1018705D01*
X1325968D01*
X1326153Y1018105D01*
Y1017931D01*
X1324753D01*
Y1018105D01*
G37*
G36*
G01X1328453D02*
X1328638Y1018705D01*
X1329668D01*
X1329853Y1018105D01*
Y1017931D01*
X1328453D01*
Y1018105D01*
G37*
G36*
G01X1321053D02*
X1321238Y1018705D01*
X1322268D01*
X1322453Y1018105D01*
Y1017931D01*
X1321053D01*
Y1018105D01*
G37*
G36*
G01X1316903Y1022919D02*
X1316718Y1022319D01*
X1315688D01*
X1315503Y1022919D01*
Y1023093D01*
X1316903D01*
Y1022919D01*
G37*
G36*
G01X1327970Y1022917D02*
X1327785Y1022317D01*
X1326755D01*
X1326570Y1022917D01*
Y1023092D01*
X1327970D01*
Y1022917D01*
G37*
G36*
G01X1320603Y1022919D02*
X1320418Y1022319D01*
X1319388D01*
X1319203Y1022919D01*
Y1023093D01*
X1320603D01*
Y1022919D01*
G37*
G36*
G01X1324303D02*
X1324118Y1022319D01*
X1323088D01*
X1322903Y1022919D01*
Y1023093D01*
X1324303D01*
Y1022919D01*
G37*
G36*
G01X1316903D02*
X1316718Y1022319D01*
X1315688D01*
X1315503Y1022919D01*
Y1023093D01*
X1316903D01*
Y1022919D01*
G37*
G36*
G01X1327970Y1022917D02*
X1327785Y1022317D01*
X1326755D01*
X1326570Y1022917D01*
Y1023092D01*
X1327970D01*
Y1022917D01*
G37*
G36*
G01X1320603Y1022919D02*
X1320418Y1022319D01*
X1319388D01*
X1319203Y1022919D01*
Y1023093D01*
X1320603D01*
Y1022919D01*
G37*
G36*
G01X1324303D02*
X1324118Y1022319D01*
X1323088D01*
X1322903Y1022919D01*
Y1023093D01*
X1324303D01*
Y1022919D01*
G37*
G36*
G01X1315503Y1027719D02*
X1315688Y1028319D01*
X1316718D01*
X1316903Y1027719D01*
Y1027544D01*
X1315503D01*
Y1027719D01*
G37*
G36*
G01X1326570D02*
X1326755Y1028319D01*
X1327785D01*
X1327970Y1027719D01*
Y1027545D01*
X1326570D01*
Y1027719D01*
G37*
G36*
G01X1322903D02*
X1323088Y1028319D01*
X1324118D01*
X1324303Y1027719D01*
Y1027544D01*
X1322903D01*
Y1027719D01*
G37*
G36*
G01X1319203D02*
X1319388Y1028319D01*
X1320418D01*
X1320603Y1027719D01*
Y1027544D01*
X1319203D01*
Y1027719D01*
G37*
G36*
G01X1315503D02*
X1315688Y1028319D01*
X1316718D01*
X1316903Y1027719D01*
Y1027544D01*
X1315503D01*
Y1027719D01*
G37*
G36*
G01X1326570D02*
X1326755Y1028319D01*
X1327785D01*
X1327970Y1027719D01*
Y1027545D01*
X1326570D01*
Y1027719D01*
G37*
G36*
G01X1322903D02*
X1323088Y1028319D01*
X1324118D01*
X1324303Y1027719D01*
Y1027544D01*
X1322903D01*
Y1027719D01*
G37*
G36*
G01X1319203D02*
X1319388Y1028319D01*
X1320418D01*
X1320603Y1027719D01*
Y1027544D01*
X1319203D01*
Y1027719D01*
G37*
G36*
G01X1317353Y1024513D02*
X1317538Y1025113D01*
X1318568D01*
X1318753Y1024513D01*
Y1024339D01*
X1317353D01*
Y1024513D01*
G37*
G36*
G01X1328487Y1024515D02*
X1328672Y1025115D01*
X1329702D01*
X1329887Y1024515D01*
Y1024340D01*
X1328487D01*
Y1024515D01*
G37*
G36*
G01X1324777D02*
X1324962Y1025115D01*
X1325992D01*
X1326177Y1024515D01*
Y1024340D01*
X1324777D01*
Y1024515D01*
G37*
G36*
G01X1321053Y1024513D02*
X1321238Y1025113D01*
X1322268D01*
X1322453Y1024513D01*
Y1024339D01*
X1321053D01*
Y1024513D01*
G37*
G36*
G01X1317353D02*
X1317538Y1025113D01*
X1318568D01*
X1318753Y1024513D01*
Y1024339D01*
X1317353D01*
Y1024513D01*
G37*
G36*
G01X1328487Y1024515D02*
X1328672Y1025115D01*
X1329702D01*
X1329887Y1024515D01*
Y1024340D01*
X1328487D01*
Y1024515D01*
G37*
G36*
G01X1324777D02*
X1324962Y1025115D01*
X1325992D01*
X1326177Y1024515D01*
Y1024340D01*
X1324777D01*
Y1024515D01*
G37*
G36*
G01X1321053Y1024513D02*
X1321238Y1025113D01*
X1322268D01*
X1322453Y1024513D01*
Y1024339D01*
X1321053D01*
Y1024513D01*
G37*
G36*
G01X1318753Y1026123D02*
X1318568Y1025523D01*
X1317538D01*
X1317353Y1026123D01*
Y1026297D01*
X1318753D01*
Y1026123D01*
G37*
G36*
G01X1329887Y1026121D02*
X1329702Y1025521D01*
X1328672D01*
X1328487Y1026121D01*
Y1026296D01*
X1329887D01*
Y1026121D01*
G37*
G36*
G01X1326177D02*
X1325992Y1025521D01*
X1324962D01*
X1324777Y1026121D01*
Y1026296D01*
X1326177D01*
Y1026121D01*
G37*
G36*
G01X1322453Y1026123D02*
X1322268Y1025523D01*
X1321238D01*
X1321053Y1026123D01*
Y1026297D01*
X1322453D01*
Y1026123D01*
G37*
G36*
G01X1318753D02*
X1318568Y1025523D01*
X1317538D01*
X1317353Y1026123D01*
Y1026297D01*
X1318753D01*
Y1026123D01*
G37*
G36*
G01X1329887Y1026121D02*
X1329702Y1025521D01*
X1328672D01*
X1328487Y1026121D01*
Y1026296D01*
X1329887D01*
Y1026121D01*
G37*
G36*
G01X1326177D02*
X1325992Y1025521D01*
X1324962D01*
X1324777Y1026121D01*
Y1026296D01*
X1326177D01*
Y1026121D01*
G37*
G36*
G01X1322453Y1026123D02*
X1322268Y1025523D01*
X1321238D01*
X1321053Y1026123D01*
Y1026297D01*
X1322453D01*
Y1026123D01*
G37*
G36*
G01X1318753Y1032531D02*
X1318568Y1031931D01*
X1317538D01*
X1317353Y1032531D01*
Y1032706D01*
X1318753D01*
Y1032531D01*
G37*
G36*
G01X1322453D02*
X1322268Y1031931D01*
X1321238D01*
X1321053Y1032531D01*
Y1032706D01*
X1322453D01*
Y1032531D01*
G37*
G36*
G01X1326177D02*
X1325992Y1031931D01*
X1324962D01*
X1324777Y1032531D01*
Y1032705D01*
X1326177D01*
Y1032531D01*
G37*
G36*
G01X1329853D02*
X1329668Y1031931D01*
X1328638D01*
X1328453Y1032531D01*
Y1032706D01*
X1329853D01*
Y1032531D01*
G37*
G36*
G01X1318753D02*
X1318568Y1031931D01*
X1317538D01*
X1317353Y1032531D01*
Y1032706D01*
X1318753D01*
Y1032531D01*
G37*
G36*
G01X1322453D02*
X1322268Y1031931D01*
X1321238D01*
X1321053Y1032531D01*
Y1032706D01*
X1322453D01*
Y1032531D01*
G37*
G36*
G01X1326177D02*
X1325992Y1031931D01*
X1324962D01*
X1324777Y1032531D01*
Y1032705D01*
X1326177D01*
Y1032531D01*
G37*
G36*
G01X1329853D02*
X1329668Y1031931D01*
X1328638D01*
X1328453Y1032531D01*
Y1032706D01*
X1329853D01*
Y1032531D01*
G37*
G36*
G01X1315503Y1034127D02*
X1315688Y1034727D01*
X1316718D01*
X1316903Y1034127D01*
Y1033952D01*
X1315503D01*
Y1034127D01*
G37*
G36*
G01X1319203D02*
X1319388Y1034727D01*
X1320418D01*
X1320603Y1034127D01*
Y1033952D01*
X1319203D01*
Y1034127D01*
G37*
G36*
G01X1322903D02*
X1323088Y1034727D01*
X1324118D01*
X1324303Y1034127D01*
Y1033952D01*
X1322903D01*
Y1034127D01*
G37*
G36*
G01X1326603D02*
X1326788Y1034727D01*
X1327818D01*
X1328003Y1034127D01*
Y1033952D01*
X1326603D01*
Y1034127D01*
G37*
G36*
G01X1315503D02*
X1315688Y1034727D01*
X1316718D01*
X1316903Y1034127D01*
Y1033952D01*
X1315503D01*
Y1034127D01*
G37*
G36*
G01X1319203D02*
X1319388Y1034727D01*
X1320418D01*
X1320603Y1034127D01*
Y1033952D01*
X1319203D01*
Y1034127D01*
G37*
G36*
G01X1322903D02*
X1323088Y1034727D01*
X1324118D01*
X1324303Y1034127D01*
Y1033952D01*
X1322903D01*
Y1034127D01*
G37*
G36*
G01X1326603D02*
X1326788Y1034727D01*
X1327818D01*
X1328003Y1034127D01*
Y1033952D01*
X1326603D01*
Y1034127D01*
G37*
G36*
G01X1317353Y1030923D02*
X1317538Y1031523D01*
X1318568D01*
X1318753Y1030923D01*
Y1030748D01*
X1317353D01*
Y1030923D01*
G37*
G36*
G01X1328477D02*
X1328662Y1031523D01*
X1329692D01*
X1329877Y1030923D01*
Y1030748D01*
X1328477D01*
Y1030923D01*
G37*
G36*
G01X1324777D02*
X1324962Y1031523D01*
X1325992D01*
X1326177Y1030923D01*
Y1030749D01*
X1324777D01*
Y1030923D01*
G37*
G36*
G01X1321053D02*
X1321238Y1031523D01*
X1322268D01*
X1322453Y1030923D01*
Y1030748D01*
X1321053D01*
Y1030923D01*
G37*
G36*
G01X1317353D02*
X1317538Y1031523D01*
X1318568D01*
X1318753Y1030923D01*
Y1030748D01*
X1317353D01*
Y1030923D01*
G37*
G36*
G01X1328477D02*
X1328662Y1031523D01*
X1329692D01*
X1329877Y1030923D01*
Y1030748D01*
X1328477D01*
Y1030923D01*
G37*
G36*
G01X1324777D02*
X1324962Y1031523D01*
X1325992D01*
X1326177Y1030923D01*
Y1030749D01*
X1324777D01*
Y1030923D01*
G37*
G36*
G01X1321053D02*
X1321238Y1031523D01*
X1322268D01*
X1322453Y1030923D01*
Y1030748D01*
X1321053D01*
Y1030923D01*
G37*
G36*
G01X1315503Y1040535D02*
X1315688Y1041135D01*
X1316718D01*
X1316903Y1040535D01*
Y1040361D01*
X1315503D01*
Y1040535D01*
G37*
G36*
G01X1326603D02*
X1326788Y1041135D01*
X1327818D01*
X1328003Y1040535D01*
Y1040361D01*
X1326603D01*
Y1040535D01*
G37*
G36*
G01X1319203D02*
X1319388Y1041135D01*
X1320418D01*
X1320603Y1040535D01*
Y1040361D01*
X1319203D01*
Y1040535D01*
G37*
G36*
G01X1322903D02*
X1323088Y1041135D01*
X1324118D01*
X1324303Y1040535D01*
Y1040361D01*
X1322903D01*
Y1040535D01*
G37*
G36*
G01X1315503D02*
X1315688Y1041135D01*
X1316718D01*
X1316903Y1040535D01*
Y1040361D01*
X1315503D01*
Y1040535D01*
G37*
G36*
G01X1326603D02*
X1326788Y1041135D01*
X1327818D01*
X1328003Y1040535D01*
Y1040361D01*
X1326603D01*
Y1040535D01*
G37*
G36*
G01X1319203D02*
X1319388Y1041135D01*
X1320418D01*
X1320603Y1040535D01*
Y1040361D01*
X1319203D01*
Y1040535D01*
G37*
G36*
G01X1322903D02*
X1323088Y1041135D01*
X1324118D01*
X1324303Y1040535D01*
Y1040361D01*
X1322903D01*
Y1040535D01*
G37*
G36*
G01X1317353Y1037331D02*
X1317538Y1037931D01*
X1318568D01*
X1318753Y1037331D01*
Y1037157D01*
X1317353D01*
Y1037331D01*
G37*
G36*
G01X1324740D02*
X1324925Y1037931D01*
X1325955D01*
X1326140Y1037331D01*
Y1037156D01*
X1324740D01*
Y1037331D01*
G37*
G36*
G01X1328454D02*
X1328639Y1037931D01*
X1329669D01*
X1329854Y1037331D01*
Y1037156D01*
X1328454D01*
Y1037331D01*
G37*
G36*
G01X1321053D02*
X1321238Y1037931D01*
X1322268D01*
X1322453Y1037331D01*
Y1037157D01*
X1321053D01*
Y1037331D01*
G37*
G36*
G01X1317353D02*
X1317538Y1037931D01*
X1318568D01*
X1318753Y1037331D01*
Y1037157D01*
X1317353D01*
Y1037331D01*
G37*
G36*
G01X1324740D02*
X1324925Y1037931D01*
X1325955D01*
X1326140Y1037331D01*
Y1037156D01*
X1324740D01*
Y1037331D01*
G37*
G36*
G01X1328454D02*
X1328639Y1037931D01*
X1329669D01*
X1329854Y1037331D01*
Y1037156D01*
X1328454D01*
Y1037331D01*
G37*
G36*
G01X1321053D02*
X1321238Y1037931D01*
X1322268D01*
X1322453Y1037331D01*
Y1037157D01*
X1321053D01*
Y1037331D01*
G37*
G36*
G01X1318753Y1038941D02*
X1318568Y1038341D01*
X1317538D01*
X1317353Y1038941D01*
Y1039115D01*
X1318753D01*
Y1038941D01*
G37*
G36*
G01X1329853D02*
X1329668Y1038341D01*
X1328638D01*
X1328453Y1038941D01*
Y1039115D01*
X1329853D01*
Y1038941D01*
G37*
G36*
G01X1326153D02*
X1325968Y1038341D01*
X1324938D01*
X1324753Y1038941D01*
Y1039115D01*
X1326153D01*
Y1038941D01*
G37*
G36*
G01X1322453D02*
X1322268Y1038341D01*
X1321238D01*
X1321053Y1038941D01*
Y1039115D01*
X1322453D01*
Y1038941D01*
G37*
G36*
G01X1318753D02*
X1318568Y1038341D01*
X1317538D01*
X1317353Y1038941D01*
Y1039115D01*
X1318753D01*
Y1038941D01*
G37*
G36*
G01X1329853D02*
X1329668Y1038341D01*
X1328638D01*
X1328453Y1038941D01*
Y1039115D01*
X1329853D01*
Y1038941D01*
G37*
G36*
G01X1326153D02*
X1325968Y1038341D01*
X1324938D01*
X1324753Y1038941D01*
Y1039115D01*
X1326153D01*
Y1038941D01*
G37*
G36*
G01X1322453D02*
X1322268Y1038341D01*
X1321238D01*
X1321053Y1038941D01*
Y1039115D01*
X1322453D01*
Y1038941D01*
G37*
G36*
G01X1316903Y1035735D02*
X1316718Y1035135D01*
X1315688D01*
X1315503Y1035735D01*
Y1035910D01*
X1316903D01*
Y1035735D01*
G37*
G36*
G01X1324303D02*
X1324118Y1035135D01*
X1323088D01*
X1322903Y1035735D01*
Y1035910D01*
X1324303D01*
Y1035735D01*
G37*
G36*
G01X1328014D02*
X1327829Y1035135D01*
X1326799D01*
X1326614Y1035735D01*
Y1035910D01*
X1328014D01*
Y1035735D01*
G37*
G36*
G01X1320603D02*
X1320418Y1035135D01*
X1319388D01*
X1319203Y1035735D01*
Y1035910D01*
X1320603D01*
Y1035735D01*
G37*
G36*
G01X1316903D02*
X1316718Y1035135D01*
X1315688D01*
X1315503Y1035735D01*
Y1035910D01*
X1316903D01*
Y1035735D01*
G37*
G36*
G01X1324303D02*
X1324118Y1035135D01*
X1323088D01*
X1322903Y1035735D01*
Y1035910D01*
X1324303D01*
Y1035735D01*
G37*
G36*
G01X1328014D02*
X1327829Y1035135D01*
X1326799D01*
X1326614Y1035735D01*
Y1035910D01*
X1328014D01*
Y1035735D01*
G37*
G36*
G01X1320603D02*
X1320418Y1035135D01*
X1319388D01*
X1319203Y1035735D01*
Y1035910D01*
X1320603D01*
Y1035735D01*
G37*
G36*
G01X1318753Y1045349D02*
X1318568Y1044749D01*
X1317538D01*
X1317353Y1045349D01*
Y1045523D01*
X1318753D01*
Y1045349D01*
G37*
G36*
G01X1329853D02*
X1329668Y1044749D01*
X1328638D01*
X1328453Y1045349D01*
Y1045523D01*
X1329853D01*
Y1045349D01*
G37*
G36*
G01X1322453D02*
X1322268Y1044749D01*
X1321238D01*
X1321053Y1045349D01*
Y1045523D01*
X1322453D01*
Y1045349D01*
G37*
G36*
G01X1326153D02*
X1325968Y1044749D01*
X1324938D01*
X1324753Y1045349D01*
Y1045523D01*
X1326153D01*
Y1045349D01*
G37*
G36*
G01X1318753D02*
X1318568Y1044749D01*
X1317538D01*
X1317353Y1045349D01*
Y1045523D01*
X1318753D01*
Y1045349D01*
G37*
G36*
G01X1329853D02*
X1329668Y1044749D01*
X1328638D01*
X1328453Y1045349D01*
Y1045523D01*
X1329853D01*
Y1045349D01*
G37*
G36*
G01X1322453D02*
X1322268Y1044749D01*
X1321238D01*
X1321053Y1045349D01*
Y1045523D01*
X1322453D01*
Y1045349D01*
G37*
G36*
G01X1326153D02*
X1325968Y1044749D01*
X1324938D01*
X1324753Y1045349D01*
Y1045523D01*
X1326153D01*
Y1045349D01*
G37*
G36*
G01X1317353Y1043739D02*
X1317538Y1044339D01*
X1318568D01*
X1318753Y1043739D01*
Y1043565D01*
X1317353D01*
Y1043739D01*
G37*
G36*
G01X1328453D02*
X1328638Y1044339D01*
X1329668D01*
X1329853Y1043739D01*
Y1043565D01*
X1328453D01*
Y1043739D01*
G37*
G36*
G01X1324753D02*
X1324938Y1044339D01*
X1325968D01*
X1326153Y1043739D01*
Y1043565D01*
X1324753D01*
Y1043739D01*
G37*
G36*
G01X1321053D02*
X1321238Y1044339D01*
X1322268D01*
X1322453Y1043739D01*
Y1043565D01*
X1321053D01*
Y1043739D01*
G37*
G36*
G01X1317353D02*
X1317538Y1044339D01*
X1318568D01*
X1318753Y1043739D01*
Y1043565D01*
X1317353D01*
Y1043739D01*
G37*
G36*
G01X1328453D02*
X1328638Y1044339D01*
X1329668D01*
X1329853Y1043739D01*
Y1043565D01*
X1328453D01*
Y1043739D01*
G37*
G36*
G01X1324753D02*
X1324938Y1044339D01*
X1325968D01*
X1326153Y1043739D01*
Y1043565D01*
X1324753D01*
Y1043739D01*
G37*
G36*
G01X1321053D02*
X1321238Y1044339D01*
X1322268D01*
X1322453Y1043739D01*
Y1043565D01*
X1321053D01*
Y1043739D01*
G37*
G36*
G01X1315503Y1046945D02*
X1315688Y1047545D01*
X1316718D01*
X1316903Y1046945D01*
Y1046770D01*
X1315503D01*
Y1046945D01*
G37*
G36*
G01X1326603Y1046943D02*
X1326788Y1047543D01*
X1327818D01*
X1328003Y1046943D01*
Y1046769D01*
X1326603D01*
Y1046943D01*
G37*
G36*
G01X1322903Y1046945D02*
X1323088Y1047545D01*
X1324118D01*
X1324303Y1046945D01*
Y1046770D01*
X1322903D01*
Y1046945D01*
G37*
G36*
G01X1319203D02*
X1319388Y1047545D01*
X1320418D01*
X1320603Y1046945D01*
Y1046770D01*
X1319203D01*
Y1046945D01*
G37*
G36*
G01X1315503D02*
X1315688Y1047545D01*
X1316718D01*
X1316903Y1046945D01*
Y1046770D01*
X1315503D01*
Y1046945D01*
G37*
G36*
G01X1326603Y1046943D02*
X1326788Y1047543D01*
X1327818D01*
X1328003Y1046943D01*
Y1046769D01*
X1326603D01*
Y1046943D01*
G37*
G36*
G01X1322903Y1046945D02*
X1323088Y1047545D01*
X1324118D01*
X1324303Y1046945D01*
Y1046770D01*
X1322903D01*
Y1046945D01*
G37*
G36*
G01X1319203D02*
X1319388Y1047545D01*
X1320418D01*
X1320603Y1046945D01*
Y1046770D01*
X1319203D01*
Y1046945D01*
G37*
G36*
G01X1316903Y1042145D02*
X1316718Y1041545D01*
X1315688D01*
X1315503Y1042145D01*
Y1042319D01*
X1316903D01*
Y1042145D01*
G37*
G36*
G01X1328003D02*
X1327818Y1041545D01*
X1326788D01*
X1326603Y1042145D01*
Y1042319D01*
X1328003D01*
Y1042145D01*
G37*
G36*
G01X1324303D02*
X1324118Y1041545D01*
X1323088D01*
X1322903Y1042145D01*
Y1042319D01*
X1324303D01*
Y1042145D01*
G37*
G36*
G01X1320603D02*
X1320418Y1041545D01*
X1319388D01*
X1319203Y1042145D01*
Y1042319D01*
X1320603D01*
Y1042145D01*
G37*
G36*
G01X1316903D02*
X1316718Y1041545D01*
X1315688D01*
X1315503Y1042145D01*
Y1042319D01*
X1316903D01*
Y1042145D01*
G37*
G36*
G01X1328003D02*
X1327818Y1041545D01*
X1326788D01*
X1326603Y1042145D01*
Y1042319D01*
X1328003D01*
Y1042145D01*
G37*
G36*
G01X1324303D02*
X1324118Y1041545D01*
X1323088D01*
X1322903Y1042145D01*
Y1042319D01*
X1324303D01*
Y1042145D01*
G37*
G36*
G01X1320603D02*
X1320418Y1041545D01*
X1319388D01*
X1319203Y1042145D01*
Y1042319D01*
X1320603D01*
Y1042145D01*
G37*
G36*
G01X1316063Y1062403D02*
X1316675Y1062543D01*
X1317190Y1061651D01*
X1316763Y1061191D01*
X1316612Y1061104D01*
X1315912Y1062316D01*
X1316063Y1062403D01*
G37*
G36*
G01X1322903Y1059761D02*
X1323088Y1060361D01*
X1324118D01*
X1324303Y1059761D01*
Y1059586D01*
X1322903D01*
Y1059761D01*
G37*
G36*
G01X1319203D02*
X1319388Y1060361D01*
X1320418D01*
X1320603Y1059761D01*
Y1059586D01*
X1319203D01*
Y1059761D01*
G37*
G36*
G01X1326603D02*
X1326788Y1060361D01*
X1327818D01*
X1328003Y1059761D01*
Y1059586D01*
X1326603D01*
Y1059761D01*
G37*
G36*
G01X1316063Y1062403D02*
X1316675Y1062543D01*
X1317190Y1061651D01*
X1316763Y1061191D01*
X1316612Y1061104D01*
X1315912Y1062316D01*
X1316063Y1062403D01*
G37*
G36*
G01X1322903Y1059761D02*
X1323088Y1060361D01*
X1324118D01*
X1324303Y1059761D01*
Y1059586D01*
X1322903D01*
Y1059761D01*
G37*
G36*
G01X1319203D02*
X1319388Y1060361D01*
X1320418D01*
X1320603Y1059761D01*
Y1059586D01*
X1319203D01*
Y1059761D01*
G37*
G36*
G01X1326603D02*
X1326788Y1060361D01*
X1327818D01*
X1328003Y1059761D01*
Y1059586D01*
X1326603D01*
Y1059761D01*
G37*
G36*
G01X1317353Y1056557D02*
X1317538Y1057157D01*
X1318568D01*
X1318753Y1056557D01*
Y1056382D01*
X1317353D01*
Y1056557D01*
G37*
G36*
G01X1314221Y1059183D02*
X1314833Y1059323D01*
X1315348Y1058431D01*
X1314921Y1057971D01*
X1314770Y1057884D01*
X1314070Y1059096D01*
X1314221Y1059183D01*
G37*
G36*
G01X1324753Y1056557D02*
X1324938Y1057157D01*
X1325968D01*
X1326153Y1056557D01*
Y1056382D01*
X1324753D01*
Y1056557D01*
G37*
G36*
G01X1321053D02*
X1321238Y1057157D01*
X1322268D01*
X1322453Y1056557D01*
Y1056382D01*
X1321053D01*
Y1056557D01*
G37*
G36*
G01X1328453D02*
X1328638Y1057157D01*
X1329668D01*
X1329853Y1056557D01*
Y1056382D01*
X1328453D01*
Y1056557D01*
G37*
G36*
G01X1317353D02*
X1317538Y1057157D01*
X1318568D01*
X1318753Y1056557D01*
Y1056382D01*
X1317353D01*
Y1056557D01*
G37*
G36*
G01X1314221Y1059183D02*
X1314833Y1059323D01*
X1315348Y1058431D01*
X1314921Y1057971D01*
X1314770Y1057884D01*
X1314070Y1059096D01*
X1314221Y1059183D01*
G37*
G36*
G01X1324753Y1056557D02*
X1324938Y1057157D01*
X1325968D01*
X1326153Y1056557D01*
Y1056382D01*
X1324753D01*
Y1056557D01*
G37*
G36*
G01X1321053D02*
X1321238Y1057157D01*
X1322268D01*
X1322453Y1056557D01*
Y1056382D01*
X1321053D01*
Y1056557D01*
G37*
G36*
G01X1328453D02*
X1328638Y1057157D01*
X1329668D01*
X1329853Y1056557D01*
Y1056382D01*
X1328453D01*
Y1056557D01*
G37*
G36*
G01X1318753Y1058165D02*
X1318568Y1057565D01*
X1317538D01*
X1317353Y1058165D01*
Y1058340D01*
X1318753D01*
Y1058165D01*
G37*
G36*
G01X1316335Y1058743D02*
X1315723Y1058603D01*
X1315208Y1059495D01*
X1315635Y1059955D01*
X1315786Y1060042D01*
X1316486Y1058830D01*
X1316335Y1058743D01*
G37*
G36*
G01X1326153Y1058165D02*
X1325968Y1057565D01*
X1324938D01*
X1324753Y1058165D01*
Y1058340D01*
X1326153D01*
Y1058165D01*
G37*
G36*
G01X1329853D02*
X1329668Y1057565D01*
X1328638D01*
X1328453Y1058165D01*
Y1058340D01*
X1329853D01*
Y1058165D01*
G37*
G36*
G01X1322453D02*
X1322268Y1057565D01*
X1321238D01*
X1321053Y1058165D01*
Y1058340D01*
X1322453D01*
Y1058165D01*
G37*
G36*
G01X1318753D02*
X1318568Y1057565D01*
X1317538D01*
X1317353Y1058165D01*
Y1058340D01*
X1318753D01*
Y1058165D01*
G37*
G36*
G01X1316335Y1058743D02*
X1315723Y1058603D01*
X1315208Y1059495D01*
X1315635Y1059955D01*
X1315786Y1060042D01*
X1316486Y1058830D01*
X1316335Y1058743D01*
G37*
G36*
G01X1326153Y1058165D02*
X1325968Y1057565D01*
X1324938D01*
X1324753Y1058165D01*
Y1058340D01*
X1326153D01*
Y1058165D01*
G37*
G36*
G01X1329853D02*
X1329668Y1057565D01*
X1328638D01*
X1328453Y1058165D01*
Y1058340D01*
X1329853D01*
Y1058165D01*
G37*
G36*
G01X1322453D02*
X1322268Y1057565D01*
X1321238D01*
X1321053Y1058165D01*
Y1058340D01*
X1322453D01*
Y1058165D01*
G37*
G36*
G01X1316903Y1054961D02*
X1316718Y1054361D01*
X1315688D01*
X1315503Y1054961D01*
Y1055136D01*
X1316903D01*
Y1054961D01*
G37*
G36*
G01X1328003D02*
X1327818Y1054361D01*
X1326788D01*
X1326603Y1054961D01*
Y1055136D01*
X1328003D01*
Y1054961D01*
G37*
G36*
G01X1324303D02*
X1324118Y1054361D01*
X1323088D01*
X1322903Y1054961D01*
Y1055136D01*
X1324303D01*
Y1054961D01*
G37*
G36*
G01X1320603D02*
X1320418Y1054361D01*
X1319388D01*
X1319203Y1054961D01*
Y1055136D01*
X1320603D01*
Y1054961D01*
G37*
G36*
G01X1316903D02*
X1316718Y1054361D01*
X1315688D01*
X1315503Y1054961D01*
Y1055136D01*
X1316903D01*
Y1054961D01*
G37*
G36*
G01X1328003D02*
X1327818Y1054361D01*
X1326788D01*
X1326603Y1054961D01*
Y1055136D01*
X1328003D01*
Y1054961D01*
G37*
G36*
G01X1324303D02*
X1324118Y1054361D01*
X1323088D01*
X1322903Y1054961D01*
Y1055136D01*
X1324303D01*
Y1054961D01*
G37*
G36*
G01X1320603D02*
X1320418Y1054361D01*
X1319388D01*
X1319203Y1054961D01*
Y1055136D01*
X1320603D01*
Y1054961D01*
G37*
G36*
G01X1315503Y1053353D02*
X1315688Y1053953D01*
X1316718D01*
X1316903Y1053353D01*
Y1053178D01*
X1315503D01*
Y1053353D01*
G37*
G36*
G01X1326603D02*
X1326788Y1053953D01*
X1327818D01*
X1328003Y1053353D01*
Y1053178D01*
X1326603D01*
Y1053353D01*
G37*
G36*
G01X1322903D02*
X1323088Y1053953D01*
X1324118D01*
X1324303Y1053353D01*
Y1053178D01*
X1322903D01*
Y1053353D01*
G37*
G36*
G01X1319203D02*
X1319388Y1053953D01*
X1320418D01*
X1320603Y1053353D01*
Y1053178D01*
X1319203D01*
Y1053353D01*
G37*
G36*
G01X1315503D02*
X1315688Y1053953D01*
X1316718D01*
X1316903Y1053353D01*
Y1053178D01*
X1315503D01*
Y1053353D01*
G37*
G36*
G01X1326603D02*
X1326788Y1053953D01*
X1327818D01*
X1328003Y1053353D01*
Y1053178D01*
X1326603D01*
Y1053353D01*
G37*
G36*
G01X1322903D02*
X1323088Y1053953D01*
X1324118D01*
X1324303Y1053353D01*
Y1053178D01*
X1322903D01*
Y1053353D01*
G37*
G36*
G01X1319203D02*
X1319388Y1053953D01*
X1320418D01*
X1320603Y1053353D01*
Y1053178D01*
X1319203D01*
Y1053353D01*
G37*
G36*
G01X1317353Y1050149D02*
X1317538Y1050749D01*
X1318568D01*
X1318753Y1050149D01*
Y1049974D01*
X1317353D01*
Y1050149D01*
G37*
G36*
G01X1324753D02*
X1324938Y1050749D01*
X1325968D01*
X1326153Y1050149D01*
Y1049974D01*
X1324753D01*
Y1050149D01*
G37*
G36*
G01X1321053D02*
X1321238Y1050749D01*
X1322268D01*
X1322453Y1050149D01*
Y1049974D01*
X1321053D01*
Y1050149D01*
G37*
G36*
G01X1328453D02*
X1328638Y1050749D01*
X1329668D01*
X1329853Y1050149D01*
Y1049974D01*
X1328453D01*
Y1050149D01*
G37*
G36*
G01X1317353D02*
X1317538Y1050749D01*
X1318568D01*
X1318753Y1050149D01*
Y1049974D01*
X1317353D01*
Y1050149D01*
G37*
G36*
G01X1324753D02*
X1324938Y1050749D01*
X1325968D01*
X1326153Y1050149D01*
Y1049974D01*
X1324753D01*
Y1050149D01*
G37*
G36*
G01X1321053D02*
X1321238Y1050749D01*
X1322268D01*
X1322453Y1050149D01*
Y1049974D01*
X1321053D01*
Y1050149D01*
G37*
G36*
G01X1328453D02*
X1328638Y1050749D01*
X1329668D01*
X1329853Y1050149D01*
Y1049974D01*
X1328453D01*
Y1050149D01*
G37*
G36*
G01X1318753Y1051757D02*
X1318568Y1051157D01*
X1317538D01*
X1317353Y1051757D01*
Y1051931D01*
X1318753D01*
Y1051757D01*
G37*
G36*
G01X1326153D02*
X1325968Y1051157D01*
X1324938D01*
X1324753Y1051757D01*
Y1051931D01*
X1326153D01*
Y1051757D01*
G37*
G36*
G01X1329877D02*
X1329692Y1051157D01*
X1328662D01*
X1328477Y1051757D01*
Y1051931D01*
X1329877D01*
Y1051757D01*
G37*
G36*
G01X1322453D02*
X1322268Y1051157D01*
X1321238D01*
X1321053Y1051757D01*
Y1051931D01*
X1322453D01*
Y1051757D01*
G37*
G36*
G01X1318753D02*
X1318568Y1051157D01*
X1317538D01*
X1317353Y1051757D01*
Y1051931D01*
X1318753D01*
Y1051757D01*
G37*
G36*
G01X1326153D02*
X1325968Y1051157D01*
X1324938D01*
X1324753Y1051757D01*
Y1051931D01*
X1326153D01*
Y1051757D01*
G37*
G36*
G01X1329877D02*
X1329692Y1051157D01*
X1328662D01*
X1328477Y1051757D01*
Y1051931D01*
X1329877D01*
Y1051757D01*
G37*
G36*
G01X1322453D02*
X1322268Y1051157D01*
X1321238D01*
X1321053Y1051757D01*
Y1051931D01*
X1322453D01*
Y1051757D01*
G37*
G36*
G01X1316903Y1048553D02*
X1316718Y1047953D01*
X1315688D01*
X1315503Y1048553D01*
Y1048727D01*
X1316903D01*
Y1048553D01*
G37*
G36*
G01X1320603D02*
X1320418Y1047953D01*
X1319388D01*
X1319203Y1048553D01*
Y1048727D01*
X1320603D01*
Y1048553D01*
G37*
G36*
G01X1324303D02*
X1324118Y1047953D01*
X1323088D01*
X1322903Y1048553D01*
Y1048727D01*
X1324303D01*
Y1048553D01*
G37*
G36*
G01X1328003D02*
X1327818Y1047953D01*
X1326788D01*
X1326603Y1048553D01*
Y1048727D01*
X1328003D01*
Y1048553D01*
G37*
G36*
G01X1316903D02*
X1316718Y1047953D01*
X1315688D01*
X1315503Y1048553D01*
Y1048727D01*
X1316903D01*
Y1048553D01*
G37*
G36*
G01X1320603D02*
X1320418Y1047953D01*
X1319388D01*
X1319203Y1048553D01*
Y1048727D01*
X1320603D01*
Y1048553D01*
G37*
G36*
G01X1324303D02*
X1324118Y1047953D01*
X1323088D01*
X1322903Y1048553D01*
Y1048727D01*
X1324303D01*
Y1048553D01*
G37*
G36*
G01X1328003D02*
X1327818Y1047953D01*
X1326788D01*
X1326603Y1048553D01*
Y1048727D01*
X1328003D01*
Y1048553D01*
G37*
G36*
G01X1328453Y1062965D02*
X1328638Y1063565D01*
X1329668D01*
X1329853Y1062965D01*
Y1062791D01*
X1328453D01*
Y1062965D01*
G37*
G36*
G01X1324753D02*
X1324938Y1063565D01*
X1325968D01*
X1326153Y1062965D01*
Y1062791D01*
X1324753D01*
Y1062965D01*
G37*
G36*
G01X1321053D02*
X1321238Y1063565D01*
X1322268D01*
X1322453Y1062965D01*
Y1062791D01*
X1321053D01*
Y1062965D01*
G37*
G36*
G01X1328453D02*
X1328638Y1063565D01*
X1329668D01*
X1329853Y1062965D01*
Y1062791D01*
X1328453D01*
Y1062965D01*
G37*
G36*
G01X1324753D02*
X1324938Y1063565D01*
X1325968D01*
X1326153Y1062965D01*
Y1062791D01*
X1324753D01*
Y1062965D01*
G37*
G36*
G01X1321053D02*
X1321238Y1063565D01*
X1322268D01*
X1322453Y1062965D01*
Y1062791D01*
X1321053D01*
Y1062965D01*
G37*
G36*
G01X1318193Y1061932D02*
X1317581Y1061792D01*
X1317066Y1062684D01*
X1317493Y1063144D01*
X1317644Y1063231D01*
X1318344Y1062019D01*
X1318193Y1061932D01*
G37*
G36*
G01X1328003Y1061369D02*
X1327818Y1060769D01*
X1326788D01*
X1326603Y1061369D01*
Y1061544D01*
X1328003D01*
Y1061369D01*
G37*
G36*
G01X1324303D02*
X1324118Y1060769D01*
X1323088D01*
X1322903Y1061369D01*
Y1061544D01*
X1324303D01*
Y1061369D01*
G37*
G36*
G01X1320603D02*
X1320418Y1060769D01*
X1319388D01*
X1319203Y1061369D01*
Y1061544D01*
X1320603D01*
Y1061369D01*
G37*
G36*
G01X1318193Y1061932D02*
X1317581Y1061792D01*
X1317066Y1062684D01*
X1317493Y1063144D01*
X1317644Y1063231D01*
X1318344Y1062019D01*
X1318193Y1061932D01*
G37*
G36*
G01X1328003Y1061369D02*
X1327818Y1060769D01*
X1326788D01*
X1326603Y1061369D01*
Y1061544D01*
X1328003D01*
Y1061369D01*
G37*
G36*
G01X1324303D02*
X1324118Y1060769D01*
X1323088D01*
X1322903Y1061369D01*
Y1061544D01*
X1324303D01*
Y1061369D01*
G37*
G36*
G01X1320603D02*
X1320418Y1060769D01*
X1319388D01*
X1319203Y1061369D01*
Y1061544D01*
X1320603D01*
Y1061369D01*
G37*
G36*
G01X1318168Y1074793D02*
X1317556Y1074653D01*
X1317041Y1075545D01*
X1317468Y1076005D01*
X1317619Y1076092D01*
X1318319Y1074880D01*
X1318168Y1074793D01*
G37*
G36*
G01X1329877Y1070983D02*
X1329692Y1070383D01*
X1328662D01*
X1328477Y1070983D01*
Y1071157D01*
X1329877D01*
Y1070983D01*
G37*
G36*
G01X1326130Y1070981D02*
X1325945Y1070381D01*
X1324915D01*
X1324730Y1070981D01*
Y1071156D01*
X1326130D01*
Y1070981D01*
G37*
G36*
G01X1323739Y1071553D02*
X1323127Y1071413D01*
X1322612Y1072305D01*
X1323039Y1072765D01*
X1323190Y1072852D01*
X1323890Y1071640D01*
X1323739Y1071553D01*
G37*
G36*
G01X1320627Y1074187D02*
X1320442Y1073587D01*
X1319412D01*
X1319227Y1074187D01*
Y1074362D01*
X1320627D01*
Y1074187D01*
G37*
G36*
G01X1318168Y1074793D02*
X1317556Y1074653D01*
X1317041Y1075545D01*
X1317468Y1076005D01*
X1317619Y1076092D01*
X1318319Y1074880D01*
X1318168Y1074793D01*
G37*
G36*
G01X1329877Y1070983D02*
X1329692Y1070383D01*
X1328662D01*
X1328477Y1070983D01*
Y1071157D01*
X1329877D01*
Y1070983D01*
G37*
G36*
G01X1326130Y1070981D02*
X1325945Y1070381D01*
X1324915D01*
X1324730Y1070981D01*
Y1071156D01*
X1326130D01*
Y1070981D01*
G37*
G36*
G01X1323739Y1071553D02*
X1323127Y1071413D01*
X1322612Y1072305D01*
X1323039Y1072765D01*
X1323190Y1072852D01*
X1323890Y1071640D01*
X1323739Y1071553D01*
G37*
G36*
G01X1320627Y1074187D02*
X1320442Y1073587D01*
X1319412D01*
X1319227Y1074187D01*
Y1074362D01*
X1320627D01*
Y1074187D01*
G37*
G36*
G01X1318720Y1070981D02*
X1318535Y1070381D01*
X1317505D01*
X1317320Y1070981D01*
Y1071156D01*
X1318720D01*
Y1070981D01*
G37*
G36*
G01X1316339Y1071553D02*
X1315727Y1071413D01*
X1315212Y1072305D01*
X1315639Y1072765D01*
X1315790Y1072852D01*
X1316490Y1071640D01*
X1316339Y1071553D01*
G37*
G36*
G01X1327970Y1067777D02*
X1327785Y1067177D01*
X1326755D01*
X1326570Y1067777D01*
Y1067952D01*
X1327970D01*
Y1067777D01*
G37*
G36*
G01X1324303Y1067779D02*
X1324118Y1067179D01*
X1323088D01*
X1322903Y1067779D01*
Y1067953D01*
X1324303D01*
Y1067779D01*
G37*
G36*
G01X1321885Y1068356D02*
X1321273Y1068216D01*
X1320758Y1069108D01*
X1321185Y1069568D01*
X1321336Y1069655D01*
X1322036Y1068443D01*
X1321885Y1068356D01*
G37*
G36*
G01X1318720Y1070981D02*
X1318535Y1070381D01*
X1317505D01*
X1317320Y1070981D01*
Y1071156D01*
X1318720D01*
Y1070981D01*
G37*
G36*
G01X1316339Y1071553D02*
X1315727Y1071413D01*
X1315212Y1072305D01*
X1315639Y1072765D01*
X1315790Y1072852D01*
X1316490Y1071640D01*
X1316339Y1071553D01*
G37*
G36*
G01X1327970Y1067777D02*
X1327785Y1067177D01*
X1326755D01*
X1326570Y1067777D01*
Y1067952D01*
X1327970D01*
Y1067777D01*
G37*
G36*
G01X1324303Y1067779D02*
X1324118Y1067179D01*
X1323088D01*
X1322903Y1067779D01*
Y1067953D01*
X1324303D01*
Y1067779D01*
G37*
G36*
G01X1321885Y1068356D02*
X1321273Y1068216D01*
X1320758Y1069108D01*
X1321185Y1069568D01*
X1321336Y1069655D01*
X1322036Y1068443D01*
X1321885Y1068356D01*
G37*
G36*
G01X1315470Y1078987D02*
X1315655Y1079587D01*
X1316685D01*
X1316870Y1078987D01*
Y1078813D01*
X1315470D01*
Y1078987D01*
G37*
G36*
G01X1317939Y1078381D02*
X1318551Y1078521D01*
X1319066Y1077629D01*
X1318639Y1077169D01*
X1318488Y1077082D01*
X1317788Y1078294D01*
X1317939Y1078381D01*
G37*
G36*
G01X1321053Y1075783D02*
X1321238Y1076383D01*
X1322268D01*
X1322453Y1075783D01*
Y1075608D01*
X1321053D01*
Y1075783D01*
G37*
G36*
G01X1323496Y1075165D02*
X1324108Y1075305D01*
X1324623Y1074413D01*
X1324196Y1073953D01*
X1324045Y1073866D01*
X1323345Y1075078D01*
X1323496Y1075165D01*
G37*
G36*
G01X1326580Y1072579D02*
X1326765Y1073179D01*
X1327795D01*
X1327980Y1072579D01*
Y1072404D01*
X1326580D01*
Y1072579D01*
G37*
G36*
G01X1315470Y1078987D02*
X1315655Y1079587D01*
X1316685D01*
X1316870Y1078987D01*
Y1078813D01*
X1315470D01*
Y1078987D01*
G37*
G36*
G01X1317939Y1078381D02*
X1318551Y1078521D01*
X1319066Y1077629D01*
X1318639Y1077169D01*
X1318488Y1077082D01*
X1317788Y1078294D01*
X1317939Y1078381D01*
G37*
G36*
G01X1321053Y1075783D02*
X1321238Y1076383D01*
X1322268D01*
X1322453Y1075783D01*
Y1075608D01*
X1321053D01*
Y1075783D01*
G37*
G36*
G01X1323496Y1075165D02*
X1324108Y1075305D01*
X1324623Y1074413D01*
X1324196Y1073953D01*
X1324045Y1073866D01*
X1323345Y1075078D01*
X1323496Y1075165D01*
G37*
G36*
G01X1326580Y1072579D02*
X1326765Y1073179D01*
X1327795D01*
X1327980Y1072579D01*
Y1072404D01*
X1326580D01*
Y1072579D01*
G37*
G36*
G01X1316089Y1075176D02*
X1316701Y1075316D01*
X1317216Y1074424D01*
X1316789Y1073964D01*
X1316638Y1073877D01*
X1315938Y1075089D01*
X1316089Y1075176D01*
G37*
G36*
G01X1328477Y1069373D02*
X1328662Y1069973D01*
X1329692D01*
X1329877Y1069373D01*
Y1069199D01*
X1328477D01*
Y1069373D01*
G37*
G36*
G01X1324777Y1069375D02*
X1324962Y1069975D01*
X1325992D01*
X1326177Y1069375D01*
Y1069200D01*
X1324777D01*
Y1069375D01*
G37*
G36*
G01X1321613Y1072016D02*
X1322225Y1072156D01*
X1322740Y1071264D01*
X1322313Y1070804D01*
X1322162Y1070717D01*
X1321462Y1071929D01*
X1321613Y1072016D01*
G37*
G36*
G01X1319227Y1072579D02*
X1319412Y1073179D01*
X1320442D01*
X1320627Y1072579D01*
Y1072404D01*
X1319227D01*
Y1072579D01*
G37*
G36*
G01X1316089Y1075176D02*
X1316701Y1075316D01*
X1317216Y1074424D01*
X1316789Y1073964D01*
X1316638Y1073877D01*
X1315938Y1075089D01*
X1316089Y1075176D01*
G37*
G36*
G01X1328477Y1069373D02*
X1328662Y1069973D01*
X1329692D01*
X1329877Y1069373D01*
Y1069199D01*
X1328477D01*
Y1069373D01*
G37*
G36*
G01X1324777Y1069375D02*
X1324962Y1069975D01*
X1325992D01*
X1326177Y1069375D01*
Y1069200D01*
X1324777D01*
Y1069375D01*
G37*
G36*
G01X1321613Y1072016D02*
X1322225Y1072156D01*
X1322740Y1071264D01*
X1322313Y1070804D01*
X1322162Y1070717D01*
X1321462Y1071929D01*
X1321613Y1072016D01*
G37*
G36*
G01X1319227Y1072579D02*
X1319412Y1073179D01*
X1320442D01*
X1320627Y1072579D01*
Y1072404D01*
X1319227D01*
Y1072579D01*
G37*
G36*
G01X1316880Y1067777D02*
X1316695Y1067177D01*
X1315665D01*
X1315480Y1067777D01*
Y1067952D01*
X1316880D01*
Y1067777D01*
G37*
G36*
G01X1320035Y1065152D02*
X1319423Y1065012D01*
X1318908Y1065904D01*
X1319335Y1066364D01*
X1319486Y1066451D01*
X1320186Y1065239D01*
X1320035Y1065152D01*
G37*
G36*
G01X1316880Y1067777D02*
X1316695Y1067177D01*
X1315665D01*
X1315480Y1067777D01*
Y1067952D01*
X1316880D01*
Y1067777D01*
G37*
G36*
G01X1320035Y1065152D02*
X1319423Y1065012D01*
X1318908Y1065904D01*
X1319335Y1066364D01*
X1319486Y1066451D01*
X1320186Y1065239D01*
X1320035Y1065152D01*
G37*
G36*
G01X1329853Y1064575D02*
X1329668Y1063975D01*
X1328638D01*
X1328453Y1064575D01*
Y1064749D01*
X1329853D01*
Y1064575D01*
G37*
G36*
G01X1326153D02*
X1325968Y1063975D01*
X1324938D01*
X1324753Y1064575D01*
Y1064749D01*
X1326153D01*
Y1064575D01*
G37*
G36*
G01X1322453D02*
X1322268Y1063975D01*
X1321238D01*
X1321053Y1064575D01*
Y1064749D01*
X1322453D01*
Y1064575D01*
G37*
G36*
G01X1329853D02*
X1329668Y1063975D01*
X1328638D01*
X1328453Y1064575D01*
Y1064749D01*
X1329853D01*
Y1064575D01*
G37*
G36*
G01X1326153D02*
X1325968Y1063975D01*
X1324938D01*
X1324753Y1064575D01*
Y1064749D01*
X1326153D01*
Y1064575D01*
G37*
G36*
G01X1322453D02*
X1322268Y1063975D01*
X1321238D01*
X1321053Y1064575D01*
Y1064749D01*
X1322453D01*
Y1064575D01*
G37*
G36*
G01X1317921Y1065592D02*
X1318533Y1065732D01*
X1319048Y1064840D01*
X1318621Y1064380D01*
X1318470Y1064293D01*
X1317770Y1065505D01*
X1317921Y1065592D01*
G37*
G36*
G01X1315503Y1066169D02*
X1315688Y1066769D01*
X1316718D01*
X1316903Y1066169D01*
Y1065995D01*
X1315503D01*
Y1066169D01*
G37*
G36*
G01X1317921Y1065592D02*
X1318533Y1065732D01*
X1319048Y1064840D01*
X1318621Y1064380D01*
X1318470Y1064293D01*
X1317770Y1065505D01*
X1317921Y1065592D01*
G37*
G36*
G01X1315503Y1066169D02*
X1315688Y1066769D01*
X1316718D01*
X1316903Y1066169D01*
Y1065995D01*
X1315503D01*
Y1066169D01*
G37*
G36*
G01X1317386Y1069374D02*
X1317571Y1069974D01*
X1318601D01*
X1318786Y1069374D01*
Y1069200D01*
X1317386D01*
Y1069374D01*
G37*
G36*
G01X1314239Y1071971D02*
X1314851Y1072111D01*
X1315366Y1071219D01*
X1314939Y1070759D01*
X1314788Y1070672D01*
X1314088Y1071884D01*
X1314239Y1071971D01*
G37*
G36*
G01X1326603Y1066169D02*
X1326788Y1066769D01*
X1327818D01*
X1328003Y1066169D01*
Y1065995D01*
X1326603D01*
Y1066169D01*
G37*
G36*
G01X1322903D02*
X1323088Y1066769D01*
X1324118D01*
X1324303Y1066169D01*
Y1065995D01*
X1322903D01*
Y1066169D01*
G37*
G36*
G01X1319788Y1068767D02*
X1320400Y1068907D01*
X1320915Y1068015D01*
X1320488Y1067555D01*
X1320337Y1067468D01*
X1319637Y1068680D01*
X1319788Y1068767D01*
G37*
G36*
G01X1317386Y1069374D02*
X1317571Y1069974D01*
X1318601D01*
X1318786Y1069374D01*
Y1069200D01*
X1317386D01*
Y1069374D01*
G37*
G36*
G01X1314239Y1071971D02*
X1314851Y1072111D01*
X1315366Y1071219D01*
X1314939Y1070759D01*
X1314788Y1070672D01*
X1314088Y1071884D01*
X1314239Y1071971D01*
G37*
G36*
G01X1326603Y1066169D02*
X1326788Y1066769D01*
X1327818D01*
X1328003Y1066169D01*
Y1065995D01*
X1326603D01*
Y1066169D01*
G37*
G36*
G01X1322903D02*
X1323088Y1066769D01*
X1324118D01*
X1324303Y1066169D01*
Y1065995D01*
X1322903D01*
Y1066169D01*
G37*
G36*
G01X1319788Y1068767D02*
X1320400Y1068907D01*
X1320915Y1068015D01*
X1320488Y1067555D01*
X1320337Y1067468D01*
X1319637Y1068680D01*
X1319788Y1068767D01*
G37*
G36*
G01X1322903Y1078987D02*
X1323088Y1079587D01*
X1324118D01*
X1324303Y1078987D01*
Y1078812D01*
X1322903D01*
Y1078987D01*
G37*
G36*
G01X1325321Y1078409D02*
X1325933Y1078549D01*
X1326448Y1077657D01*
X1326021Y1077197D01*
X1325870Y1077110D01*
X1325170Y1078322D01*
X1325321Y1078409D01*
G37*
G36*
G01X1328453Y1075783D02*
X1328638Y1076383D01*
X1329668D01*
X1329853Y1075783D01*
Y1075608D01*
X1328453D01*
Y1075783D01*
G37*
G36*
G01X1322903Y1078987D02*
X1323088Y1079587D01*
X1324118D01*
X1324303Y1078987D01*
Y1078812D01*
X1322903D01*
Y1078987D01*
G37*
G36*
G01X1325321Y1078409D02*
X1325933Y1078549D01*
X1326448Y1077657D01*
X1326021Y1077197D01*
X1325870Y1077110D01*
X1325170Y1078322D01*
X1325321Y1078409D01*
G37*
G36*
G01X1328453Y1075783D02*
X1328638Y1076383D01*
X1329668D01*
X1329853Y1075783D01*
Y1075608D01*
X1328453D01*
Y1075783D01*
G37*
G36*
G01X1329853Y1077391D02*
X1329668Y1076791D01*
X1328638D01*
X1328453Y1077391D01*
Y1077566D01*
X1329853D01*
Y1077391D01*
G37*
G36*
G01X1327435Y1077969D02*
X1326823Y1077829D01*
X1326308Y1078721D01*
X1326735Y1079181D01*
X1326886Y1079268D01*
X1327586Y1078056D01*
X1327435Y1077969D01*
G37*
G36*
G01X1329853Y1077391D02*
X1329668Y1076791D01*
X1328638D01*
X1328453Y1077391D01*
Y1077566D01*
X1329853D01*
Y1077391D01*
G37*
G36*
G01X1327435Y1077969D02*
X1326823Y1077829D01*
X1326308Y1078721D01*
X1326735Y1079181D01*
X1326886Y1079268D01*
X1327586Y1078056D01*
X1327435Y1077969D01*
G37*
G36*
G01X1328027Y1074187D02*
X1327842Y1073587D01*
X1326812D01*
X1326627Y1074187D01*
Y1074362D01*
X1328027D01*
Y1074187D01*
G37*
G36*
G01X1325568Y1074793D02*
X1324956Y1074653D01*
X1324441Y1075545D01*
X1324868Y1076005D01*
X1325019Y1076092D01*
X1325719Y1074880D01*
X1325568Y1074793D01*
G37*
G36*
G01X1322453Y1077391D02*
X1322268Y1076791D01*
X1321238D01*
X1321053Y1077391D01*
Y1077566D01*
X1322453D01*
Y1077391D01*
G37*
G36*
G01X1320035Y1077969D02*
X1319423Y1077829D01*
X1318908Y1078721D01*
X1319335Y1079181D01*
X1319486Y1079268D01*
X1320186Y1078056D01*
X1320035Y1077969D01*
G37*
G36*
G01X1328027Y1074187D02*
X1327842Y1073587D01*
X1326812D01*
X1326627Y1074187D01*
Y1074362D01*
X1328027D01*
Y1074187D01*
G37*
G36*
G01X1325568Y1074793D02*
X1324956Y1074653D01*
X1324441Y1075545D01*
X1324868Y1076005D01*
X1325019Y1076092D01*
X1325719Y1074880D01*
X1325568Y1074793D01*
G37*
G36*
G01X1322453Y1077391D02*
X1322268Y1076791D01*
X1321238D01*
X1321053Y1077391D01*
Y1077566D01*
X1322453D01*
Y1077391D01*
G37*
G36*
G01X1320035Y1077969D02*
X1319423Y1077829D01*
X1318908Y1078721D01*
X1319335Y1079181D01*
X1319486Y1079268D01*
X1320186Y1078056D01*
X1320035Y1077969D01*
G37*
G36*
G01X1329293Y1093975D02*
X1328681Y1093835D01*
X1328166Y1094727D01*
X1328593Y1095187D01*
X1328744Y1095274D01*
X1329444Y1094062D01*
X1329293Y1093975D01*
G37*
G36*
G01X1331118Y1090815D02*
X1330506Y1090675D01*
X1329991Y1091567D01*
X1330418Y1092027D01*
X1330569Y1092114D01*
X1331269Y1090902D01*
X1331118Y1090815D01*
G37*
G36*
G01X1329293Y1093975D02*
X1328681Y1093835D01*
X1328166Y1094727D01*
X1328593Y1095187D01*
X1328744Y1095274D01*
X1329444Y1094062D01*
X1329293Y1093975D01*
G37*
G36*
G01X1331118Y1090815D02*
X1330506Y1090675D01*
X1329991Y1091567D01*
X1330418Y1092027D01*
X1330569Y1092114D01*
X1331269Y1090902D01*
X1331118Y1090815D01*
G37*
G36*
G01X1316066Y1088032D02*
X1316678Y1088172D01*
X1317193Y1087280D01*
X1316766Y1086820D01*
X1316615Y1086733D01*
X1315915Y1087945D01*
X1316066Y1088032D01*
G37*
G36*
G01X1321623Y1084814D02*
X1322235Y1084954D01*
X1322750Y1084062D01*
X1322323Y1083602D01*
X1322172Y1083515D01*
X1321472Y1084727D01*
X1321623Y1084814D01*
G37*
G36*
G01X1319202Y1085396D02*
X1319387Y1085996D01*
X1320417D01*
X1320602Y1085396D01*
Y1085221D01*
X1319202D01*
Y1085396D01*
G37*
G36*
G01X1316066Y1088032D02*
X1316678Y1088172D01*
X1317193Y1087280D01*
X1316766Y1086820D01*
X1316615Y1086733D01*
X1315915Y1087945D01*
X1316066Y1088032D01*
G37*
G36*
G01X1321623Y1084814D02*
X1322235Y1084954D01*
X1322750Y1084062D01*
X1322323Y1083602D01*
X1322172Y1083515D01*
X1321472Y1084727D01*
X1321623Y1084814D01*
G37*
G36*
G01X1319202Y1085396D02*
X1319387Y1085996D01*
X1320417D01*
X1320602Y1085396D01*
Y1085221D01*
X1319202D01*
Y1085396D01*
G37*
G36*
G01X1324753Y1082191D02*
X1324938Y1082791D01*
X1325968D01*
X1326153Y1082191D01*
Y1082016D01*
X1324753D01*
Y1082191D01*
G37*
G36*
G01X1327171Y1081613D02*
X1327783Y1081753D01*
X1328298Y1080861D01*
X1327871Y1080401D01*
X1327720Y1080314D01*
X1327020Y1081526D01*
X1327171Y1081613D01*
G37*
G36*
G01X1324753Y1082191D02*
X1324938Y1082791D01*
X1325968D01*
X1326153Y1082191D01*
Y1082016D01*
X1324753D01*
Y1082191D01*
G37*
G36*
G01X1327171Y1081613D02*
X1327783Y1081753D01*
X1328298Y1080861D01*
X1327871Y1080401D01*
X1327720Y1080314D01*
X1327020Y1081526D01*
X1327171Y1081613D01*
G37*
G36*
G01X1314212Y1084833D02*
X1314824Y1084973D01*
X1315339Y1084081D01*
X1314912Y1083621D01*
X1314761Y1083534D01*
X1314061Y1084746D01*
X1314212Y1084833D01*
G37*
G36*
G01D02*
X1314824Y1084973D01*
X1315339Y1084081D01*
X1314912Y1083621D01*
X1314761Y1083534D01*
X1314061Y1084746D01*
X1314212Y1084833D01*
G37*
G36*
G01X1317319Y1082191D02*
X1317504Y1082791D01*
X1318534D01*
X1318719Y1082191D01*
Y1082017D01*
X1317319D01*
Y1082191D01*
G37*
G36*
G01X1319788Y1081585D02*
X1320400Y1081725D01*
X1320915Y1080833D01*
X1320488Y1080373D01*
X1320337Y1080286D01*
X1319637Y1081498D01*
X1319788Y1081585D01*
G37*
G36*
G01X1317319Y1082191D02*
X1317504Y1082791D01*
X1318534D01*
X1318719Y1082191D01*
Y1082017D01*
X1317319D01*
Y1082191D01*
G37*
G36*
G01X1319788Y1081585D02*
X1320400Y1081725D01*
X1320915Y1080833D01*
X1320488Y1080373D01*
X1320337Y1080286D01*
X1319637Y1081498D01*
X1319788Y1081585D01*
G37*
G36*
G01X1316342Y1084362D02*
X1315730Y1084222D01*
X1315215Y1085114D01*
X1315642Y1085574D01*
X1315793Y1085661D01*
X1316493Y1084449D01*
X1316342Y1084362D01*
G37*
G36*
G01X1318752Y1083799D02*
X1318567Y1083199D01*
X1317537D01*
X1317352Y1083799D01*
Y1083974D01*
X1318752D01*
Y1083799D01*
G37*
G36*
G01X1316342Y1084362D02*
X1315730Y1084222D01*
X1315215Y1085114D01*
X1315642Y1085574D01*
X1315793Y1085661D01*
X1316493Y1084449D01*
X1316342Y1084362D01*
G37*
G36*
G01X1318752Y1083799D02*
X1318567Y1083199D01*
X1317537D01*
X1317352Y1083799D01*
Y1083974D01*
X1318752D01*
Y1083799D01*
G37*
G36*
G01X1324303Y1080595D02*
X1324118Y1079995D01*
X1323088D01*
X1322903Y1080595D01*
Y1080770D01*
X1324303D01*
Y1080595D01*
G37*
G36*
G01X1321860Y1081213D02*
X1321248Y1081073D01*
X1320733Y1081965D01*
X1321160Y1082425D01*
X1321311Y1082512D01*
X1322011Y1081300D01*
X1321860Y1081213D01*
G37*
G36*
G01X1324303Y1080595D02*
X1324118Y1079995D01*
X1323088D01*
X1322903Y1080595D01*
Y1080770D01*
X1324303D01*
Y1080595D01*
G37*
G36*
G01X1321860Y1081213D02*
X1321248Y1081073D01*
X1320733Y1081965D01*
X1321160Y1082425D01*
X1321311Y1082512D01*
X1322011Y1081300D01*
X1321860Y1081213D01*
G37*
G36*
G01X1316936Y1080595D02*
X1316751Y1079995D01*
X1315721D01*
X1315536Y1080595D01*
Y1080769D01*
X1316936D01*
Y1080595D01*
G37*
G36*
G01D02*
X1316751Y1079995D01*
X1315721D01*
X1315536Y1080595D01*
Y1080769D01*
X1316936D01*
Y1080595D01*
G37*
G36*
G01X1316869Y1093413D02*
X1316684Y1092813D01*
X1315654D01*
X1315469Y1093413D01*
Y1093587D01*
X1316869D01*
Y1093413D01*
G37*
G36*
G01X1320569D02*
X1320384Y1092813D01*
X1319354D01*
X1319169Y1093413D01*
Y1093587D01*
X1320569D01*
Y1093413D01*
G37*
G36*
G01X1316869D02*
X1316684Y1092813D01*
X1315654D01*
X1315469Y1093413D01*
Y1093587D01*
X1316869D01*
Y1093413D01*
G37*
G36*
G01X1320569D02*
X1320384Y1092813D01*
X1319354D01*
X1319169Y1093413D01*
Y1093587D01*
X1320569D01*
Y1093413D01*
G37*
G36*
G01X1331143Y1084362D02*
X1330531Y1084222D01*
X1330016Y1085114D01*
X1330443Y1085574D01*
X1330594Y1085661D01*
X1331294Y1084449D01*
X1331143Y1084362D01*
G37*
G36*
G01X1329285Y1087582D02*
X1328673Y1087442D01*
X1328158Y1088334D01*
X1328585Y1088794D01*
X1328736Y1088881D01*
X1329436Y1087669D01*
X1329285Y1087582D01*
G37*
G36*
G01X1324269Y1093413D02*
X1324084Y1092813D01*
X1323054D01*
X1322869Y1093413D01*
Y1093587D01*
X1324269D01*
Y1093413D01*
G37*
G36*
G01X1327410Y1090827D02*
X1326798Y1090687D01*
X1326283Y1091579D01*
X1326710Y1092039D01*
X1326861Y1092126D01*
X1327561Y1090914D01*
X1327410Y1090827D01*
G37*
G36*
G01X1331143Y1084362D02*
X1330531Y1084222D01*
X1330016Y1085114D01*
X1330443Y1085574D01*
X1330594Y1085661D01*
X1331294Y1084449D01*
X1331143Y1084362D01*
G37*
G36*
G01X1329285Y1087582D02*
X1328673Y1087442D01*
X1328158Y1088334D01*
X1328585Y1088794D01*
X1328736Y1088881D01*
X1329436Y1087669D01*
X1329285Y1087582D01*
G37*
G36*
G01X1324269Y1093413D02*
X1324084Y1092813D01*
X1323054D01*
X1322869Y1093413D01*
Y1093587D01*
X1324269D01*
Y1093413D01*
G37*
G36*
G01X1327410Y1090827D02*
X1326798Y1090687D01*
X1326283Y1091579D01*
X1326710Y1092039D01*
X1326861Y1092126D01*
X1327561Y1090914D01*
X1327410Y1090827D01*
G37*
G36*
G01X1315469Y1091805D02*
X1315654Y1092405D01*
X1316684D01*
X1316869Y1091805D01*
Y1091631D01*
X1315469D01*
Y1091805D01*
G37*
G36*
G01X1321086Y1088600D02*
X1321271Y1089200D01*
X1322301D01*
X1322486Y1088600D01*
Y1088426D01*
X1321086D01*
Y1088600D01*
G37*
G36*
G01X1315469Y1091805D02*
X1315654Y1092405D01*
X1316684D01*
X1316869Y1091805D01*
Y1091631D01*
X1315469D01*
Y1091805D01*
G37*
G36*
G01X1321086Y1088600D02*
X1321271Y1089200D01*
X1322301D01*
X1322486Y1088600D01*
Y1088426D01*
X1321086D01*
Y1088600D01*
G37*
G36*
G01X1329013Y1084833D02*
X1329625Y1084973D01*
X1330140Y1084081D01*
X1329713Y1083621D01*
X1329562Y1083534D01*
X1328862Y1084746D01*
X1329013Y1084833D01*
G37*
G36*
G01X1327171Y1088022D02*
X1327783Y1088162D01*
X1328298Y1087270D01*
X1327871Y1086810D01*
X1327720Y1086723D01*
X1327020Y1087935D01*
X1327171Y1088022D01*
G37*
G36*
G01X1324753Y1088599D02*
X1324938Y1089199D01*
X1325968D01*
X1326153Y1088599D01*
Y1088425D01*
X1324753D01*
Y1088599D01*
G37*
G36*
G01X1329013Y1084833D02*
X1329625Y1084973D01*
X1330140Y1084081D01*
X1329713Y1083621D01*
X1329562Y1083534D01*
X1328862Y1084746D01*
X1329013Y1084833D01*
G37*
G36*
G01X1327171Y1088022D02*
X1327783Y1088162D01*
X1328298Y1087270D01*
X1327871Y1086810D01*
X1327720Y1086723D01*
X1327020Y1087935D01*
X1327171Y1088022D01*
G37*
G36*
G01X1324753Y1088599D02*
X1324938Y1089199D01*
X1325968D01*
X1326153Y1088599D01*
Y1088425D01*
X1324753D01*
Y1088599D01*
G37*
G36*
G01X1317386Y1095009D02*
X1317571Y1095609D01*
X1318601D01*
X1318786Y1095009D01*
Y1094835D01*
X1317386D01*
Y1095009D01*
G37*
G36*
G01X1321086D02*
X1321271Y1095609D01*
X1322301D01*
X1322486Y1095009D01*
Y1094835D01*
X1321086D01*
Y1095009D01*
G37*
G36*
G01X1317386D02*
X1317571Y1095609D01*
X1318601D01*
X1318786Y1095009D01*
Y1094835D01*
X1317386D01*
Y1095009D01*
G37*
G36*
G01X1321086D02*
X1321271Y1095609D01*
X1322301D01*
X1322486Y1095009D01*
Y1094835D01*
X1321086D01*
Y1095009D01*
G37*
G36*
G01X1324786D02*
X1324971Y1095609D01*
X1326001D01*
X1326186Y1095009D01*
Y1094835D01*
X1324786D01*
Y1095009D01*
G37*
G36*
G01X1327188Y1094402D02*
X1327800Y1094542D01*
X1328315Y1093650D01*
X1327888Y1093190D01*
X1327737Y1093103D01*
X1327037Y1094315D01*
X1327188Y1094402D01*
G37*
G36*
G01X1329021Y1091226D02*
X1329633Y1091366D01*
X1330148Y1090474D01*
X1329721Y1090014D01*
X1329570Y1089927D01*
X1328870Y1091139D01*
X1329021Y1091226D01*
G37*
G36*
G01X1324786Y1095009D02*
X1324971Y1095609D01*
X1326001D01*
X1326186Y1095009D01*
Y1094835D01*
X1324786D01*
Y1095009D01*
G37*
G36*
G01X1327188Y1094402D02*
X1327800Y1094542D01*
X1328315Y1093650D01*
X1327888Y1093190D01*
X1327737Y1093103D01*
X1327037Y1094315D01*
X1327188Y1094402D01*
G37*
G36*
G01X1329021Y1091226D02*
X1329633Y1091366D01*
X1330148Y1090474D01*
X1329721Y1090014D01*
X1329570Y1089927D01*
X1328870Y1091139D01*
X1329021Y1091226D01*
G37*
G36*
G01X1318189Y1087572D02*
X1317577Y1087432D01*
X1317062Y1088324D01*
X1317489Y1088784D01*
X1317640Y1088871D01*
X1318340Y1087659D01*
X1318189Y1087572D01*
G37*
G36*
G01X1320569Y1087003D02*
X1320384Y1086403D01*
X1319354D01*
X1319169Y1087003D01*
Y1087178D01*
X1320569D01*
Y1087003D01*
G37*
G36*
G01X1318189Y1087572D02*
X1317577Y1087432D01*
X1317062Y1088324D01*
X1317489Y1088784D01*
X1317640Y1088871D01*
X1318340Y1087659D01*
X1318189Y1087572D01*
G37*
G36*
G01X1320569Y1087003D02*
X1320384Y1086403D01*
X1319354D01*
X1319169Y1087003D01*
Y1087178D01*
X1320569D01*
Y1087003D01*
G37*
G36*
G01X1327443Y1084362D02*
X1326831Y1084222D01*
X1326316Y1085114D01*
X1326743Y1085574D01*
X1326894Y1085661D01*
X1327594Y1084449D01*
X1327443Y1084362D01*
G37*
G36*
G01X1329285Y1081173D02*
X1328673Y1081033D01*
X1328158Y1081925D01*
X1328585Y1082385D01*
X1328736Y1082472D01*
X1329436Y1081260D01*
X1329285Y1081173D01*
G37*
G36*
G01X1324279Y1087003D02*
X1324094Y1086403D01*
X1323064D01*
X1322879Y1087003D01*
Y1087178D01*
X1324279D01*
Y1087003D01*
G37*
G36*
G01X1327443Y1084362D02*
X1326831Y1084222D01*
X1326316Y1085114D01*
X1326743Y1085574D01*
X1326894Y1085661D01*
X1327594Y1084449D01*
X1327443Y1084362D01*
G37*
G36*
G01X1329285Y1081173D02*
X1328673Y1081033D01*
X1328158Y1081925D01*
X1328585Y1082385D01*
X1328736Y1082472D01*
X1329436Y1081260D01*
X1329285Y1081173D01*
G37*
G36*
G01X1324279Y1087003D02*
X1324094Y1086403D01*
X1323064D01*
X1322879Y1087003D01*
Y1087178D01*
X1324279D01*
Y1087003D01*
G37*
G36*
G01X1316071Y1107248D02*
X1316683Y1107388D01*
X1317198Y1106496D01*
X1316771Y1106036D01*
X1316620Y1105949D01*
X1315920Y1107161D01*
X1316071Y1107248D01*
G37*
G36*
G01X1317913Y1104059D02*
X1318525Y1104199D01*
X1319040Y1103307D01*
X1318613Y1102847D01*
X1318462Y1102760D01*
X1317762Y1103972D01*
X1317913Y1104059D01*
G37*
G36*
G01X1321053Y1101416D02*
X1321238Y1102016D01*
X1322268D01*
X1322453Y1101416D01*
Y1101242D01*
X1321053D01*
Y1101416D01*
G37*
G36*
G01X1316071Y1107248D02*
X1316683Y1107388D01*
X1317198Y1106496D01*
X1316771Y1106036D01*
X1316620Y1105949D01*
X1315920Y1107161D01*
X1316071Y1107248D01*
G37*
G36*
G01X1317913Y1104059D02*
X1318525Y1104199D01*
X1319040Y1103307D01*
X1318613Y1102847D01*
X1318462Y1102760D01*
X1317762Y1103972D01*
X1317913Y1104059D01*
G37*
G36*
G01X1321053Y1101416D02*
X1321238Y1102016D01*
X1322268D01*
X1322453Y1101416D01*
Y1101242D01*
X1321053D01*
Y1101416D01*
G37*
G36*
G01X1324753D02*
X1324938Y1102016D01*
X1325968D01*
X1326153Y1101416D01*
Y1101242D01*
X1324753D01*
Y1101416D01*
G37*
G36*
G01D02*
X1324938Y1102016D01*
X1325968D01*
X1326153Y1101416D01*
Y1101242D01*
X1324753D01*
Y1101416D01*
G37*
G36*
G01X1316071Y1100839D02*
X1316683Y1100979D01*
X1317198Y1100087D01*
X1316771Y1099627D01*
X1316620Y1099540D01*
X1315920Y1100752D01*
X1316071Y1100839D01*
G37*
G36*
G01X1314213Y1104059D02*
X1314825Y1104199D01*
X1315340Y1103307D01*
X1314913Y1102847D01*
X1314762Y1102760D01*
X1314062Y1103972D01*
X1314213Y1104059D01*
G37*
G36*
G01X1319203Y1098212D02*
X1319388Y1098812D01*
X1320418D01*
X1320603Y1098212D01*
Y1098038D01*
X1319203D01*
Y1098212D01*
G37*
G36*
G01X1316071Y1100839D02*
X1316683Y1100979D01*
X1317198Y1100087D01*
X1316771Y1099627D01*
X1316620Y1099540D01*
X1315920Y1100752D01*
X1316071Y1100839D01*
G37*
G36*
G01X1314213Y1104059D02*
X1314825Y1104199D01*
X1315340Y1103307D01*
X1314913Y1102847D01*
X1314762Y1102760D01*
X1314062Y1103972D01*
X1314213Y1104059D01*
G37*
G36*
G01X1319203Y1098212D02*
X1319388Y1098812D01*
X1320418D01*
X1320603Y1098212D01*
Y1098038D01*
X1319203D01*
Y1098212D01*
G37*
G36*
G01X1329021Y1097635D02*
X1329633Y1097775D01*
X1330148Y1096883D01*
X1329721Y1096423D01*
X1329570Y1096336D01*
X1328870Y1097548D01*
X1329021Y1097635D01*
G37*
G36*
G01X1326603Y1098212D02*
X1326788Y1098812D01*
X1327818D01*
X1328003Y1098212D01*
Y1098038D01*
X1326603D01*
Y1098212D01*
G37*
G36*
G01X1322903D02*
X1323088Y1098812D01*
X1324118D01*
X1324303Y1098212D01*
Y1098038D01*
X1322903D01*
Y1098212D01*
G37*
G36*
G01X1329021Y1097635D02*
X1329633Y1097775D01*
X1330148Y1096883D01*
X1329721Y1096423D01*
X1329570Y1096336D01*
X1328870Y1097548D01*
X1329021Y1097635D01*
G37*
G36*
G01X1326603Y1098212D02*
X1326788Y1098812D01*
X1327818D01*
X1328003Y1098212D01*
Y1098038D01*
X1326603D01*
Y1098212D01*
G37*
G36*
G01X1322903D02*
X1323088Y1098812D01*
X1324118D01*
X1324303Y1098212D01*
Y1098038D01*
X1322903D01*
Y1098212D01*
G37*
G36*
G01X1318185Y1100399D02*
X1317573Y1100259D01*
X1317058Y1101151D01*
X1317485Y1101611D01*
X1317636Y1101698D01*
X1318336Y1100486D01*
X1318185Y1100399D01*
G37*
G36*
G01X1316343Y1103588D02*
X1315731Y1103448D01*
X1315216Y1104340D01*
X1315643Y1104800D01*
X1315794Y1104887D01*
X1316494Y1103675D01*
X1316343Y1103588D01*
G37*
G36*
G01X1320603Y1099822D02*
X1320418Y1099222D01*
X1319388D01*
X1319203Y1099822D01*
Y1099996D01*
X1320603D01*
Y1099822D01*
G37*
G36*
G01X1318185Y1100399D02*
X1317573Y1100259D01*
X1317058Y1101151D01*
X1317485Y1101611D01*
X1317636Y1101698D01*
X1318336Y1100486D01*
X1318185Y1100399D01*
G37*
G36*
G01X1316343Y1103588D02*
X1315731Y1103448D01*
X1315216Y1104340D01*
X1315643Y1104800D01*
X1315794Y1104887D01*
X1316494Y1103675D01*
X1316343Y1103588D01*
G37*
G36*
G01X1320603Y1099822D02*
X1320418Y1099222D01*
X1319388D01*
X1319203Y1099822D01*
Y1099996D01*
X1320603D01*
Y1099822D01*
G37*
G36*
G01X1331135Y1097195D02*
X1330523Y1097055D01*
X1330008Y1097947D01*
X1330435Y1098407D01*
X1330586Y1098494D01*
X1331286Y1097282D01*
X1331135Y1097195D01*
G37*
G36*
G01D02*
X1330523Y1097055D01*
X1330008Y1097947D01*
X1330435Y1098407D01*
X1330586Y1098494D01*
X1331286Y1097282D01*
X1331135Y1097195D01*
G37*
G36*
G01X1324303Y1099822D02*
X1324118Y1099222D01*
X1323088D01*
X1322903Y1099822D01*
Y1099996D01*
X1324303D01*
Y1099822D01*
G37*
G36*
G01X1328003D02*
X1327818Y1099222D01*
X1326788D01*
X1326603Y1099822D01*
Y1099996D01*
X1328003D01*
Y1099822D01*
G37*
G36*
G01X1324303D02*
X1324118Y1099222D01*
X1323088D01*
X1322903Y1099822D01*
Y1099996D01*
X1324303D01*
Y1099822D01*
G37*
G36*
G01X1328003D02*
X1327818Y1099222D01*
X1326788D01*
X1326603Y1099822D01*
Y1099996D01*
X1328003D01*
Y1099822D01*
G37*
G36*
G01X1318753Y1096617D02*
X1318568Y1096017D01*
X1317538D01*
X1317353Y1096617D01*
Y1096792D01*
X1318753D01*
Y1096617D01*
G37*
G36*
G01X1316335Y1097195D02*
X1315723Y1097055D01*
X1315208Y1097947D01*
X1315635Y1098407D01*
X1315786Y1098494D01*
X1316486Y1097282D01*
X1316335Y1097195D01*
G37*
G36*
G01X1322453Y1096617D02*
X1322268Y1096017D01*
X1321238D01*
X1321053Y1096617D01*
Y1096792D01*
X1322453D01*
Y1096617D01*
G37*
G36*
G01X1318753D02*
X1318568Y1096017D01*
X1317538D01*
X1317353Y1096617D01*
Y1096792D01*
X1318753D01*
Y1096617D01*
G37*
G36*
G01X1316335Y1097195D02*
X1315723Y1097055D01*
X1315208Y1097947D01*
X1315635Y1098407D01*
X1315786Y1098494D01*
X1316486Y1097282D01*
X1316335Y1097195D01*
G37*
G36*
G01X1322453Y1096617D02*
X1322268Y1096017D01*
X1321238D01*
X1321053Y1096617D01*
Y1096792D01*
X1322453D01*
Y1096617D01*
G37*
G36*
G01X1326153D02*
X1325968Y1096017D01*
X1324938D01*
X1324753Y1096617D01*
Y1096792D01*
X1326153D01*
Y1096617D01*
G37*
G36*
G01D02*
X1325968Y1096017D01*
X1324938D01*
X1324753Y1096617D01*
Y1096792D01*
X1326153D01*
Y1096617D01*
G37*
G36*
G01X1347373Y82912D02*
G03I-653J0D01*
G37*
G36*
G01X1331853Y882813D02*
X1331426Y882353D01*
X1331941Y881461D01*
X1332553Y881601D01*
X1332704Y881688D01*
X1332004Y882900D01*
X1331853Y882813D01*
G37*
G36*
G01X1336689D02*
X1337116Y882353D01*
X1336601Y881461D01*
X1335989Y881601D01*
X1335838Y881688D01*
X1336538Y882900D01*
X1336689Y882813D01*
G37*
G36*
G01X1344085Y882803D02*
X1344512Y882343D01*
X1343997Y881451D01*
X1343385Y881591D01*
X1343234Y881678D01*
X1343934Y882890D01*
X1344085Y882803D01*
G37*
G36*
G01X1339253Y882813D02*
X1338826Y882353D01*
X1339341Y881461D01*
X1339953Y881601D01*
X1340104Y881688D01*
X1339404Y882900D01*
X1339253Y882813D01*
G37*
G36*
G01X1331853D02*
X1331426Y882353D01*
X1331941Y881461D01*
X1332553Y881601D01*
X1332704Y881688D01*
X1332004Y882900D01*
X1331853Y882813D01*
G37*
G36*
G01X1336689D02*
X1337116Y882353D01*
X1336601Y881461D01*
X1335989Y881601D01*
X1335838Y881688D01*
X1336538Y882900D01*
X1336689Y882813D01*
G37*
G36*
G01X1344085Y882803D02*
X1344512Y882343D01*
X1343997Y881451D01*
X1343385Y881591D01*
X1343234Y881678D01*
X1343934Y882890D01*
X1344085Y882803D01*
G37*
G36*
G01X1339253Y882813D02*
X1338826Y882353D01*
X1339341Y881461D01*
X1339953Y881601D01*
X1340104Y881688D01*
X1339404Y882900D01*
X1339253Y882813D01*
G37*
G36*
G01X1342957Y884043D02*
X1342530Y884503D01*
X1343045Y885395D01*
X1343657Y885255D01*
X1343808Y885168D01*
X1343108Y883956D01*
X1342957Y884043D01*
G37*
G36*
G01X1335552Y884033D02*
X1335125Y884493D01*
X1335640Y885385D01*
X1336252Y885245D01*
X1336403Y885158D01*
X1335703Y883946D01*
X1335552Y884033D01*
G37*
G36*
G01X1342957Y884043D02*
X1342530Y884503D01*
X1343045Y885395D01*
X1343657Y885255D01*
X1343808Y885168D01*
X1343108Y883956D01*
X1342957Y884043D01*
G37*
G36*
G01X1335552Y884033D02*
X1335125Y884493D01*
X1335640Y885385D01*
X1336252Y885245D01*
X1336403Y885158D01*
X1335703Y883946D01*
X1335552Y884033D01*
G37*
G36*
G01X1332306Y885217D02*
X1332918Y885357D01*
X1333433Y884465D01*
X1333006Y884005D01*
X1332855Y883918D01*
X1332155Y885130D01*
X1332306Y885217D01*
G37*
G36*
G01X1339706D02*
X1340318Y885357D01*
X1340833Y884465D01*
X1340406Y884005D01*
X1340255Y883918D01*
X1339555Y885130D01*
X1339706Y885217D01*
G37*
G36*
G01X1334947Y900249D02*
X1334762Y899649D01*
X1333732D01*
X1333547Y900249D01*
Y900423D01*
X1334947D01*
Y900249D01*
G37*
G36*
G01D02*
X1334762Y899649D01*
X1333732D01*
X1333547Y900249D01*
Y900423D01*
X1334947D01*
Y900249D01*
G37*
G36*
G01X1333547Y898641D02*
X1333732Y899241D01*
X1334762D01*
X1334947Y898641D01*
Y898467D01*
X1333547D01*
Y898641D01*
G37*
G36*
G01X1337385Y900027D02*
X1336958Y900487D01*
X1337473Y901379D01*
X1338085Y901239D01*
X1338236Y901152D01*
X1337536Y899940D01*
X1337385Y900027D01*
G37*
G36*
G01X1333547Y898641D02*
X1333732Y899241D01*
X1334762D01*
X1334947Y898641D01*
Y898467D01*
X1333547D01*
Y898641D01*
G37*
G36*
G01X1337385Y900027D02*
X1336958Y900487D01*
X1337473Y901379D01*
X1338085Y901239D01*
X1338236Y901152D01*
X1337536Y899940D01*
X1337385Y900027D01*
G37*
G36*
G01X1333154Y897043D02*
X1332969Y896443D01*
X1331939D01*
X1331754Y897043D01*
Y897218D01*
X1333154D01*
Y897043D01*
G37*
G36*
G01X1336797Y897045D02*
X1336612Y896445D01*
X1335582D01*
X1335397Y897045D01*
Y897219D01*
X1336797D01*
Y897045D01*
G37*
G36*
G01X1338535Y898827D02*
X1338962Y898367D01*
X1338447Y897475D01*
X1337835Y897615D01*
X1337684Y897702D01*
X1338384Y898914D01*
X1338535Y898827D01*
G37*
G36*
G01X1342337Y900249D02*
X1342152Y899649D01*
X1341122D01*
X1340937Y900249D01*
Y900423D01*
X1342337D01*
Y900249D01*
G37*
G36*
G01X1346037D02*
X1345852Y899649D01*
X1344822D01*
X1344637Y900249D01*
Y900423D01*
X1346037D01*
Y900249D01*
G37*
G36*
G01X1333154Y897043D02*
X1332969Y896443D01*
X1331939D01*
X1331754Y897043D01*
Y897218D01*
X1333154D01*
Y897043D01*
G37*
G36*
G01X1336797Y897045D02*
X1336612Y896445D01*
X1335582D01*
X1335397Y897045D01*
Y897219D01*
X1336797D01*
Y897045D01*
G37*
G36*
G01X1338535Y898827D02*
X1338962Y898367D01*
X1338447Y897475D01*
X1337835Y897615D01*
X1337684Y897702D01*
X1338384Y898914D01*
X1338535Y898827D01*
G37*
G36*
G01X1342337Y900249D02*
X1342152Y899649D01*
X1341122D01*
X1340937Y900249D01*
Y900423D01*
X1342337D01*
Y900249D01*
G37*
G36*
G01X1346037D02*
X1345852Y899649D01*
X1344822D01*
X1344637Y900249D01*
Y900423D01*
X1346037D01*
Y900249D01*
G37*
G36*
G01X1331744Y889027D02*
X1331929Y889627D01*
X1332959D01*
X1333144Y889027D01*
Y888853D01*
X1331744D01*
Y889027D01*
G37*
G36*
G01X1335444Y889029D02*
X1335629Y889629D01*
X1336659D01*
X1336844Y889029D01*
Y888854D01*
X1335444D01*
Y889029D01*
G37*
G36*
G01X1339154D02*
X1339339Y889629D01*
X1340369D01*
X1340554Y889029D01*
Y888854D01*
X1339154D01*
Y889029D01*
G37*
G36*
G01X1342953Y890442D02*
X1342526Y890902D01*
X1343041Y891794D01*
X1343653Y891654D01*
X1343804Y891567D01*
X1343104Y890355D01*
X1342953Y890442D01*
G37*
G36*
G01X1344637Y892233D02*
X1344822Y892833D01*
X1345852D01*
X1346037Y892233D01*
Y892058D01*
X1344637D01*
Y892233D01*
G37*
G36*
G01X1331744Y889027D02*
X1331929Y889627D01*
X1332959D01*
X1333144Y889027D01*
Y888853D01*
X1331744D01*
Y889027D01*
G37*
G36*
G01X1335444Y889029D02*
X1335629Y889629D01*
X1336659D01*
X1336844Y889029D01*
Y888854D01*
X1335444D01*
Y889029D01*
G37*
G36*
G01X1339154D02*
X1339339Y889629D01*
X1340369D01*
X1340554Y889029D01*
Y888854D01*
X1339154D01*
Y889029D01*
G37*
G36*
G01X1342953Y890442D02*
X1342526Y890902D01*
X1343041Y891794D01*
X1343653Y891654D01*
X1343804Y891567D01*
X1343104Y890355D01*
X1342953Y890442D01*
G37*
G36*
G01X1344637Y892233D02*
X1344822Y892833D01*
X1345852D01*
X1346037Y892233D01*
Y892058D01*
X1344637D01*
Y892233D01*
G37*
G36*
G01X1345934Y886007D02*
X1346361Y885547D01*
X1345846Y884655D01*
X1345234Y884795D01*
X1345083Y884882D01*
X1345783Y886094D01*
X1345934Y886007D01*
G37*
G36*
G01D02*
X1346361Y885547D01*
X1345846Y884655D01*
X1345234Y884795D01*
X1345083Y884882D01*
X1345783Y886094D01*
X1345934Y886007D01*
G37*
G36*
G01X1344085Y889214D02*
X1344512Y888754D01*
X1343997Y887862D01*
X1343385Y888002D01*
X1343234Y888089D01*
X1343934Y889301D01*
X1344085Y889214D01*
G37*
G36*
G01D02*
X1344512Y888754D01*
X1343997Y887862D01*
X1343385Y888002D01*
X1343234Y888089D01*
X1343934Y889301D01*
X1344085Y889214D01*
G37*
G36*
G01X1334970Y887431D02*
X1334785Y886831D01*
X1333755D01*
X1333570Y887431D01*
Y887606D01*
X1334970D01*
Y887431D01*
G37*
G36*
G01X1338637D02*
X1338452Y886831D01*
X1337422D01*
X1337237Y887431D01*
Y887605D01*
X1338637D01*
Y887431D01*
G37*
G36*
G01X1342337D02*
X1342152Y886831D01*
X1341122D01*
X1340937Y887431D01*
Y887605D01*
X1342337D01*
Y887431D01*
G37*
G36*
G01X1334970D02*
X1334785Y886831D01*
X1333755D01*
X1333570Y887431D01*
Y887606D01*
X1334970D01*
Y887431D01*
G37*
G36*
G01X1338637D02*
X1338452Y886831D01*
X1337422D01*
X1337237Y887431D01*
Y887605D01*
X1338637D01*
Y887431D01*
G37*
G36*
G01X1342337D02*
X1342152Y886831D01*
X1341122D01*
X1340937Y887431D01*
Y887605D01*
X1342337D01*
Y887431D01*
G37*
G36*
G01X1344806Y887245D02*
X1344379Y887705D01*
X1344894Y888597D01*
X1345506Y888457D01*
X1345657Y888370D01*
X1344957Y887158D01*
X1344806Y887245D01*
G37*
G36*
G01D02*
X1344379Y887705D01*
X1344894Y888597D01*
X1345506Y888457D01*
X1345657Y888370D01*
X1344957Y887158D01*
X1344806Y887245D01*
G37*
G36*
G01X1334947Y893839D02*
X1334762Y893239D01*
X1333732D01*
X1333547Y893839D01*
Y894014D01*
X1334947D01*
Y893839D01*
G37*
G36*
G01X1344254Y897043D02*
X1344069Y896443D01*
X1343039D01*
X1342854Y897043D01*
Y897218D01*
X1344254D01*
Y897043D01*
G37*
G36*
G01X1340406Y895659D02*
X1340833Y895199D01*
X1340318Y894307D01*
X1339706Y894447D01*
X1339555Y894534D01*
X1340255Y895746D01*
X1340406Y895659D01*
G37*
G36*
G01X1338704Y893839D02*
X1338519Y893239D01*
X1337489D01*
X1337304Y893839D01*
Y894014D01*
X1338704D01*
Y893839D01*
G37*
G36*
G01X1334947D02*
X1334762Y893239D01*
X1333732D01*
X1333547Y893839D01*
Y894014D01*
X1334947D01*
Y893839D01*
G37*
G36*
G01X1344254Y897043D02*
X1344069Y896443D01*
X1343039D01*
X1342854Y897043D01*
Y897218D01*
X1344254D01*
Y897043D01*
G37*
G36*
G01X1340406Y895659D02*
X1340833Y895199D01*
X1340318Y894307D01*
X1339706Y894447D01*
X1339555Y894534D01*
X1340255Y895746D01*
X1340406Y895659D01*
G37*
G36*
G01X1338704Y893839D02*
X1338519Y893239D01*
X1337489D01*
X1337304Y893839D01*
Y894014D01*
X1338704D01*
Y893839D01*
G37*
G36*
G01X1333594Y892233D02*
X1333779Y892833D01*
X1334809D01*
X1334994Y892233D01*
Y892058D01*
X1333594D01*
Y892233D01*
G37*
G36*
G01X1342854Y895437D02*
X1343039Y896037D01*
X1344069D01*
X1344254Y895437D01*
Y895262D01*
X1342854D01*
Y895437D01*
G37*
G36*
G01X1341103Y893646D02*
X1340676Y894106D01*
X1341191Y894998D01*
X1341803Y894858D01*
X1341954Y894771D01*
X1341254Y893559D01*
X1341103Y893646D01*
G37*
G36*
G01X1337271Y892231D02*
X1337456Y892831D01*
X1338486D01*
X1338671Y892231D01*
Y892057D01*
X1337271D01*
Y892231D01*
G37*
G36*
G01X1333594Y892233D02*
X1333779Y892833D01*
X1334809D01*
X1334994Y892233D01*
Y892058D01*
X1333594D01*
Y892233D01*
G37*
G36*
G01X1342854Y895437D02*
X1343039Y896037D01*
X1344069D01*
X1344254Y895437D01*
Y895262D01*
X1342854D01*
Y895437D01*
G37*
G36*
G01X1341103Y893646D02*
X1340676Y894106D01*
X1341191Y894998D01*
X1341803Y894858D01*
X1341954Y894771D01*
X1341254Y893559D01*
X1341103Y893646D01*
G37*
G36*
G01X1337271Y892231D02*
X1337456Y892831D01*
X1338486D01*
X1338671Y892231D01*
Y892057D01*
X1337271D01*
Y892231D01*
G37*
G36*
G01X1331754Y895437D02*
X1331939Y896037D01*
X1332969D01*
X1333154Y895437D01*
Y895262D01*
X1331754D01*
Y895437D01*
G37*
G36*
G01X1340937Y898641D02*
X1341122Y899241D01*
X1342152D01*
X1342337Y898641D01*
Y898467D01*
X1340937D01*
Y898641D01*
G37*
G36*
G01X1339256Y896858D02*
X1338829Y897318D01*
X1339344Y898210D01*
X1339956Y898070D01*
X1340107Y897983D01*
X1339407Y896771D01*
X1339256Y896858D01*
G37*
G36*
G01X1335397Y895435D02*
X1335582Y896035D01*
X1336612D01*
X1336797Y895435D01*
Y895261D01*
X1335397D01*
Y895435D01*
G37*
G36*
G01X1331754Y895437D02*
X1331939Y896037D01*
X1332969D01*
X1333154Y895437D01*
Y895262D01*
X1331754D01*
Y895437D01*
G37*
G36*
G01X1340937Y898641D02*
X1341122Y899241D01*
X1342152D01*
X1342337Y898641D01*
Y898467D01*
X1340937D01*
Y898641D01*
G37*
G36*
G01X1339256Y896858D02*
X1338829Y897318D01*
X1339344Y898210D01*
X1339956Y898070D01*
X1340107Y897983D01*
X1339407Y896771D01*
X1339256Y896858D01*
G37*
G36*
G01X1335397Y895435D02*
X1335582Y896035D01*
X1336612D01*
X1336797Y895435D01*
Y895261D01*
X1335397D01*
Y895435D01*
G37*
G36*
G01X1333144Y890637D02*
X1332959Y890037D01*
X1331929D01*
X1331744Y890637D01*
Y890811D01*
X1333144D01*
Y890637D01*
G37*
G36*
G01X1346037Y893839D02*
X1345852Y893239D01*
X1344822D01*
X1344637Y893839D01*
Y894014D01*
X1346037D01*
Y893839D01*
G37*
G36*
G01X1342239Y892426D02*
X1342666Y891966D01*
X1342151Y891074D01*
X1341539Y891214D01*
X1341388Y891301D01*
X1342088Y892513D01*
X1342239Y892426D01*
G37*
G36*
G01X1340521Y890637D02*
X1340336Y890037D01*
X1339306D01*
X1339121Y890637D01*
Y890811D01*
X1340521D01*
Y890637D01*
G37*
G36*
G01X1336797Y890635D02*
X1336612Y890035D01*
X1335582D01*
X1335397Y890635D01*
Y890810D01*
X1336797D01*
Y890635D01*
G37*
G36*
G01X1333144Y890637D02*
X1332959Y890037D01*
X1331929D01*
X1331744Y890637D01*
Y890811D01*
X1333144D01*
Y890637D01*
G37*
G36*
G01X1346037Y893839D02*
X1345852Y893239D01*
X1344822D01*
X1344637Y893839D01*
Y894014D01*
X1346037D01*
Y893839D01*
G37*
G36*
G01X1342239Y892426D02*
X1342666Y891966D01*
X1342151Y891074D01*
X1341539Y891214D01*
X1341388Y891301D01*
X1342088Y892513D01*
X1342239Y892426D01*
G37*
G36*
G01X1340521Y890637D02*
X1340336Y890037D01*
X1339306D01*
X1339121Y890637D01*
Y890811D01*
X1340521D01*
Y890637D01*
G37*
G36*
G01X1336797Y890635D02*
X1336612Y890035D01*
X1335582D01*
X1335397Y890635D01*
Y890810D01*
X1336797D01*
Y890635D01*
G37*
G36*
G01X1336689Y902039D02*
X1337116Y901579D01*
X1336601Y900687D01*
X1335989Y900827D01*
X1335838Y900914D01*
X1336538Y902126D01*
X1336689Y902039D01*
G37*
G36*
G01X1340554Y903453D02*
X1340369Y902853D01*
X1339339D01*
X1339154Y903453D01*
Y903627D01*
X1340554D01*
Y903453D01*
G37*
G36*
G01X1344254D02*
X1344069Y902853D01*
X1343039D01*
X1342854Y903453D01*
Y903627D01*
X1344254D01*
Y903453D01*
G37*
G36*
G01X1336689Y902039D02*
X1337116Y901579D01*
X1336601Y900687D01*
X1335989Y900827D01*
X1335838Y900914D01*
X1336538Y902126D01*
X1336689Y902039D01*
G37*
G36*
G01X1340554Y903453D02*
X1340369Y902853D01*
X1339339D01*
X1339154Y903453D01*
Y903627D01*
X1340554D01*
Y903453D01*
G37*
G36*
G01X1344254D02*
X1344069Y902853D01*
X1343039D01*
X1342854Y903453D01*
Y903627D01*
X1344254D01*
Y903453D01*
G37*
G36*
G01X1339154Y901845D02*
X1339339Y902445D01*
X1340369D01*
X1340554Y901845D01*
Y901671D01*
X1339154D01*
Y901845D01*
G37*
G36*
G01X1342854D02*
X1343039Y902445D01*
X1344069D01*
X1344254Y901845D01*
Y901671D01*
X1342854D01*
Y901845D01*
G37*
G36*
G01X1339154D02*
X1339339Y902445D01*
X1340369D01*
X1340554Y901845D01*
Y901671D01*
X1339154D01*
Y901845D01*
G37*
G36*
G01X1342854D02*
X1343039Y902445D01*
X1344069D01*
X1344254Y901845D01*
Y901671D01*
X1342854D01*
Y901845D01*
G37*
G36*
G01X1331754D02*
X1331939Y902445D01*
X1332969D01*
X1333154Y901845D01*
Y901671D01*
X1331754D01*
Y901845D01*
G37*
G36*
G01X1335557Y903269D02*
X1335130Y903729D01*
X1335645Y904621D01*
X1336257Y904481D01*
X1336408Y904394D01*
X1335708Y903182D01*
X1335557Y903269D01*
G37*
G36*
G01X1337237Y905049D02*
X1337422Y905649D01*
X1338452D01*
X1338637Y905049D01*
Y904875D01*
X1337237D01*
Y905049D01*
G37*
G36*
G01X1340937D02*
X1341122Y905649D01*
X1342152D01*
X1342337Y905049D01*
Y904875D01*
X1340937D01*
Y905049D01*
G37*
G36*
G01X1344637D02*
X1344822Y905649D01*
X1345852D01*
X1346037Y905049D01*
Y904875D01*
X1344637D01*
Y905049D01*
G37*
G36*
G01X1331754Y901845D02*
X1331939Y902445D01*
X1332969D01*
X1333154Y901845D01*
Y901671D01*
X1331754D01*
Y901845D01*
G37*
G36*
G01X1335557Y903269D02*
X1335130Y903729D01*
X1335645Y904621D01*
X1336257Y904481D01*
X1336408Y904394D01*
X1335708Y903182D01*
X1335557Y903269D01*
G37*
G36*
G01X1337237Y905049D02*
X1337422Y905649D01*
X1338452D01*
X1338637Y905049D01*
Y904875D01*
X1337237D01*
Y905049D01*
G37*
G36*
G01X1340937D02*
X1341122Y905649D01*
X1342152D01*
X1342337Y905049D01*
Y904875D01*
X1340937D01*
Y905049D01*
G37*
G36*
G01X1344637D02*
X1344822Y905649D01*
X1345852D01*
X1346037Y905049D01*
Y904875D01*
X1344637D01*
Y905049D01*
G37*
G36*
G01X1331860Y909683D02*
X1331433Y910143D01*
X1331948Y911035D01*
X1332560Y910895D01*
X1332711Y910808D01*
X1332011Y909596D01*
X1331860Y909683D01*
G37*
G36*
G01X1333570Y911457D02*
X1333755Y912057D01*
X1334785D01*
X1334970Y911457D01*
Y911283D01*
X1333570D01*
Y911457D01*
G37*
G36*
G01X1344647Y911459D02*
X1344832Y912059D01*
X1345862D01*
X1346047Y911459D01*
Y911284D01*
X1344647D01*
Y911459D01*
G37*
G36*
G01X1340937D02*
X1341122Y912059D01*
X1342152D01*
X1342337Y911459D01*
Y911284D01*
X1340937D01*
Y911459D01*
G37*
G36*
G01X1337237D02*
X1337422Y912059D01*
X1338452D01*
X1338637Y911459D01*
Y911284D01*
X1337237D01*
Y911459D01*
G37*
G36*
G01X1331860Y909683D02*
X1331433Y910143D01*
X1331948Y911035D01*
X1332560Y910895D01*
X1332711Y910808D01*
X1332011Y909596D01*
X1331860Y909683D01*
G37*
G36*
G01X1333570Y911457D02*
X1333755Y912057D01*
X1334785D01*
X1334970Y911457D01*
Y911283D01*
X1333570D01*
Y911457D01*
G37*
G36*
G01X1344647Y911459D02*
X1344832Y912059D01*
X1345862D01*
X1346047Y911459D01*
Y911284D01*
X1344647D01*
Y911459D01*
G37*
G36*
G01X1340937D02*
X1341122Y912059D01*
X1342152D01*
X1342337Y911459D01*
Y911284D01*
X1340937D01*
Y911459D01*
G37*
G36*
G01X1337237D02*
X1337422Y912059D01*
X1338452D01*
X1338637Y911459D01*
Y911284D01*
X1337237D01*
Y911459D01*
G37*
G36*
G01X1333702Y906463D02*
X1333275Y906923D01*
X1333790Y907815D01*
X1334402Y907675D01*
X1334553Y907588D01*
X1333853Y906376D01*
X1333702Y906463D01*
G37*
G36*
G01X1335444Y908253D02*
X1335629Y908853D01*
X1336659D01*
X1336844Y908253D01*
Y908079D01*
X1335444D01*
Y908253D01*
G37*
G36*
G01X1339154D02*
X1339339Y908853D01*
X1340369D01*
X1340554Y908253D01*
Y908079D01*
X1339154D01*
Y908253D01*
G37*
G36*
G01X1342854D02*
X1343039Y908853D01*
X1344069D01*
X1344254Y908253D01*
Y908079D01*
X1342854D01*
Y908253D01*
G37*
G36*
G01X1333702Y906463D02*
X1333275Y906923D01*
X1333790Y907815D01*
X1334402Y907675D01*
X1334553Y907588D01*
X1333853Y906376D01*
X1333702Y906463D01*
G37*
G36*
G01X1335444Y908253D02*
X1335629Y908853D01*
X1336659D01*
X1336844Y908253D01*
Y908079D01*
X1335444D01*
Y908253D01*
G37*
G36*
G01X1339154D02*
X1339339Y908853D01*
X1340369D01*
X1340554Y908253D01*
Y908079D01*
X1339154D01*
Y908253D01*
G37*
G36*
G01X1342854D02*
X1343039Y908853D01*
X1344069D01*
X1344254Y908253D01*
Y908079D01*
X1342854D01*
Y908253D01*
G37*
G36*
G01X1332989Y908447D02*
X1333416Y907987D01*
X1332901Y907095D01*
X1332289Y907235D01*
X1332138Y907322D01*
X1332838Y908534D01*
X1332989Y908447D01*
G37*
G36*
G01X1344254Y909861D02*
X1344069Y909261D01*
X1343039D01*
X1342854Y909861D01*
Y910035D01*
X1344254D01*
Y909861D01*
G37*
G36*
G01X1340554D02*
X1340369Y909261D01*
X1339339D01*
X1339154Y909861D01*
Y910035D01*
X1340554D01*
Y909861D01*
G37*
G36*
G01X1336844D02*
X1336659Y909261D01*
X1335629D01*
X1335444Y909861D01*
Y910035D01*
X1336844D01*
Y909861D01*
G37*
G36*
G01X1332989Y908447D02*
X1333416Y907987D01*
X1332901Y907095D01*
X1332289Y907235D01*
X1332138Y907322D01*
X1332838Y908534D01*
X1332989Y908447D01*
G37*
G36*
G01X1344254Y909861D02*
X1344069Y909261D01*
X1343039D01*
X1342854Y909861D01*
Y910035D01*
X1344254D01*
Y909861D01*
G37*
G36*
G01X1340554D02*
X1340369Y909261D01*
X1339339D01*
X1339154Y909861D01*
Y910035D01*
X1340554D01*
Y909861D01*
G37*
G36*
G01X1336844D02*
X1336659Y909261D01*
X1335629D01*
X1335444Y909861D01*
Y910035D01*
X1336844D01*
Y909861D01*
G37*
G36*
G01X1334839Y905243D02*
X1335266Y904783D01*
X1334751Y903891D01*
X1334139Y904031D01*
X1333988Y904118D01*
X1334688Y905330D01*
X1334839Y905243D01*
G37*
G36*
G01X1333121Y903453D02*
X1332936Y902853D01*
X1331906D01*
X1331721Y903453D01*
Y903628D01*
X1333121D01*
Y903453D01*
G37*
G36*
G01X1338637Y906657D02*
X1338452Y906057D01*
X1337422D01*
X1337237Y906657D01*
Y906831D01*
X1338637D01*
Y906657D01*
G37*
G36*
G01X1342337D02*
X1342152Y906057D01*
X1341122D01*
X1340937Y906657D01*
Y906831D01*
X1342337D01*
Y906657D01*
G37*
G36*
G01X1346037D02*
X1345852Y906057D01*
X1344822D01*
X1344637Y906657D01*
Y906831D01*
X1346037D01*
Y906657D01*
G37*
G36*
G01X1334839Y905243D02*
X1335266Y904783D01*
X1334751Y903891D01*
X1334139Y904031D01*
X1333988Y904118D01*
X1334688Y905330D01*
X1334839Y905243D01*
G37*
G36*
G01X1333121Y903453D02*
X1332936Y902853D01*
X1331906D01*
X1331721Y903453D01*
Y903628D01*
X1333121D01*
Y903453D01*
G37*
G36*
G01X1338637Y906657D02*
X1338452Y906057D01*
X1337422D01*
X1337237Y906657D01*
Y906831D01*
X1338637D01*
Y906657D01*
G37*
G36*
G01X1342337D02*
X1342152Y906057D01*
X1341122D01*
X1340937Y906657D01*
Y906831D01*
X1342337D01*
Y906657D01*
G37*
G36*
G01X1346037D02*
X1345852Y906057D01*
X1344822D01*
X1344637Y906657D01*
Y906831D01*
X1346037D01*
Y906657D01*
G37*
G36*
G01X1333154Y916269D02*
X1332969Y915669D01*
X1331939D01*
X1331754Y916269D01*
Y916444D01*
X1333154D01*
Y916269D01*
G37*
G36*
G01X1344254D02*
X1344069Y915669D01*
X1343039D01*
X1342854Y916269D01*
Y916444D01*
X1344254D01*
Y916269D01*
G37*
G36*
G01X1336797Y916271D02*
X1336612Y915671D01*
X1335582D01*
X1335397Y916271D01*
Y916445D01*
X1336797D01*
Y916271D01*
G37*
G36*
G01X1340544Y916269D02*
X1340359Y915669D01*
X1339329D01*
X1339144Y916269D01*
Y916444D01*
X1340544D01*
Y916269D01*
G37*
G36*
G01X1333154D02*
X1332969Y915669D01*
X1331939D01*
X1331754Y916269D01*
Y916444D01*
X1333154D01*
Y916269D01*
G37*
G36*
G01X1344254D02*
X1344069Y915669D01*
X1343039D01*
X1342854Y916269D01*
Y916444D01*
X1344254D01*
Y916269D01*
G37*
G36*
G01X1336797Y916271D02*
X1336612Y915671D01*
X1335582D01*
X1335397Y916271D01*
Y916445D01*
X1336797D01*
Y916271D01*
G37*
G36*
G01X1340544Y916269D02*
X1340359Y915669D01*
X1339329D01*
X1339144Y916269D01*
Y916444D01*
X1340544D01*
Y916269D01*
G37*
G36*
G01X1331754Y914663D02*
X1331939Y915263D01*
X1332969D01*
X1333154Y914663D01*
Y914488D01*
X1331754D01*
Y914663D01*
G37*
G36*
G01X1335444Y914661D02*
X1335629Y915261D01*
X1336659D01*
X1336844Y914661D01*
Y914487D01*
X1335444D01*
Y914661D01*
G37*
G36*
G01X1339144Y914663D02*
X1339329Y915263D01*
X1340359D01*
X1340544Y914663D01*
Y914488D01*
X1339144D01*
Y914663D01*
G37*
G36*
G01X1342854D02*
X1343039Y915263D01*
X1344069D01*
X1344254Y914663D01*
Y914488D01*
X1342854D01*
Y914663D01*
G37*
G36*
G01X1331754D02*
X1331939Y915263D01*
X1332969D01*
X1333154Y914663D01*
Y914488D01*
X1331754D01*
Y914663D01*
G37*
G36*
G01X1335444Y914661D02*
X1335629Y915261D01*
X1336659D01*
X1336844Y914661D01*
Y914487D01*
X1335444D01*
Y914661D01*
G37*
G36*
G01X1339144Y914663D02*
X1339329Y915263D01*
X1340359D01*
X1340544Y914663D01*
Y914488D01*
X1339144D01*
Y914663D01*
G37*
G36*
G01X1342854D02*
X1343039Y915263D01*
X1344069D01*
X1344254Y914663D01*
Y914488D01*
X1342854D01*
Y914663D01*
G37*
G36*
G01X1334937Y913065D02*
X1334752Y912465D01*
X1333722D01*
X1333537Y913065D01*
Y913240D01*
X1334937D01*
Y913065D01*
G37*
G36*
G01X1331127Y911636D02*
X1331554Y911176D01*
X1331039Y910284D01*
X1330427Y910424D01*
X1330276Y910511D01*
X1330976Y911723D01*
X1331127Y911636D01*
G37*
G36*
G01X1338670Y913067D02*
X1338485Y912467D01*
X1337455D01*
X1337270Y913067D01*
Y913241D01*
X1338670D01*
Y913067D01*
G37*
G36*
G01X1342337Y913065D02*
X1342152Y912465D01*
X1341122D01*
X1340937Y913065D01*
Y913240D01*
X1342337D01*
Y913065D01*
G37*
G36*
G01X1346047D02*
X1345862Y912465D01*
X1344832D01*
X1344647Y913065D01*
Y913240D01*
X1346047D01*
Y913065D01*
G37*
G36*
G01X1334937D02*
X1334752Y912465D01*
X1333722D01*
X1333537Y913065D01*
Y913240D01*
X1334937D01*
Y913065D01*
G37*
G36*
G01X1331127Y911636D02*
X1331554Y911176D01*
X1331039Y910284D01*
X1330427Y910424D01*
X1330276Y910511D01*
X1330976Y911723D01*
X1331127Y911636D01*
G37*
G36*
G01X1338670Y913067D02*
X1338485Y912467D01*
X1337455D01*
X1337270Y913067D01*
Y913241D01*
X1338670D01*
Y913067D01*
G37*
G36*
G01X1342337Y913065D02*
X1342152Y912465D01*
X1341122D01*
X1340937Y913065D01*
Y913240D01*
X1342337D01*
Y913065D01*
G37*
G36*
G01X1346047D02*
X1345862Y912465D01*
X1344832D01*
X1344647Y913065D01*
Y913240D01*
X1346047D01*
Y913065D01*
G37*
G36*
G01X1333570Y930683D02*
X1333755Y931283D01*
X1334785D01*
X1334970Y930683D01*
Y930509D01*
X1333570D01*
Y930683D01*
G37*
G36*
G01X1337237Y930685D02*
X1337422Y931285D01*
X1338452D01*
X1338637Y930685D01*
Y930510D01*
X1337237D01*
Y930685D01*
G37*
G36*
G01X1344647D02*
X1344832Y931285D01*
X1345862D01*
X1346047Y930685D01*
Y930510D01*
X1344647D01*
Y930685D01*
G37*
G36*
G01X1340937D02*
X1341122Y931285D01*
X1342152D01*
X1342337Y930685D01*
Y930510D01*
X1340937D01*
Y930685D01*
G37*
G36*
G01X1333570Y930683D02*
X1333755Y931283D01*
X1334785D01*
X1334970Y930683D01*
Y930509D01*
X1333570D01*
Y930683D01*
G37*
G36*
G01X1337237Y930685D02*
X1337422Y931285D01*
X1338452D01*
X1338637Y930685D01*
Y930510D01*
X1337237D01*
Y930685D01*
G37*
G36*
G01X1344647D02*
X1344832Y931285D01*
X1345862D01*
X1346047Y930685D01*
Y930510D01*
X1344647D01*
Y930685D01*
G37*
G36*
G01X1340937D02*
X1341122Y931285D01*
X1342152D01*
X1342337Y930685D01*
Y930510D01*
X1340937D01*
Y930685D01*
G37*
G36*
G01X1331697Y927479D02*
X1331882Y928079D01*
X1332912D01*
X1333097Y927479D01*
Y927304D01*
X1331697D01*
Y927479D01*
G37*
G36*
G01X1342854D02*
X1343039Y928079D01*
X1344069D01*
X1344254Y927479D01*
Y927305D01*
X1342854D01*
Y927479D01*
G37*
G36*
G01X1335444D02*
X1335629Y928079D01*
X1336659D01*
X1336844Y927479D01*
Y927305D01*
X1335444D01*
Y927479D01*
G37*
G36*
G01X1339154D02*
X1339339Y928079D01*
X1340369D01*
X1340554Y927479D01*
Y927305D01*
X1339154D01*
Y927479D01*
G37*
G36*
G01X1331697D02*
X1331882Y928079D01*
X1332912D01*
X1333097Y927479D01*
Y927304D01*
X1331697D01*
Y927479D01*
G37*
G36*
G01X1342854D02*
X1343039Y928079D01*
X1344069D01*
X1344254Y927479D01*
Y927305D01*
X1342854D01*
Y927479D01*
G37*
G36*
G01X1335444D02*
X1335629Y928079D01*
X1336659D01*
X1336844Y927479D01*
Y927305D01*
X1335444D01*
Y927479D01*
G37*
G36*
G01X1339154D02*
X1339339Y928079D01*
X1340369D01*
X1340554Y927479D01*
Y927305D01*
X1339154D01*
Y927479D01*
G37*
G36*
G01X1333144Y929087D02*
X1332959Y928487D01*
X1331929D01*
X1331744Y929087D01*
Y929262D01*
X1333144D01*
Y929087D01*
G37*
G36*
G01X1344254D02*
X1344069Y928487D01*
X1343039D01*
X1342854Y929087D01*
Y929261D01*
X1344254D01*
Y929087D01*
G37*
G36*
G01X1340554D02*
X1340369Y928487D01*
X1339339D01*
X1339154Y929087D01*
Y929261D01*
X1340554D01*
Y929087D01*
G37*
G36*
G01X1336844D02*
X1336659Y928487D01*
X1335629D01*
X1335444Y929087D01*
Y929261D01*
X1336844D01*
Y929087D01*
G37*
G36*
G01X1333144D02*
X1332959Y928487D01*
X1331929D01*
X1331744Y929087D01*
Y929262D01*
X1333144D01*
Y929087D01*
G37*
G36*
G01X1344254D02*
X1344069Y928487D01*
X1343039D01*
X1342854Y929087D01*
Y929261D01*
X1344254D01*
Y929087D01*
G37*
G36*
G01X1340554D02*
X1340369Y928487D01*
X1339339D01*
X1339154Y929087D01*
Y929261D01*
X1340554D01*
Y929087D01*
G37*
G36*
G01X1336844D02*
X1336659Y928487D01*
X1335629D01*
X1335444Y929087D01*
Y929261D01*
X1336844D01*
Y929087D01*
G37*
G36*
G01X1334994Y925883D02*
X1334809Y925283D01*
X1333779D01*
X1333594Y925883D01*
Y926058D01*
X1334994D01*
Y925883D01*
G37*
G36*
G01X1346037D02*
X1345852Y925283D01*
X1344822D01*
X1344637Y925883D01*
Y926057D01*
X1346037D01*
Y925883D01*
G37*
G36*
G01X1342337D02*
X1342152Y925283D01*
X1341122D01*
X1340937Y925883D01*
Y926057D01*
X1342337D01*
Y925883D01*
G37*
G36*
G01X1338637D02*
X1338452Y925283D01*
X1337422D01*
X1337237Y925883D01*
Y926057D01*
X1338637D01*
Y925883D01*
G37*
G36*
G01X1334994D02*
X1334809Y925283D01*
X1333779D01*
X1333594Y925883D01*
Y926058D01*
X1334994D01*
Y925883D01*
G37*
G36*
G01X1346037D02*
X1345852Y925283D01*
X1344822D01*
X1344637Y925883D01*
Y926057D01*
X1346037D01*
Y925883D01*
G37*
G36*
G01X1342337D02*
X1342152Y925283D01*
X1341122D01*
X1340937Y925883D01*
Y926057D01*
X1342337D01*
Y925883D01*
G37*
G36*
G01X1338637D02*
X1338452Y925283D01*
X1337422D01*
X1337237Y925883D01*
Y926057D01*
X1338637D01*
Y925883D01*
G37*
G36*
G01X1334937Y932291D02*
X1334752Y931691D01*
X1333722D01*
X1333537Y932291D01*
Y932465D01*
X1334937D01*
Y932291D01*
G37*
G36*
G01X1338670D02*
X1338485Y931691D01*
X1337455D01*
X1337270Y932291D01*
Y932466D01*
X1338670D01*
Y932291D01*
G37*
G36*
G01X1342337D02*
X1342152Y931691D01*
X1341122D01*
X1340937Y932291D01*
Y932465D01*
X1342337D01*
Y932291D01*
G37*
G36*
G01X1346047D02*
X1345862Y931691D01*
X1344832D01*
X1344647Y932291D01*
Y932465D01*
X1346047D01*
Y932291D01*
G37*
G36*
G01X1334937D02*
X1334752Y931691D01*
X1333722D01*
X1333537Y932291D01*
Y932465D01*
X1334937D01*
Y932291D01*
G37*
G36*
G01X1338670D02*
X1338485Y931691D01*
X1337455D01*
X1337270Y932291D01*
Y932466D01*
X1338670D01*
Y932291D01*
G37*
G36*
G01X1342337D02*
X1342152Y931691D01*
X1341122D01*
X1340937Y932291D01*
Y932465D01*
X1342337D01*
Y932291D01*
G37*
G36*
G01X1346047D02*
X1345862Y931691D01*
X1344832D01*
X1344647Y932291D01*
Y932465D01*
X1346047D01*
Y932291D01*
G37*
G36*
G01X1333547Y924275D02*
X1333732Y924875D01*
X1334762D01*
X1334947Y924275D01*
Y924100D01*
X1333547D01*
Y924275D01*
G37*
G36*
G01X1344637D02*
X1344822Y924875D01*
X1345852D01*
X1346037Y924275D01*
Y924101D01*
X1344637D01*
Y924275D01*
G37*
G36*
G01X1340937D02*
X1341122Y924875D01*
X1342152D01*
X1342337Y924275D01*
Y924101D01*
X1340937D01*
Y924275D01*
G37*
G36*
G01X1337237D02*
X1337422Y924875D01*
X1338452D01*
X1338637Y924275D01*
Y924101D01*
X1337237D01*
Y924275D01*
G37*
G36*
G01X1333547D02*
X1333732Y924875D01*
X1334762D01*
X1334947Y924275D01*
Y924100D01*
X1333547D01*
Y924275D01*
G37*
G36*
G01X1344637D02*
X1344822Y924875D01*
X1345852D01*
X1346037Y924275D01*
Y924101D01*
X1344637D01*
Y924275D01*
G37*
G36*
G01X1340937D02*
X1341122Y924875D01*
X1342152D01*
X1342337Y924275D01*
Y924101D01*
X1340937D01*
Y924275D01*
G37*
G36*
G01X1337237D02*
X1337422Y924875D01*
X1338452D01*
X1338637Y924275D01*
Y924101D01*
X1337237D01*
Y924275D01*
G37*
G36*
G01X1331754Y921071D02*
X1331939Y921671D01*
X1332969D01*
X1333154Y921071D01*
Y920897D01*
X1331754D01*
Y921071D01*
G37*
G36*
G01X1342854D02*
X1343039Y921671D01*
X1344069D01*
X1344254Y921071D01*
Y920897D01*
X1342854D01*
Y921071D01*
G37*
G36*
G01X1339154D02*
X1339339Y921671D01*
X1340369D01*
X1340554Y921071D01*
Y920897D01*
X1339154D01*
Y921071D01*
G37*
G36*
G01X1335421D02*
X1335606Y921671D01*
X1336636D01*
X1336821Y921071D01*
Y920896D01*
X1335421D01*
Y921071D01*
G37*
G36*
G01X1331754D02*
X1331939Y921671D01*
X1332969D01*
X1333154Y921071D01*
Y920897D01*
X1331754D01*
Y921071D01*
G37*
G36*
G01X1342854D02*
X1343039Y921671D01*
X1344069D01*
X1344254Y921071D01*
Y920897D01*
X1342854D01*
Y921071D01*
G37*
G36*
G01X1339154D02*
X1339339Y921671D01*
X1340369D01*
X1340554Y921071D01*
Y920897D01*
X1339154D01*
Y921071D01*
G37*
G36*
G01X1335421D02*
X1335606Y921671D01*
X1336636D01*
X1336821Y921071D01*
Y920896D01*
X1335421D01*
Y921071D01*
G37*
G36*
G01X1333121Y922679D02*
X1332936Y922079D01*
X1331906D01*
X1331721Y922679D01*
Y922854D01*
X1333121D01*
Y922679D01*
G37*
G36*
G01X1344254D02*
X1344069Y922079D01*
X1343039D01*
X1342854Y922679D01*
Y922853D01*
X1344254D01*
Y922679D01*
G37*
G36*
G01X1340554D02*
X1340369Y922079D01*
X1339339D01*
X1339154Y922679D01*
Y922853D01*
X1340554D01*
Y922679D01*
G37*
G36*
G01X1336854D02*
X1336669Y922079D01*
X1335639D01*
X1335454Y922679D01*
Y922853D01*
X1336854D01*
Y922679D01*
G37*
G36*
G01X1333121D02*
X1332936Y922079D01*
X1331906D01*
X1331721Y922679D01*
Y922854D01*
X1333121D01*
Y922679D01*
G37*
G36*
G01X1344254D02*
X1344069Y922079D01*
X1343039D01*
X1342854Y922679D01*
Y922853D01*
X1344254D01*
Y922679D01*
G37*
G36*
G01X1340554D02*
X1340369Y922079D01*
X1339339D01*
X1339154Y922679D01*
Y922853D01*
X1340554D01*
Y922679D01*
G37*
G36*
G01X1336854D02*
X1336669Y922079D01*
X1335639D01*
X1335454Y922679D01*
Y922853D01*
X1336854D01*
Y922679D01*
G37*
G36*
G01X1334947Y919473D02*
X1334762Y918873D01*
X1333732D01*
X1333547Y919473D01*
Y919648D01*
X1334947D01*
Y919473D01*
G37*
G36*
G01X1346037D02*
X1345852Y918873D01*
X1344822D01*
X1344637Y919473D01*
Y919648D01*
X1346037D01*
Y919473D01*
G37*
G36*
G01X1342337D02*
X1342152Y918873D01*
X1341122D01*
X1340937Y919473D01*
Y919648D01*
X1342337D01*
Y919473D01*
G37*
G36*
G01X1338647Y919475D02*
X1338462Y918875D01*
X1337432D01*
X1337247Y919475D01*
Y919649D01*
X1338647D01*
Y919475D01*
G37*
G36*
G01X1334947Y919473D02*
X1334762Y918873D01*
X1333732D01*
X1333547Y919473D01*
Y919648D01*
X1334947D01*
Y919473D01*
G37*
G36*
G01X1346037D02*
X1345852Y918873D01*
X1344822D01*
X1344637Y919473D01*
Y919648D01*
X1346037D01*
Y919473D01*
G37*
G36*
G01X1342337D02*
X1342152Y918873D01*
X1341122D01*
X1340937Y919473D01*
Y919648D01*
X1342337D01*
Y919473D01*
G37*
G36*
G01X1338647Y919475D02*
X1338462Y918875D01*
X1337432D01*
X1337247Y919475D01*
Y919649D01*
X1338647D01*
Y919475D01*
G37*
G36*
G01X1333547Y917867D02*
X1333732Y918467D01*
X1334762D01*
X1334947Y917867D01*
Y917692D01*
X1333547D01*
Y917867D01*
G37*
G36*
G01X1337294Y917865D02*
X1337479Y918465D01*
X1338509D01*
X1338694Y917865D01*
Y917691D01*
X1337294D01*
Y917865D01*
G37*
G36*
G01X1340937Y917867D02*
X1341122Y918467D01*
X1342152D01*
X1342337Y917867D01*
Y917692D01*
X1340937D01*
Y917867D01*
G37*
G36*
G01X1344637D02*
X1344822Y918467D01*
X1345852D01*
X1346037Y917867D01*
Y917692D01*
X1344637D01*
Y917867D01*
G37*
G36*
G01X1333547D02*
X1333732Y918467D01*
X1334762D01*
X1334947Y917867D01*
Y917692D01*
X1333547D01*
Y917867D01*
G37*
G36*
G01X1337294Y917865D02*
X1337479Y918465D01*
X1338509D01*
X1338694Y917865D01*
Y917691D01*
X1337294D01*
Y917865D01*
G37*
G36*
G01X1340937Y917867D02*
X1341122Y918467D01*
X1342152D01*
X1342337Y917867D01*
Y917692D01*
X1340937D01*
Y917867D01*
G37*
G36*
G01X1344637D02*
X1344822Y918467D01*
X1345852D01*
X1346037Y917867D01*
Y917692D01*
X1344637D01*
Y917867D01*
G37*
G36*
G01X1333121Y941905D02*
X1332936Y941305D01*
X1331906D01*
X1331721Y941905D01*
Y942079D01*
X1333121D01*
Y941905D01*
G37*
G36*
G01X1340554Y941903D02*
X1340369Y941303D01*
X1339339D01*
X1339154Y941903D01*
Y942078D01*
X1340554D01*
Y941903D01*
G37*
G36*
G01X1336854D02*
X1336669Y941303D01*
X1335639D01*
X1335454Y941903D01*
Y942078D01*
X1336854D01*
Y941903D01*
G37*
G36*
G01X1344254D02*
X1344069Y941303D01*
X1343039D01*
X1342854Y941903D01*
Y942078D01*
X1344254D01*
Y941903D01*
G37*
G36*
G01X1333121Y941905D02*
X1332936Y941305D01*
X1331906D01*
X1331721Y941905D01*
Y942079D01*
X1333121D01*
Y941905D01*
G37*
G36*
G01X1340554Y941903D02*
X1340369Y941303D01*
X1339339D01*
X1339154Y941903D01*
Y942078D01*
X1340554D01*
Y941903D01*
G37*
G36*
G01X1336854D02*
X1336669Y941303D01*
X1335639D01*
X1335454Y941903D01*
Y942078D01*
X1336854D01*
Y941903D01*
G37*
G36*
G01X1344254D02*
X1344069Y941303D01*
X1343039D01*
X1342854Y941903D01*
Y942078D01*
X1344254D01*
Y941903D01*
G37*
G36*
G01X1334947Y938699D02*
X1334762Y938099D01*
X1333732D01*
X1333547Y938699D01*
Y938874D01*
X1334947D01*
Y938699D01*
G37*
G36*
G01X1342337D02*
X1342152Y938099D01*
X1341122D01*
X1340937Y938699D01*
Y938874D01*
X1342337D01*
Y938699D01*
G37*
G36*
G01X1338647Y938701D02*
X1338462Y938101D01*
X1337432D01*
X1337247Y938701D01*
Y938875D01*
X1338647D01*
Y938701D01*
G37*
G36*
G01X1346037Y938699D02*
X1345852Y938099D01*
X1344822D01*
X1344637Y938699D01*
Y938874D01*
X1346037D01*
Y938699D01*
G37*
G36*
G01X1334947D02*
X1334762Y938099D01*
X1333732D01*
X1333547Y938699D01*
Y938874D01*
X1334947D01*
Y938699D01*
G37*
G36*
G01X1342337D02*
X1342152Y938099D01*
X1341122D01*
X1340937Y938699D01*
Y938874D01*
X1342337D01*
Y938699D01*
G37*
G36*
G01X1338647Y938701D02*
X1338462Y938101D01*
X1337432D01*
X1337247Y938701D01*
Y938875D01*
X1338647D01*
Y938701D01*
G37*
G36*
G01X1346037Y938699D02*
X1345852Y938099D01*
X1344822D01*
X1344637Y938699D01*
Y938874D01*
X1346037D01*
Y938699D01*
G37*
G36*
G01X1331697Y946705D02*
X1331882Y947305D01*
X1332912D01*
X1333097Y946705D01*
Y946530D01*
X1331697D01*
Y946705D01*
G37*
G36*
G01X1339154D02*
X1339339Y947305D01*
X1340369D01*
X1340554Y946705D01*
Y946531D01*
X1339154D01*
Y946705D01*
G37*
G36*
G01X1342854D02*
X1343039Y947305D01*
X1344069D01*
X1344254Y946705D01*
Y946531D01*
X1342854D01*
Y946705D01*
G37*
G36*
G01X1335444D02*
X1335629Y947305D01*
X1336659D01*
X1336844Y946705D01*
Y946531D01*
X1335444D01*
Y946705D01*
G37*
G36*
G01X1331697D02*
X1331882Y947305D01*
X1332912D01*
X1333097Y946705D01*
Y946530D01*
X1331697D01*
Y946705D01*
G37*
G36*
G01X1339154D02*
X1339339Y947305D01*
X1340369D01*
X1340554Y946705D01*
Y946531D01*
X1339154D01*
Y946705D01*
G37*
G36*
G01X1342854D02*
X1343039Y947305D01*
X1344069D01*
X1344254Y946705D01*
Y946531D01*
X1342854D01*
Y946705D01*
G37*
G36*
G01X1335444D02*
X1335629Y947305D01*
X1336659D01*
X1336844Y946705D01*
Y946531D01*
X1335444D01*
Y946705D01*
G37*
G36*
G01X1333144Y948313D02*
X1332959Y947713D01*
X1331929D01*
X1331744Y948313D01*
Y948488D01*
X1333144D01*
Y948313D01*
G37*
G36*
G01X1344254D02*
X1344069Y947713D01*
X1343039D01*
X1342854Y948313D01*
Y948487D01*
X1344254D01*
Y948313D01*
G37*
G36*
G01X1340554D02*
X1340369Y947713D01*
X1339339D01*
X1339154Y948313D01*
Y948487D01*
X1340554D01*
Y948313D01*
G37*
G36*
G01X1336844D02*
X1336659Y947713D01*
X1335629D01*
X1335444Y948313D01*
Y948487D01*
X1336844D01*
Y948313D01*
G37*
G36*
G01X1333144D02*
X1332959Y947713D01*
X1331929D01*
X1331744Y948313D01*
Y948488D01*
X1333144D01*
Y948313D01*
G37*
G36*
G01X1344254D02*
X1344069Y947713D01*
X1343039D01*
X1342854Y948313D01*
Y948487D01*
X1344254D01*
Y948313D01*
G37*
G36*
G01X1340554D02*
X1340369Y947713D01*
X1339339D01*
X1339154Y948313D01*
Y948487D01*
X1340554D01*
Y948313D01*
G37*
G36*
G01X1336844D02*
X1336659Y947713D01*
X1335629D01*
X1335444Y948313D01*
Y948487D01*
X1336844D01*
Y948313D01*
G37*
G36*
G01X1334994Y945109D02*
X1334809Y944509D01*
X1333779D01*
X1333594Y945109D01*
Y945283D01*
X1334994D01*
Y945109D01*
G37*
G36*
G01X1346037Y945107D02*
X1345852Y944507D01*
X1344822D01*
X1344637Y945107D01*
Y945282D01*
X1346037D01*
Y945107D01*
G37*
G36*
G01X1342337D02*
X1342152Y944507D01*
X1341122D01*
X1340937Y945107D01*
Y945282D01*
X1342337D01*
Y945107D01*
G37*
G36*
G01X1338637D02*
X1338452Y944507D01*
X1337422D01*
X1337237Y945107D01*
Y945282D01*
X1338637D01*
Y945107D01*
G37*
G36*
G01X1334994Y945109D02*
X1334809Y944509D01*
X1333779D01*
X1333594Y945109D01*
Y945283D01*
X1334994D01*
Y945109D01*
G37*
G36*
G01X1346037Y945107D02*
X1345852Y944507D01*
X1344822D01*
X1344637Y945107D01*
Y945282D01*
X1346037D01*
Y945107D01*
G37*
G36*
G01X1342337D02*
X1342152Y944507D01*
X1341122D01*
X1340937Y945107D01*
Y945282D01*
X1342337D01*
Y945107D01*
G37*
G36*
G01X1338637D02*
X1338452Y944507D01*
X1337422D01*
X1337237Y945107D01*
Y945282D01*
X1338637D01*
Y945107D01*
G37*
G36*
G01X1333547Y943499D02*
X1333732Y944099D01*
X1334762D01*
X1334947Y943499D01*
Y943325D01*
X1333547D01*
Y943499D01*
G37*
G36*
G01X1344637Y943501D02*
X1344822Y944101D01*
X1345852D01*
X1346037Y943501D01*
Y943326D01*
X1344637D01*
Y943501D01*
G37*
G36*
G01X1340937D02*
X1341122Y944101D01*
X1342152D01*
X1342337Y943501D01*
Y943326D01*
X1340937D01*
Y943501D01*
G37*
G36*
G01X1337237D02*
X1337422Y944101D01*
X1338452D01*
X1338637Y943501D01*
Y943326D01*
X1337237D01*
Y943501D01*
G37*
G36*
G01X1333547Y943499D02*
X1333732Y944099D01*
X1334762D01*
X1334947Y943499D01*
Y943325D01*
X1333547D01*
Y943499D01*
G37*
G36*
G01X1344637Y943501D02*
X1344822Y944101D01*
X1345852D01*
X1346037Y943501D01*
Y943326D01*
X1344637D01*
Y943501D01*
G37*
G36*
G01X1340937D02*
X1341122Y944101D01*
X1342152D01*
X1342337Y943501D01*
Y943326D01*
X1340937D01*
Y943501D01*
G37*
G36*
G01X1337237D02*
X1337422Y944101D01*
X1338452D01*
X1338637Y943501D01*
Y943326D01*
X1337237D01*
Y943501D01*
G37*
G36*
G01X1331754Y940297D02*
X1331939Y940897D01*
X1332969D01*
X1333154Y940297D01*
Y940122D01*
X1331754D01*
Y940297D01*
G37*
G36*
G01X1335421Y940295D02*
X1335606Y940895D01*
X1336636D01*
X1336821Y940295D01*
Y940121D01*
X1335421D01*
Y940295D01*
G37*
G36*
G01X1339154Y940297D02*
X1339339Y940897D01*
X1340369D01*
X1340554Y940297D01*
Y940122D01*
X1339154D01*
Y940297D01*
G37*
G36*
G01X1342854D02*
X1343039Y940897D01*
X1344069D01*
X1344254Y940297D01*
Y940122D01*
X1342854D01*
Y940297D01*
G37*
G36*
G01X1331754D02*
X1331939Y940897D01*
X1332969D01*
X1333154Y940297D01*
Y940122D01*
X1331754D01*
Y940297D01*
G37*
G36*
G01X1335421Y940295D02*
X1335606Y940895D01*
X1336636D01*
X1336821Y940295D01*
Y940121D01*
X1335421D01*
Y940295D01*
G37*
G36*
G01X1339154Y940297D02*
X1339339Y940897D01*
X1340369D01*
X1340554Y940297D01*
Y940122D01*
X1339154D01*
Y940297D01*
G37*
G36*
G01X1342854D02*
X1343039Y940897D01*
X1344069D01*
X1344254Y940297D01*
Y940122D01*
X1342854D01*
Y940297D01*
G37*
G36*
G01X1333154Y935495D02*
X1332969Y934895D01*
X1331939D01*
X1331754Y935495D01*
Y935670D01*
X1333154D01*
Y935495D01*
G37*
G36*
G01X1336797Y935497D02*
X1336612Y934897D01*
X1335582D01*
X1335397Y935497D01*
Y935671D01*
X1336797D01*
Y935497D01*
G37*
G36*
G01X1340496D02*
X1340311Y934897D01*
X1339281D01*
X1339096Y935497D01*
Y935671D01*
X1340496D01*
Y935497D01*
G37*
G36*
G01X1344254Y935495D02*
X1344069Y934895D01*
X1343039D01*
X1342854Y935495D01*
Y935669D01*
X1344254D01*
Y935495D01*
G37*
G36*
G01X1333154D02*
X1332969Y934895D01*
X1331939D01*
X1331754Y935495D01*
Y935670D01*
X1333154D01*
Y935495D01*
G37*
G36*
G01X1336797Y935497D02*
X1336612Y934897D01*
X1335582D01*
X1335397Y935497D01*
Y935671D01*
X1336797D01*
Y935497D01*
G37*
G36*
G01X1340496D02*
X1340311Y934897D01*
X1339281D01*
X1339096Y935497D01*
Y935671D01*
X1340496D01*
Y935497D01*
G37*
G36*
G01X1344254Y935495D02*
X1344069Y934895D01*
X1343039D01*
X1342854Y935495D01*
Y935669D01*
X1344254D01*
Y935495D01*
G37*
G36*
G01X1331754Y933889D02*
X1331939Y934489D01*
X1332969D01*
X1333154Y933889D01*
Y933714D01*
X1331754D01*
Y933889D01*
G37*
G36*
G01X1335444Y933887D02*
X1335629Y934487D01*
X1336659D01*
X1336844Y933887D01*
Y933713D01*
X1335444D01*
Y933887D01*
G37*
G36*
G01X1339144Y933889D02*
X1339329Y934489D01*
X1340359D01*
X1340544Y933889D01*
Y933714D01*
X1339144D01*
Y933889D01*
G37*
G36*
G01X1342854D02*
X1343039Y934489D01*
X1344069D01*
X1344254Y933889D01*
Y933714D01*
X1342854D01*
Y933889D01*
G37*
G36*
G01X1331754D02*
X1331939Y934489D01*
X1332969D01*
X1333154Y933889D01*
Y933714D01*
X1331754D01*
Y933889D01*
G37*
G36*
G01X1335444Y933887D02*
X1335629Y934487D01*
X1336659D01*
X1336844Y933887D01*
Y933713D01*
X1335444D01*
Y933887D01*
G37*
G36*
G01X1339144Y933889D02*
X1339329Y934489D01*
X1340359D01*
X1340544Y933889D01*
Y933714D01*
X1339144D01*
Y933889D01*
G37*
G36*
G01X1342854D02*
X1343039Y934489D01*
X1344069D01*
X1344254Y933889D01*
Y933714D01*
X1342854D01*
Y933889D01*
G37*
G36*
G01X1333547Y937093D02*
X1333732Y937693D01*
X1334762D01*
X1334947Y937093D01*
Y936918D01*
X1333547D01*
Y937093D01*
G37*
G36*
G01X1344639Y937091D02*
X1344824Y937691D01*
X1345854D01*
X1346039Y937091D01*
Y936917D01*
X1344639D01*
Y937091D01*
G37*
G36*
G01X1337294D02*
X1337479Y937691D01*
X1338509D01*
X1338694Y937091D01*
Y936917D01*
X1337294D01*
Y937091D01*
G37*
G36*
G01X1340937Y937093D02*
X1341122Y937693D01*
X1342152D01*
X1342337Y937093D01*
Y936918D01*
X1340937D01*
Y937093D01*
G37*
G36*
G01X1333547D02*
X1333732Y937693D01*
X1334762D01*
X1334947Y937093D01*
Y936918D01*
X1333547D01*
Y937093D01*
G37*
G36*
G01X1344639Y937091D02*
X1344824Y937691D01*
X1345854D01*
X1346039Y937091D01*
Y936917D01*
X1344639D01*
Y937091D01*
G37*
G36*
G01X1337294D02*
X1337479Y937691D01*
X1338509D01*
X1338694Y937091D01*
Y936917D01*
X1337294D01*
Y937091D01*
G37*
G36*
G01X1340937Y937093D02*
X1341122Y937693D01*
X1342152D01*
X1342337Y937093D01*
Y936918D01*
X1340937D01*
Y937093D01*
G37*
G36*
G01X1333547Y962725D02*
X1333732Y963325D01*
X1334762D01*
X1334947Y962725D01*
Y962551D01*
X1333547D01*
Y962725D01*
G37*
G36*
G01X1337247Y962727D02*
X1337432Y963327D01*
X1338462D01*
X1338647Y962727D01*
Y962552D01*
X1337247D01*
Y962727D01*
G37*
G36*
G01X1340947Y962725D02*
X1341132Y963325D01*
X1342162D01*
X1342347Y962725D01*
Y962551D01*
X1340947D01*
Y962725D01*
G37*
G36*
G01X1344637Y962727D02*
X1344822Y963327D01*
X1345852D01*
X1346037Y962727D01*
Y962552D01*
X1344637D01*
Y962727D01*
G37*
G36*
G01X1333547Y962725D02*
X1333732Y963325D01*
X1334762D01*
X1334947Y962725D01*
Y962551D01*
X1333547D01*
Y962725D01*
G37*
G36*
G01X1337247Y962727D02*
X1337432Y963327D01*
X1338462D01*
X1338647Y962727D01*
Y962552D01*
X1337247D01*
Y962727D01*
G37*
G36*
G01X1340947Y962725D02*
X1341132Y963325D01*
X1342162D01*
X1342347Y962725D01*
Y962551D01*
X1340947D01*
Y962725D01*
G37*
G36*
G01X1344637Y962727D02*
X1344822Y963327D01*
X1345852D01*
X1346037Y962727D01*
Y962552D01*
X1344637D01*
Y962727D01*
G37*
G36*
G01X1331707Y959521D02*
X1331892Y960121D01*
X1332922D01*
X1333107Y959521D01*
Y959347D01*
X1331707D01*
Y959521D01*
G37*
G36*
G01X1346507D02*
X1346692Y960121D01*
X1347722D01*
X1347907Y959521D01*
Y959347D01*
X1346507D01*
Y959521D01*
G37*
G36*
G01X1342807D02*
X1342992Y960121D01*
X1344022D01*
X1344207Y959521D01*
Y959347D01*
X1342807D01*
Y959521D01*
G37*
G36*
G01X1339107D02*
X1339292Y960121D01*
X1340322D01*
X1340507Y959521D01*
Y959347D01*
X1339107D01*
Y959521D01*
G37*
G36*
G01X1335407D02*
X1335592Y960121D01*
X1336622D01*
X1336807Y959521D01*
Y959347D01*
X1335407D01*
Y959521D01*
G37*
G36*
G01X1331707D02*
X1331892Y960121D01*
X1332922D01*
X1333107Y959521D01*
Y959347D01*
X1331707D01*
Y959521D01*
G37*
G36*
G01X1346507D02*
X1346692Y960121D01*
X1347722D01*
X1347907Y959521D01*
Y959347D01*
X1346507D01*
Y959521D01*
G37*
G36*
G01X1342807D02*
X1342992Y960121D01*
X1344022D01*
X1344207Y959521D01*
Y959347D01*
X1342807D01*
Y959521D01*
G37*
G36*
G01X1339107D02*
X1339292Y960121D01*
X1340322D01*
X1340507Y959521D01*
Y959347D01*
X1339107D01*
Y959521D01*
G37*
G36*
G01X1335407D02*
X1335592Y960121D01*
X1336622D01*
X1336807Y959521D01*
Y959347D01*
X1335407D01*
Y959521D01*
G37*
G36*
G01X1333121Y961131D02*
X1332936Y960531D01*
X1331906D01*
X1331721Y961131D01*
Y961305D01*
X1333121D01*
Y961131D01*
G37*
G36*
G01X1344254Y961129D02*
X1344069Y960529D01*
X1343039D01*
X1342854Y961129D01*
Y961304D01*
X1344254D01*
Y961129D01*
G37*
G36*
G01X1340521Y961131D02*
X1340336Y960531D01*
X1339306D01*
X1339121Y961131D01*
Y961305D01*
X1340521D01*
Y961131D01*
G37*
G36*
G01X1336854Y961129D02*
X1336669Y960529D01*
X1335639D01*
X1335454Y961129D01*
Y961304D01*
X1336854D01*
Y961129D01*
G37*
G36*
G01X1333121Y961131D02*
X1332936Y960531D01*
X1331906D01*
X1331721Y961131D01*
Y961305D01*
X1333121D01*
Y961131D01*
G37*
G36*
G01X1344254Y961129D02*
X1344069Y960529D01*
X1343039D01*
X1342854Y961129D01*
Y961304D01*
X1344254D01*
Y961129D01*
G37*
G36*
G01X1340521Y961131D02*
X1340336Y960531D01*
X1339306D01*
X1339121Y961131D01*
Y961305D01*
X1340521D01*
Y961131D01*
G37*
G36*
G01X1336854Y961129D02*
X1336669Y960529D01*
X1335639D01*
X1335454Y961129D01*
Y961304D01*
X1336854D01*
Y961129D01*
G37*
G36*
G01X1334984Y957927D02*
X1334799Y957327D01*
X1333769D01*
X1333584Y957927D01*
Y958101D01*
X1334984D01*
Y957927D01*
G37*
G36*
G01X1338684D02*
X1338499Y957327D01*
X1337469D01*
X1337284Y957927D01*
Y958101D01*
X1338684D01*
Y957927D01*
G37*
G36*
G01X1342384D02*
X1342199Y957327D01*
X1341169D01*
X1340984Y957927D01*
Y958101D01*
X1342384D01*
Y957927D01*
G37*
G36*
G01X1346084D02*
X1345899Y957327D01*
X1344869D01*
X1344684Y957927D01*
Y958101D01*
X1346084D01*
Y957927D01*
G37*
G36*
G01X1334984D02*
X1334799Y957327D01*
X1333769D01*
X1333584Y957927D01*
Y958101D01*
X1334984D01*
Y957927D01*
G37*
G36*
G01X1338684D02*
X1338499Y957327D01*
X1337469D01*
X1337284Y957927D01*
Y958101D01*
X1338684D01*
Y957927D01*
G37*
G36*
G01X1342384D02*
X1342199Y957327D01*
X1341169D01*
X1340984Y957927D01*
Y958101D01*
X1342384D01*
Y957927D01*
G37*
G36*
G01X1346084D02*
X1345899Y957327D01*
X1344869D01*
X1344684Y957927D01*
Y958101D01*
X1346084D01*
Y957927D01*
G37*
G36*
G01X1333570Y949909D02*
X1333755Y950509D01*
X1334785D01*
X1334970Y949909D01*
Y949734D01*
X1333570D01*
Y949909D01*
G37*
G36*
G01X1340937D02*
X1341122Y950509D01*
X1342152D01*
X1342337Y949909D01*
Y949735D01*
X1340937D01*
Y949909D01*
G37*
G36*
G01X1337237D02*
X1337422Y950509D01*
X1338452D01*
X1338637Y949909D01*
Y949735D01*
X1337237D01*
Y949909D01*
G37*
G36*
G01X1344647D02*
X1344832Y950509D01*
X1345862D01*
X1346047Y949909D01*
Y949735D01*
X1344647D01*
Y949909D01*
G37*
G36*
G01X1333570D02*
X1333755Y950509D01*
X1334785D01*
X1334970Y949909D01*
Y949734D01*
X1333570D01*
Y949909D01*
G37*
G36*
G01X1340937D02*
X1341122Y950509D01*
X1342152D01*
X1342337Y949909D01*
Y949735D01*
X1340937D01*
Y949909D01*
G37*
G36*
G01X1337237D02*
X1337422Y950509D01*
X1338452D01*
X1338637Y949909D01*
Y949735D01*
X1337237D01*
Y949909D01*
G37*
G36*
G01X1344647D02*
X1344832Y950509D01*
X1345862D01*
X1346047Y949909D01*
Y949735D01*
X1344647D01*
Y949909D01*
G37*
G36*
G01X1333118Y954723D02*
X1332933Y954123D01*
X1331903D01*
X1331718Y954723D01*
Y954897D01*
X1333118D01*
Y954723D01*
G37*
G36*
G01X1344254Y954721D02*
X1344069Y954121D01*
X1343039D01*
X1342854Y954721D01*
Y954895D01*
X1344254D01*
Y954721D01*
G37*
G36*
G01X1340554D02*
X1340369Y954121D01*
X1339339D01*
X1339154Y954721D01*
Y954895D01*
X1340554D01*
Y954721D01*
G37*
G36*
G01X1336820Y954723D02*
X1336635Y954123D01*
X1335605D01*
X1335420Y954723D01*
Y954897D01*
X1336820D01*
Y954723D01*
G37*
G36*
G01X1333118D02*
X1332933Y954123D01*
X1331903D01*
X1331718Y954723D01*
Y954897D01*
X1333118D01*
Y954723D01*
G37*
G36*
G01X1344254Y954721D02*
X1344069Y954121D01*
X1343039D01*
X1342854Y954721D01*
Y954895D01*
X1344254D01*
Y954721D01*
G37*
G36*
G01X1340554D02*
X1340369Y954121D01*
X1339339D01*
X1339154Y954721D01*
Y954895D01*
X1340554D01*
Y954721D01*
G37*
G36*
G01X1336820Y954723D02*
X1336635Y954123D01*
X1335605D01*
X1335420Y954723D01*
Y954897D01*
X1336820D01*
Y954723D01*
G37*
G36*
G01X1331754Y953113D02*
X1331939Y953713D01*
X1332969D01*
X1333154Y953113D01*
Y952939D01*
X1331754D01*
Y953113D01*
G37*
G36*
G01X1335454D02*
X1335639Y953713D01*
X1336669D01*
X1336854Y953113D01*
Y952939D01*
X1335454D01*
Y953113D01*
G37*
G36*
G01X1339154D02*
X1339339Y953713D01*
X1340369D01*
X1340554Y953113D01*
Y952939D01*
X1339154D01*
Y953113D01*
G37*
G36*
G01X1342854D02*
X1343039Y953713D01*
X1344069D01*
X1344254Y953113D01*
Y952939D01*
X1342854D01*
Y953113D01*
G37*
G36*
G01X1331754D02*
X1331939Y953713D01*
X1332969D01*
X1333154Y953113D01*
Y952939D01*
X1331754D01*
Y953113D01*
G37*
G36*
G01X1335454D02*
X1335639Y953713D01*
X1336669D01*
X1336854Y953113D01*
Y952939D01*
X1335454D01*
Y953113D01*
G37*
G36*
G01X1339154D02*
X1339339Y953713D01*
X1340369D01*
X1340554Y953113D01*
Y952939D01*
X1339154D01*
Y953113D01*
G37*
G36*
G01X1342854D02*
X1343039Y953713D01*
X1344069D01*
X1344254Y953113D01*
Y952939D01*
X1342854D01*
Y953113D01*
G37*
G36*
G01X1333547Y956319D02*
X1333732Y956919D01*
X1334762D01*
X1334947Y956319D01*
Y956144D01*
X1333547D01*
Y956319D01*
G37*
G36*
G01X1340937D02*
X1341122Y956919D01*
X1342152D01*
X1342337Y956319D01*
Y956144D01*
X1340937D01*
Y956319D01*
G37*
G36*
G01X1344639Y956317D02*
X1344824Y956917D01*
X1345854D01*
X1346039Y956317D01*
Y956143D01*
X1344639D01*
Y956317D01*
G37*
G36*
G01X1337294D02*
X1337479Y956917D01*
X1338509D01*
X1338694Y956317D01*
Y956143D01*
X1337294D01*
Y956317D01*
G37*
G36*
G01X1333547Y956319D02*
X1333732Y956919D01*
X1334762D01*
X1334947Y956319D01*
Y956144D01*
X1333547D01*
Y956319D01*
G37*
G36*
G01X1340937D02*
X1341122Y956919D01*
X1342152D01*
X1342337Y956319D01*
Y956144D01*
X1340937D01*
Y956319D01*
G37*
G36*
G01X1344639Y956317D02*
X1344824Y956917D01*
X1345854D01*
X1346039Y956317D01*
Y956143D01*
X1344639D01*
Y956317D01*
G37*
G36*
G01X1337294D02*
X1337479Y956917D01*
X1338509D01*
X1338694Y956317D01*
Y956143D01*
X1337294D01*
Y956317D01*
G37*
G36*
G01X1334937Y951517D02*
X1334752Y950917D01*
X1333722D01*
X1333537Y951517D01*
Y951691D01*
X1334937D01*
Y951517D01*
G37*
G36*
G01X1338637D02*
X1338452Y950917D01*
X1337422D01*
X1337237Y951517D01*
Y951691D01*
X1338637D01*
Y951517D01*
G37*
G36*
G01X1342337D02*
X1342152Y950917D01*
X1341122D01*
X1340937Y951517D01*
Y951691D01*
X1342337D01*
Y951517D01*
G37*
G36*
G01X1346047D02*
X1345862Y950917D01*
X1344832D01*
X1344647Y951517D01*
Y951691D01*
X1346047D01*
Y951517D01*
G37*
G36*
G01X1334937D02*
X1334752Y950917D01*
X1333722D01*
X1333537Y951517D01*
Y951691D01*
X1334937D01*
Y951517D01*
G37*
G36*
G01X1338637D02*
X1338452Y950917D01*
X1337422D01*
X1337237Y951517D01*
Y951691D01*
X1338637D01*
Y951517D01*
G37*
G36*
G01X1342337D02*
X1342152Y950917D01*
X1341122D01*
X1340937Y951517D01*
Y951691D01*
X1342337D01*
Y951517D01*
G37*
G36*
G01X1346047D02*
X1345862Y950917D01*
X1344832D01*
X1344647Y951517D01*
Y951691D01*
X1346047D01*
Y951517D01*
G37*
G36*
G01X1334994Y964335D02*
X1334809Y963735D01*
X1333779D01*
X1333594Y964335D01*
Y964509D01*
X1334994D01*
Y964335D01*
G37*
G36*
G01X1338647Y964333D02*
X1338462Y963733D01*
X1337432D01*
X1337247Y964333D01*
Y964508D01*
X1338647D01*
Y964333D01*
G37*
G36*
G01X1342394Y964335D02*
X1342209Y963735D01*
X1341179D01*
X1340994Y964335D01*
Y964509D01*
X1342394D01*
Y964335D01*
G37*
G36*
G01X1346037Y964333D02*
X1345852Y963733D01*
X1344822D01*
X1344637Y964333D01*
Y964508D01*
X1346037D01*
Y964333D01*
G37*
G36*
G01X1334994Y964335D02*
X1334809Y963735D01*
X1333779D01*
X1333594Y964335D01*
Y964509D01*
X1334994D01*
Y964335D01*
G37*
G36*
G01X1338647Y964333D02*
X1338462Y963733D01*
X1337432D01*
X1337247Y964333D01*
Y964508D01*
X1338647D01*
Y964333D01*
G37*
G36*
G01X1342394Y964335D02*
X1342209Y963735D01*
X1341179D01*
X1340994Y964335D01*
Y964509D01*
X1342394D01*
Y964335D01*
G37*
G36*
G01X1346037Y964333D02*
X1345852Y963733D01*
X1344822D01*
X1344637Y964333D01*
Y964508D01*
X1346037D01*
Y964333D01*
G37*
G36*
G01X1334947Y977151D02*
X1334762Y976551D01*
X1333732D01*
X1333547Y977151D01*
Y977325D01*
X1334947D01*
Y977151D01*
G37*
G36*
G01X1338647D02*
X1338462Y976551D01*
X1337432D01*
X1337247Y977151D01*
Y977326D01*
X1338647D01*
Y977151D01*
G37*
G36*
G01X1342337D02*
X1342152Y976551D01*
X1341122D01*
X1340937Y977151D01*
Y977325D01*
X1342337D01*
Y977151D01*
G37*
G36*
G01X1346037D02*
X1345852Y976551D01*
X1344822D01*
X1344637Y977151D01*
Y977325D01*
X1346037D01*
Y977151D01*
G37*
G36*
G01X1334947D02*
X1334762Y976551D01*
X1333732D01*
X1333547Y977151D01*
Y977325D01*
X1334947D01*
Y977151D01*
G37*
G36*
G01X1338647D02*
X1338462Y976551D01*
X1337432D01*
X1337247Y977151D01*
Y977326D01*
X1338647D01*
Y977151D01*
G37*
G36*
G01X1342337D02*
X1342152Y976551D01*
X1341122D01*
X1340937Y977151D01*
Y977325D01*
X1342337D01*
Y977151D01*
G37*
G36*
G01X1346037D02*
X1345852Y976551D01*
X1344822D01*
X1344637Y977151D01*
Y977325D01*
X1346037D01*
Y977151D01*
G37*
G36*
G01X1333547Y975543D02*
X1333732Y976143D01*
X1334762D01*
X1334947Y975543D01*
Y975369D01*
X1333547D01*
Y975543D01*
G37*
G36*
G01X1337294D02*
X1337479Y976143D01*
X1338509D01*
X1338694Y975543D01*
Y975368D01*
X1337294D01*
Y975543D01*
G37*
G36*
G01X1340937D02*
X1341122Y976143D01*
X1342152D01*
X1342337Y975543D01*
Y975369D01*
X1340937D01*
Y975543D01*
G37*
G36*
G01X1344637D02*
X1344822Y976143D01*
X1345852D01*
X1346037Y975543D01*
Y975369D01*
X1344637D01*
Y975543D01*
G37*
G36*
G01X1333547D02*
X1333732Y976143D01*
X1334762D01*
X1334947Y975543D01*
Y975369D01*
X1333547D01*
Y975543D01*
G37*
G36*
G01X1337294D02*
X1337479Y976143D01*
X1338509D01*
X1338694Y975543D01*
Y975368D01*
X1337294D01*
Y975543D01*
G37*
G36*
G01X1340937D02*
X1341122Y976143D01*
X1342152D01*
X1342337Y975543D01*
Y975369D01*
X1340937D01*
Y975543D01*
G37*
G36*
G01X1344637D02*
X1344822Y976143D01*
X1345852D01*
X1346037Y975543D01*
Y975369D01*
X1344637D01*
Y975543D01*
G37*
G36*
G01X1331754Y978749D02*
X1331939Y979349D01*
X1332969D01*
X1333154Y978749D01*
Y978574D01*
X1331754D01*
Y978749D01*
G37*
G36*
G01X1335421Y978747D02*
X1335606Y979347D01*
X1336636D01*
X1336821Y978747D01*
Y978573D01*
X1335421D01*
Y978747D01*
G37*
G36*
G01X1339154Y978749D02*
X1339339Y979349D01*
X1340369D01*
X1340554Y978749D01*
Y978574D01*
X1339154D01*
Y978749D01*
G37*
G36*
G01X1342854D02*
X1343039Y979349D01*
X1344069D01*
X1344254Y978749D01*
Y978574D01*
X1342854D01*
Y978749D01*
G37*
G36*
G01X1331754D02*
X1331939Y979349D01*
X1332969D01*
X1333154Y978749D01*
Y978574D01*
X1331754D01*
Y978749D01*
G37*
G36*
G01X1335421Y978747D02*
X1335606Y979347D01*
X1336636D01*
X1336821Y978747D01*
Y978573D01*
X1335421D01*
Y978747D01*
G37*
G36*
G01X1339154Y978749D02*
X1339339Y979349D01*
X1340369D01*
X1340554Y978749D01*
Y978574D01*
X1339154D01*
Y978749D01*
G37*
G36*
G01X1342854D02*
X1343039Y979349D01*
X1344069D01*
X1344254Y978749D01*
Y978574D01*
X1342854D01*
Y978749D01*
G37*
G36*
G01X1333144Y973947D02*
X1332959Y973347D01*
X1331929D01*
X1331744Y973947D01*
Y974121D01*
X1333144D01*
Y973947D01*
G37*
G36*
G01X1336797D02*
X1336612Y973347D01*
X1335582D01*
X1335397Y973947D01*
Y974122D01*
X1336797D01*
Y973947D01*
G37*
G36*
G01X1340544D02*
X1340359Y973347D01*
X1339329D01*
X1339144Y973947D01*
Y974121D01*
X1340544D01*
Y973947D01*
G37*
G36*
G01X1344254D02*
X1344069Y973347D01*
X1343039D01*
X1342854Y973947D01*
Y974121D01*
X1344254D01*
Y973947D01*
G37*
G36*
G01X1333144D02*
X1332959Y973347D01*
X1331929D01*
X1331744Y973947D01*
Y974121D01*
X1333144D01*
Y973947D01*
G37*
G36*
G01X1336797D02*
X1336612Y973347D01*
X1335582D01*
X1335397Y973947D01*
Y974122D01*
X1336797D01*
Y973947D01*
G37*
G36*
G01X1340544D02*
X1340359Y973347D01*
X1339329D01*
X1339144Y973947D01*
Y974121D01*
X1340544D01*
Y973947D01*
G37*
G36*
G01X1344254D02*
X1344069Y973347D01*
X1343039D01*
X1342854Y973947D01*
Y974121D01*
X1344254D01*
Y973947D01*
G37*
G36*
G01X1331697Y965931D02*
X1331882Y966531D01*
X1332912D01*
X1333097Y965931D01*
Y965756D01*
X1331697D01*
Y965931D01*
G37*
G36*
G01X1342844D02*
X1343029Y966531D01*
X1344059D01*
X1344244Y965931D01*
Y965757D01*
X1342844D01*
Y965931D01*
G37*
G36*
G01X1339097D02*
X1339282Y966531D01*
X1340312D01*
X1340497Y965931D01*
Y965756D01*
X1339097D01*
Y965931D01*
G37*
G36*
G01X1335444D02*
X1335629Y966531D01*
X1336659D01*
X1336844Y965931D01*
Y965757D01*
X1335444D01*
Y965931D01*
G37*
G36*
G01X1331697D02*
X1331882Y966531D01*
X1332912D01*
X1333097Y965931D01*
Y965756D01*
X1331697D01*
Y965931D01*
G37*
G36*
G01X1342844D02*
X1343029Y966531D01*
X1344059D01*
X1344244Y965931D01*
Y965757D01*
X1342844D01*
Y965931D01*
G37*
G36*
G01X1339097D02*
X1339282Y966531D01*
X1340312D01*
X1340497Y965931D01*
Y965756D01*
X1339097D01*
Y965931D01*
G37*
G36*
G01X1335444D02*
X1335629Y966531D01*
X1336659D01*
X1336844Y965931D01*
Y965757D01*
X1335444D01*
Y965931D01*
G37*
G36*
G01X1333570Y969135D02*
X1333755Y969735D01*
X1334785D01*
X1334970Y969135D01*
Y968960D01*
X1333570D01*
Y969135D01*
G37*
G36*
G01X1344647D02*
X1344832Y969735D01*
X1345862D01*
X1346047Y969135D01*
Y968961D01*
X1344647D01*
Y969135D01*
G37*
G36*
G01X1340970D02*
X1341155Y969735D01*
X1342185D01*
X1342370Y969135D01*
Y968960D01*
X1340970D01*
Y969135D01*
G37*
G36*
G01X1337237D02*
X1337422Y969735D01*
X1338452D01*
X1338637Y969135D01*
Y968961D01*
X1337237D01*
Y969135D01*
G37*
G36*
G01X1333570D02*
X1333755Y969735D01*
X1334785D01*
X1334970Y969135D01*
Y968960D01*
X1333570D01*
Y969135D01*
G37*
G36*
G01X1344647D02*
X1344832Y969735D01*
X1345862D01*
X1346047Y969135D01*
Y968961D01*
X1344647D01*
Y969135D01*
G37*
G36*
G01X1340970D02*
X1341155Y969735D01*
X1342185D01*
X1342370Y969135D01*
Y968960D01*
X1340970D01*
Y969135D01*
G37*
G36*
G01X1337237D02*
X1337422Y969735D01*
X1338452D01*
X1338637Y969135D01*
Y968961D01*
X1337237D01*
Y969135D01*
G37*
G36*
G01X1333144Y967539D02*
X1332959Y966939D01*
X1331929D01*
X1331744Y967539D01*
Y967714D01*
X1333144D01*
Y967539D01*
G37*
G36*
G01X1344244D02*
X1344059Y966939D01*
X1343029D01*
X1342844Y967539D01*
Y967713D01*
X1344244D01*
Y967539D01*
G37*
G36*
G01X1340544D02*
X1340359Y966939D01*
X1339329D01*
X1339144Y967539D01*
Y967714D01*
X1340544D01*
Y967539D01*
G37*
G36*
G01X1336844D02*
X1336659Y966939D01*
X1335629D01*
X1335444Y967539D01*
Y967713D01*
X1336844D01*
Y967539D01*
G37*
G36*
G01X1333144D02*
X1332959Y966939D01*
X1331929D01*
X1331744Y967539D01*
Y967714D01*
X1333144D01*
Y967539D01*
G37*
G36*
G01X1344244D02*
X1344059Y966939D01*
X1343029D01*
X1342844Y967539D01*
Y967713D01*
X1344244D01*
Y967539D01*
G37*
G36*
G01X1340544D02*
X1340359Y966939D01*
X1339329D01*
X1339144Y967539D01*
Y967714D01*
X1340544D01*
Y967539D01*
G37*
G36*
G01X1336844D02*
X1336659Y966939D01*
X1335629D01*
X1335444Y967539D01*
Y967713D01*
X1336844D01*
Y967539D01*
G37*
G36*
G01X1332177Y1005289D02*
X1332362Y1005889D01*
X1333392D01*
X1333577Y1005289D01*
Y1005115D01*
X1332177D01*
Y1005289D01*
G37*
G36*
G01X1335830D02*
X1336015Y1005889D01*
X1337045D01*
X1337230Y1005289D01*
Y1005114D01*
X1335830D01*
Y1005289D01*
G37*
G36*
G01X1339577D02*
X1339762Y1005889D01*
X1340792D01*
X1340977Y1005289D01*
Y1005115D01*
X1339577D01*
Y1005289D01*
G37*
G36*
G01X1343287D02*
X1343472Y1005889D01*
X1344502D01*
X1344687Y1005289D01*
Y1005115D01*
X1343287D01*
Y1005289D01*
G37*
G36*
G01X1332177D02*
X1332362Y1005889D01*
X1333392D01*
X1333577Y1005289D01*
Y1005115D01*
X1332177D01*
Y1005289D01*
G37*
G36*
G01X1335830D02*
X1336015Y1005889D01*
X1337045D01*
X1337230Y1005289D01*
Y1005114D01*
X1335830D01*
Y1005289D01*
G37*
G36*
G01X1339577D02*
X1339762Y1005889D01*
X1340792D01*
X1340977Y1005289D01*
Y1005115D01*
X1339577D01*
Y1005289D01*
G37*
G36*
G01X1343287D02*
X1343472Y1005889D01*
X1344502D01*
X1344687Y1005289D01*
Y1005115D01*
X1343287D01*
Y1005289D01*
G37*
G36*
G01X1330303Y1002083D02*
X1330488Y1002683D01*
X1331518D01*
X1331703Y1002083D01*
Y1001909D01*
X1330303D01*
Y1002083D01*
G37*
G36*
G01X1333980Y1002085D02*
X1334165Y1002685D01*
X1335195D01*
X1335380Y1002085D01*
Y1001910D01*
X1333980D01*
Y1002085D01*
G37*
G36*
G01X1345070D02*
X1345255Y1002685D01*
X1346285D01*
X1346470Y1002085D01*
Y1001910D01*
X1345070D01*
Y1002085D01*
G37*
G36*
G01X1341370D02*
X1341555Y1002685D01*
X1342585D01*
X1342770Y1002085D01*
Y1001910D01*
X1341370D01*
Y1002085D01*
G37*
G36*
G01X1337680Y1002083D02*
X1337865Y1002683D01*
X1338895D01*
X1339080Y1002083D01*
Y1001909D01*
X1337680D01*
Y1002083D01*
G37*
G36*
G01X1330303D02*
X1330488Y1002683D01*
X1331518D01*
X1331703Y1002083D01*
Y1001909D01*
X1330303D01*
Y1002083D01*
G37*
G36*
G01X1333980Y1002085D02*
X1334165Y1002685D01*
X1335195D01*
X1335380Y1002085D01*
Y1001910D01*
X1333980D01*
Y1002085D01*
G37*
G36*
G01X1345070D02*
X1345255Y1002685D01*
X1346285D01*
X1346470Y1002085D01*
Y1001910D01*
X1345070D01*
Y1002085D01*
G37*
G36*
G01X1341370D02*
X1341555Y1002685D01*
X1342585D01*
X1342770Y1002085D01*
Y1001910D01*
X1341370D01*
Y1002085D01*
G37*
G36*
G01X1337680Y1002083D02*
X1337865Y1002683D01*
X1338895D01*
X1339080Y1002083D01*
Y1001909D01*
X1337680D01*
Y1002083D01*
G37*
G36*
G01X1331703Y1003693D02*
X1331518Y1003093D01*
X1330488D01*
X1330303Y1003693D01*
Y1003867D01*
X1331703D01*
Y1003693D01*
G37*
G36*
G01X1335380Y1003691D02*
X1335195Y1003091D01*
X1334165D01*
X1333980Y1003691D01*
Y1003866D01*
X1335380D01*
Y1003691D01*
G37*
G36*
G01X1346470D02*
X1346285Y1003091D01*
X1345255D01*
X1345070Y1003691D01*
Y1003866D01*
X1346470D01*
Y1003691D01*
G37*
G36*
G01X1342770D02*
X1342585Y1003091D01*
X1341555D01*
X1341370Y1003691D01*
Y1003866D01*
X1342770D01*
Y1003691D01*
G37*
G36*
G01X1339127Y1003693D02*
X1338942Y1003093D01*
X1337912D01*
X1337727Y1003693D01*
Y1003867D01*
X1339127D01*
Y1003693D01*
G37*
G36*
G01X1331703D02*
X1331518Y1003093D01*
X1330488D01*
X1330303Y1003693D01*
Y1003867D01*
X1331703D01*
Y1003693D01*
G37*
G36*
G01X1335380Y1003691D02*
X1335195Y1003091D01*
X1334165D01*
X1333980Y1003691D01*
Y1003866D01*
X1335380D01*
Y1003691D01*
G37*
G36*
G01X1346470D02*
X1346285Y1003091D01*
X1345255D01*
X1345070Y1003691D01*
Y1003866D01*
X1346470D01*
Y1003691D01*
G37*
G36*
G01X1342770D02*
X1342585Y1003091D01*
X1341555D01*
X1341370Y1003691D01*
Y1003866D01*
X1342770D01*
Y1003691D01*
G37*
G36*
G01X1339127Y1003693D02*
X1338942Y1003093D01*
X1337912D01*
X1337727Y1003693D01*
Y1003867D01*
X1339127D01*
Y1003693D01*
G37*
G36*
G01X1333577Y1000487D02*
X1333392Y999887D01*
X1332362D01*
X1332177Y1000487D01*
Y1000662D01*
X1333577D01*
Y1000487D01*
G37*
G36*
G01X1344687D02*
X1344502Y999887D01*
X1343472D01*
X1343287Y1000487D01*
Y1000662D01*
X1344687D01*
Y1000487D01*
G37*
G36*
G01X1340987D02*
X1340802Y999887D01*
X1339772D01*
X1339587Y1000487D01*
Y1000662D01*
X1340987D01*
Y1000487D01*
G37*
G36*
G01X1337254Y1000489D02*
X1337069Y999889D01*
X1336039D01*
X1335854Y1000489D01*
Y1000663D01*
X1337254D01*
Y1000489D01*
G37*
G36*
G01X1333577Y1000487D02*
X1333392Y999887D01*
X1332362D01*
X1332177Y1000487D01*
Y1000662D01*
X1333577D01*
Y1000487D01*
G37*
G36*
G01X1344687D02*
X1344502Y999887D01*
X1343472D01*
X1343287Y1000487D01*
Y1000662D01*
X1344687D01*
Y1000487D01*
G37*
G36*
G01X1340987D02*
X1340802Y999887D01*
X1339772D01*
X1339587Y1000487D01*
Y1000662D01*
X1340987D01*
Y1000487D01*
G37*
G36*
G01X1337254Y1000489D02*
X1337069Y999889D01*
X1336039D01*
X1335854Y1000489D01*
Y1000663D01*
X1337254D01*
Y1000489D01*
G37*
G36*
G01X1332153Y1011697D02*
X1332338Y1012297D01*
X1333368D01*
X1333553Y1011697D01*
Y1011522D01*
X1332153D01*
Y1011697D01*
G37*
G36*
G01X1335877D02*
X1336062Y1012297D01*
X1337092D01*
X1337277Y1011697D01*
Y1011523D01*
X1335877D01*
Y1011697D01*
G37*
G36*
G01X1339577D02*
X1339762Y1012297D01*
X1340792D01*
X1340977Y1011697D01*
Y1011522D01*
X1339577D01*
Y1011697D01*
G37*
G36*
G01X1343277D02*
X1343462Y1012297D01*
X1344492D01*
X1344677Y1011697D01*
Y1011523D01*
X1343277D01*
Y1011697D01*
G37*
G36*
G01X1332153D02*
X1332338Y1012297D01*
X1333368D01*
X1333553Y1011697D01*
Y1011522D01*
X1332153D01*
Y1011697D01*
G37*
G36*
G01X1335877D02*
X1336062Y1012297D01*
X1337092D01*
X1337277Y1011697D01*
Y1011523D01*
X1335877D01*
Y1011697D01*
G37*
G36*
G01X1339577D02*
X1339762Y1012297D01*
X1340792D01*
X1340977Y1011697D01*
Y1011522D01*
X1339577D01*
Y1011697D01*
G37*
G36*
G01X1343277D02*
X1343462Y1012297D01*
X1344492D01*
X1344677Y1011697D01*
Y1011523D01*
X1343277D01*
Y1011697D01*
G37*
G36*
G01X1330303Y1008493D02*
X1330488Y1009093D01*
X1331518D01*
X1331703Y1008493D01*
Y1008318D01*
X1330303D01*
Y1008493D01*
G37*
G36*
G01X1333970D02*
X1334155Y1009093D01*
X1335185D01*
X1335370Y1008493D01*
Y1008319D01*
X1333970D01*
Y1008493D01*
G37*
G36*
G01X1345080D02*
X1345265Y1009093D01*
X1346295D01*
X1346480Y1008493D01*
Y1008319D01*
X1345080D01*
Y1008493D01*
G37*
G36*
G01X1341370D02*
X1341555Y1009093D01*
X1342585D01*
X1342770Y1008493D01*
Y1008319D01*
X1341370D01*
Y1008493D01*
G37*
G36*
G01X1337703D02*
X1337888Y1009093D01*
X1338918D01*
X1339103Y1008493D01*
Y1008318D01*
X1337703D01*
Y1008493D01*
G37*
G36*
G01X1330303D02*
X1330488Y1009093D01*
X1331518D01*
X1331703Y1008493D01*
Y1008318D01*
X1330303D01*
Y1008493D01*
G37*
G36*
G01X1333970D02*
X1334155Y1009093D01*
X1335185D01*
X1335370Y1008493D01*
Y1008319D01*
X1333970D01*
Y1008493D01*
G37*
G36*
G01X1345080D02*
X1345265Y1009093D01*
X1346295D01*
X1346480Y1008493D01*
Y1008319D01*
X1345080D01*
Y1008493D01*
G37*
G36*
G01X1341370D02*
X1341555Y1009093D01*
X1342585D01*
X1342770Y1008493D01*
Y1008319D01*
X1341370D01*
Y1008493D01*
G37*
G36*
G01X1337703D02*
X1337888Y1009093D01*
X1338918D01*
X1339103Y1008493D01*
Y1008318D01*
X1337703D01*
Y1008493D01*
G37*
G36*
G01X1335403Y1010101D02*
X1335218Y1009501D01*
X1334188D01*
X1334003Y1010101D01*
Y1010276D01*
X1335403D01*
Y1010101D01*
G37*
G36*
G01X1331703D02*
X1331518Y1009501D01*
X1330488D01*
X1330303Y1010101D01*
Y1010276D01*
X1331703D01*
Y1010101D01*
G37*
G36*
G01X1346480D02*
X1346295Y1009501D01*
X1345265D01*
X1345080Y1010101D01*
Y1010275D01*
X1346480D01*
Y1010101D01*
G37*
G36*
G01X1342803D02*
X1342618Y1009501D01*
X1341588D01*
X1341403Y1010101D01*
Y1010276D01*
X1342803D01*
Y1010101D01*
G37*
G36*
G01X1339070D02*
X1338885Y1009501D01*
X1337855D01*
X1337670Y1010101D01*
Y1010275D01*
X1339070D01*
Y1010101D01*
G37*
G36*
G01X1335403D02*
X1335218Y1009501D01*
X1334188D01*
X1334003Y1010101D01*
Y1010276D01*
X1335403D01*
Y1010101D01*
G37*
G36*
G01X1331703D02*
X1331518Y1009501D01*
X1330488D01*
X1330303Y1010101D01*
Y1010276D01*
X1331703D01*
Y1010101D01*
G37*
G36*
G01X1346480D02*
X1346295Y1009501D01*
X1345265D01*
X1345080Y1010101D01*
Y1010275D01*
X1346480D01*
Y1010101D01*
G37*
G36*
G01X1342803D02*
X1342618Y1009501D01*
X1341588D01*
X1341403Y1010101D01*
Y1010276D01*
X1342803D01*
Y1010101D01*
G37*
G36*
G01X1339070D02*
X1338885Y1009501D01*
X1337855D01*
X1337670Y1010101D01*
Y1010275D01*
X1339070D01*
Y1010101D01*
G37*
G36*
G01X1333577Y1006897D02*
X1333392Y1006297D01*
X1332362D01*
X1332177Y1006897D01*
Y1007071D01*
X1333577D01*
Y1006897D01*
G37*
G36*
G01X1337277D02*
X1337092Y1006297D01*
X1336062D01*
X1335877Y1006897D01*
Y1007072D01*
X1337277D01*
Y1006897D01*
G37*
G36*
G01X1344687D02*
X1344502Y1006297D01*
X1343472D01*
X1343287Y1006897D01*
Y1007071D01*
X1344687D01*
Y1006897D01*
G37*
G36*
G01X1340977D02*
X1340792Y1006297D01*
X1339762D01*
X1339577Y1006897D01*
Y1007071D01*
X1340977D01*
Y1006897D01*
G37*
G36*
G01X1333577D02*
X1333392Y1006297D01*
X1332362D01*
X1332177Y1006897D01*
Y1007071D01*
X1333577D01*
Y1006897D01*
G37*
G36*
G01X1337277D02*
X1337092Y1006297D01*
X1336062D01*
X1335877Y1006897D01*
Y1007072D01*
X1337277D01*
Y1006897D01*
G37*
G36*
G01X1344687D02*
X1344502Y1006297D01*
X1343472D01*
X1343287Y1006897D01*
Y1007071D01*
X1344687D01*
Y1006897D01*
G37*
G36*
G01X1340977D02*
X1340792Y1006297D01*
X1339762D01*
X1339577Y1006897D01*
Y1007071D01*
X1340977D01*
Y1006897D01*
G37*
G36*
G01X1331703Y1029327D02*
X1331518Y1028727D01*
X1330488D01*
X1330303Y1029327D01*
Y1029502D01*
X1331703D01*
Y1029327D01*
G37*
G36*
G01X1335403D02*
X1335218Y1028727D01*
X1334188D01*
X1334003Y1029327D01*
Y1029502D01*
X1335403D01*
Y1029327D01*
G37*
G36*
G01X1339070D02*
X1338885Y1028727D01*
X1337855D01*
X1337670Y1029327D01*
Y1029501D01*
X1339070D01*
Y1029327D01*
G37*
G36*
G01X1342770D02*
X1342585Y1028727D01*
X1341555D01*
X1341370Y1029327D01*
Y1029501D01*
X1342770D01*
Y1029327D01*
G37*
G36*
G01X1346470D02*
X1346285Y1028727D01*
X1345255D01*
X1345070Y1029327D01*
Y1029501D01*
X1346470D01*
Y1029327D01*
G37*
G36*
G01X1331703D02*
X1331518Y1028727D01*
X1330488D01*
X1330303Y1029327D01*
Y1029502D01*
X1331703D01*
Y1029327D01*
G37*
G36*
G01X1335403D02*
X1335218Y1028727D01*
X1334188D01*
X1334003Y1029327D01*
Y1029502D01*
X1335403D01*
Y1029327D01*
G37*
G36*
G01X1339070D02*
X1338885Y1028727D01*
X1337855D01*
X1337670Y1029327D01*
Y1029501D01*
X1339070D01*
Y1029327D01*
G37*
G36*
G01X1342770D02*
X1342585Y1028727D01*
X1341555D01*
X1341370Y1029327D01*
Y1029501D01*
X1342770D01*
Y1029327D01*
G37*
G36*
G01X1346470D02*
X1346285Y1028727D01*
X1345255D01*
X1345070Y1029327D01*
Y1029501D01*
X1346470D01*
Y1029327D01*
G37*
G36*
G01X1333577Y1019713D02*
X1333392Y1019113D01*
X1332362D01*
X1332177Y1019713D01*
Y1019888D01*
X1333577D01*
Y1019713D01*
G37*
G36*
G01X1337254Y1019715D02*
X1337069Y1019115D01*
X1336039D01*
X1335854Y1019715D01*
Y1019889D01*
X1337254D01*
Y1019715D01*
G37*
G36*
G01X1340987Y1019713D02*
X1340802Y1019113D01*
X1339772D01*
X1339587Y1019713D01*
Y1019888D01*
X1340987D01*
Y1019713D01*
G37*
G36*
G01X1344687D02*
X1344502Y1019113D01*
X1343472D01*
X1343287Y1019713D01*
Y1019888D01*
X1344687D01*
Y1019713D01*
G37*
G36*
G01X1333577D02*
X1333392Y1019113D01*
X1332362D01*
X1332177Y1019713D01*
Y1019888D01*
X1333577D01*
Y1019713D01*
G37*
G36*
G01X1337254Y1019715D02*
X1337069Y1019115D01*
X1336039D01*
X1335854Y1019715D01*
Y1019889D01*
X1337254D01*
Y1019715D01*
G37*
G36*
G01X1340987Y1019713D02*
X1340802Y1019113D01*
X1339772D01*
X1339587Y1019713D01*
Y1019888D01*
X1340987D01*
Y1019713D01*
G37*
G36*
G01X1344687D02*
X1344502Y1019113D01*
X1343472D01*
X1343287Y1019713D01*
Y1019888D01*
X1344687D01*
Y1019713D01*
G37*
G36*
G01X1335380Y1016509D02*
X1335195Y1015909D01*
X1334165D01*
X1333980Y1016509D01*
Y1016684D01*
X1335380D01*
Y1016509D01*
G37*
G36*
G01X1331727D02*
X1331542Y1015909D01*
X1330512D01*
X1330327Y1016509D01*
Y1016683D01*
X1331727D01*
Y1016509D01*
G37*
G36*
G01X1346470D02*
X1346285Y1015909D01*
X1345255D01*
X1345070Y1016509D01*
Y1016683D01*
X1346470D01*
Y1016509D01*
G37*
G36*
G01X1342780D02*
X1342595Y1015909D01*
X1341565D01*
X1341380Y1016509D01*
Y1016684D01*
X1342780D01*
Y1016509D01*
G37*
G36*
G01X1339080D02*
X1338895Y1015909D01*
X1337865D01*
X1337680Y1016509D01*
Y1016683D01*
X1339080D01*
Y1016509D01*
G37*
G36*
G01X1335380D02*
X1335195Y1015909D01*
X1334165D01*
X1333980Y1016509D01*
Y1016684D01*
X1335380D01*
Y1016509D01*
G37*
G36*
G01X1331727D02*
X1331542Y1015909D01*
X1330512D01*
X1330327Y1016509D01*
Y1016683D01*
X1331727D01*
Y1016509D01*
G37*
G36*
G01X1346470D02*
X1346285Y1015909D01*
X1345255D01*
X1345070Y1016509D01*
Y1016683D01*
X1346470D01*
Y1016509D01*
G37*
G36*
G01X1342780D02*
X1342595Y1015909D01*
X1341565D01*
X1341380Y1016509D01*
Y1016684D01*
X1342780D01*
Y1016509D01*
G37*
G36*
G01X1339080D02*
X1338895Y1015909D01*
X1337865D01*
X1337680Y1016509D01*
Y1016683D01*
X1339080D01*
Y1016509D01*
G37*
G36*
G01X1330303Y1021309D02*
X1330488Y1021909D01*
X1331518D01*
X1331703Y1021309D01*
Y1021135D01*
X1330303D01*
Y1021309D01*
G37*
G36*
G01X1333980Y1021311D02*
X1334165Y1021911D01*
X1335195D01*
X1335380Y1021311D01*
Y1021136D01*
X1333980D01*
Y1021311D01*
G37*
G36*
G01X1345070D02*
X1345255Y1021911D01*
X1346285D01*
X1346470Y1021311D01*
Y1021136D01*
X1345070D01*
Y1021311D01*
G37*
G36*
G01X1341370D02*
X1341555Y1021911D01*
X1342585D01*
X1342770Y1021311D01*
Y1021136D01*
X1341370D01*
Y1021311D01*
G37*
G36*
G01X1337680Y1021309D02*
X1337865Y1021909D01*
X1338895D01*
X1339080Y1021309D01*
Y1021135D01*
X1337680D01*
Y1021309D01*
G37*
G36*
G01X1330303D02*
X1330488Y1021909D01*
X1331518D01*
X1331703Y1021309D01*
Y1021135D01*
X1330303D01*
Y1021309D01*
G37*
G36*
G01X1333980Y1021311D02*
X1334165Y1021911D01*
X1335195D01*
X1335380Y1021311D01*
Y1021136D01*
X1333980D01*
Y1021311D01*
G37*
G36*
G01X1345070D02*
X1345255Y1021911D01*
X1346285D01*
X1346470Y1021311D01*
Y1021136D01*
X1345070D01*
Y1021311D01*
G37*
G36*
G01X1341370D02*
X1341555Y1021911D01*
X1342585D01*
X1342770Y1021311D01*
Y1021136D01*
X1341370D01*
Y1021311D01*
G37*
G36*
G01X1337680Y1021309D02*
X1337865Y1021909D01*
X1338895D01*
X1339080Y1021309D01*
Y1021135D01*
X1337680D01*
Y1021309D01*
G37*
G36*
G01X1332130Y1018107D02*
X1332315Y1018707D01*
X1333345D01*
X1333530Y1018107D01*
Y1017932D01*
X1332130D01*
Y1018107D01*
G37*
G36*
G01X1335887D02*
X1336072Y1018707D01*
X1337102D01*
X1337287Y1018107D01*
Y1017932D01*
X1335887D01*
Y1018107D01*
G37*
G36*
G01X1339554Y1018105D02*
X1339739Y1018705D01*
X1340769D01*
X1340954Y1018105D01*
Y1017931D01*
X1339554D01*
Y1018105D01*
G37*
G36*
G01X1343287Y1018107D02*
X1343472Y1018707D01*
X1344502D01*
X1344687Y1018107D01*
Y1017932D01*
X1343287D01*
Y1018107D01*
G37*
G36*
G01X1332130D02*
X1332315Y1018707D01*
X1333345D01*
X1333530Y1018107D01*
Y1017932D01*
X1332130D01*
Y1018107D01*
G37*
G36*
G01X1335887D02*
X1336072Y1018707D01*
X1337102D01*
X1337287Y1018107D01*
Y1017932D01*
X1335887D01*
Y1018107D01*
G37*
G36*
G01X1339554Y1018105D02*
X1339739Y1018705D01*
X1340769D01*
X1340954Y1018105D01*
Y1017931D01*
X1339554D01*
Y1018105D01*
G37*
G36*
G01X1343287Y1018107D02*
X1343472Y1018707D01*
X1344502D01*
X1344687Y1018107D01*
Y1017932D01*
X1343287D01*
Y1018107D01*
G37*
G36*
G01X1335380Y1022917D02*
X1335195Y1022317D01*
X1334165D01*
X1333980Y1022917D01*
Y1023092D01*
X1335380D01*
Y1022917D01*
G37*
G36*
G01X1331670D02*
X1331485Y1022317D01*
X1330455D01*
X1330270Y1022917D01*
Y1023092D01*
X1331670D01*
Y1022917D01*
G37*
G36*
G01X1339127Y1022919D02*
X1338942Y1022319D01*
X1337912D01*
X1337727Y1022919D01*
Y1023093D01*
X1339127D01*
Y1022919D01*
G37*
G36*
G01X1342770Y1022917D02*
X1342585Y1022317D01*
X1341555D01*
X1341370Y1022917D01*
Y1023092D01*
X1342770D01*
Y1022917D01*
G37*
G36*
G01X1335380D02*
X1335195Y1022317D01*
X1334165D01*
X1333980Y1022917D01*
Y1023092D01*
X1335380D01*
Y1022917D01*
G37*
G36*
G01X1331670D02*
X1331485Y1022317D01*
X1330455D01*
X1330270Y1022917D01*
Y1023092D01*
X1331670D01*
Y1022917D01*
G37*
G36*
G01X1339127Y1022919D02*
X1338942Y1022319D01*
X1337912D01*
X1337727Y1022919D01*
Y1023093D01*
X1339127D01*
Y1022919D01*
G37*
G36*
G01X1342770Y1022917D02*
X1342585Y1022317D01*
X1341555D01*
X1341370Y1022917D01*
Y1023092D01*
X1342770D01*
Y1022917D01*
G37*
G36*
G01X1333970Y1027719D02*
X1334155Y1028319D01*
X1335185D01*
X1335370Y1027719D01*
Y1027545D01*
X1333970D01*
Y1027719D01*
G37*
G36*
G01X1330270D02*
X1330455Y1028319D01*
X1331485D01*
X1331670Y1027719D01*
Y1027545D01*
X1330270D01*
Y1027719D01*
G37*
G36*
G01X1337703D02*
X1337888Y1028319D01*
X1338918D01*
X1339103Y1027719D01*
Y1027544D01*
X1337703D01*
Y1027719D01*
G37*
G36*
G01X1341370D02*
X1341555Y1028319D01*
X1342585D01*
X1342770Y1027719D01*
Y1027545D01*
X1341370D01*
Y1027719D01*
G37*
G36*
G01X1345070D02*
X1345255Y1028319D01*
X1346285D01*
X1346470Y1027719D01*
Y1027545D01*
X1345070D01*
Y1027719D01*
G37*
G36*
G01X1333970D02*
X1334155Y1028319D01*
X1335185D01*
X1335370Y1027719D01*
Y1027545D01*
X1333970D01*
Y1027719D01*
G37*
G36*
G01X1330270D02*
X1330455Y1028319D01*
X1331485D01*
X1331670Y1027719D01*
Y1027545D01*
X1330270D01*
Y1027719D01*
G37*
G36*
G01X1337703D02*
X1337888Y1028319D01*
X1338918D01*
X1339103Y1027719D01*
Y1027544D01*
X1337703D01*
Y1027719D01*
G37*
G36*
G01X1341370D02*
X1341555Y1028319D01*
X1342585D01*
X1342770Y1027719D01*
Y1027545D01*
X1341370D01*
Y1027719D01*
G37*
G36*
G01X1345070D02*
X1345255Y1028319D01*
X1346285D01*
X1346470Y1027719D01*
Y1027545D01*
X1345070D01*
Y1027719D01*
G37*
G36*
G01X1332187Y1024515D02*
X1332372Y1025115D01*
X1333402D01*
X1333587Y1024515D01*
Y1024340D01*
X1332187D01*
Y1024515D01*
G37*
G36*
G01X1335830Y1024513D02*
X1336015Y1025113D01*
X1337045D01*
X1337230Y1024513D01*
Y1024339D01*
X1335830D01*
Y1024513D01*
G37*
G36*
G01X1339577Y1024515D02*
X1339762Y1025115D01*
X1340792D01*
X1340977Y1024515D01*
Y1024340D01*
X1339577D01*
Y1024515D01*
G37*
G36*
G01X1343287D02*
X1343472Y1025115D01*
X1344502D01*
X1344687Y1024515D01*
Y1024340D01*
X1343287D01*
Y1024515D01*
G37*
G36*
G01X1332187D02*
X1332372Y1025115D01*
X1333402D01*
X1333587Y1024515D01*
Y1024340D01*
X1332187D01*
Y1024515D01*
G37*
G36*
G01X1335830Y1024513D02*
X1336015Y1025113D01*
X1337045D01*
X1337230Y1024513D01*
Y1024339D01*
X1335830D01*
Y1024513D01*
G37*
G36*
G01X1339577Y1024515D02*
X1339762Y1025115D01*
X1340792D01*
X1340977Y1024515D01*
Y1024340D01*
X1339577D01*
Y1024515D01*
G37*
G36*
G01X1343287D02*
X1343472Y1025115D01*
X1344502D01*
X1344687Y1024515D01*
Y1024340D01*
X1343287D01*
Y1024515D01*
G37*
G36*
G01X1333587Y1026121D02*
X1333402Y1025521D01*
X1332372D01*
X1332187Y1026121D01*
Y1026296D01*
X1333587D01*
Y1026121D01*
G37*
G36*
G01X1337277Y1026123D02*
X1337092Y1025523D01*
X1336062D01*
X1335877Y1026123D01*
Y1026297D01*
X1337277D01*
Y1026123D01*
G37*
G36*
G01X1340977Y1026121D02*
X1340792Y1025521D01*
X1339762D01*
X1339577Y1026121D01*
Y1026296D01*
X1340977D01*
Y1026121D01*
G37*
G36*
G01X1344687D02*
X1344502Y1025521D01*
X1343472D01*
X1343287Y1026121D01*
Y1026296D01*
X1344687D01*
Y1026121D01*
G37*
G36*
G01X1333587D02*
X1333402Y1025521D01*
X1332372D01*
X1332187Y1026121D01*
Y1026296D01*
X1333587D01*
Y1026121D01*
G37*
G36*
G01X1337277Y1026123D02*
X1337092Y1025523D01*
X1336062D01*
X1335877Y1026123D01*
Y1026297D01*
X1337277D01*
Y1026123D01*
G37*
G36*
G01X1340977Y1026121D02*
X1340792Y1025521D01*
X1339762D01*
X1339577Y1026121D01*
Y1026296D01*
X1340977D01*
Y1026121D01*
G37*
G36*
G01X1344687D02*
X1344502Y1025521D01*
X1343472D01*
X1343287Y1026121D01*
Y1026296D01*
X1344687D01*
Y1026121D01*
G37*
G36*
G01X1333520Y1032531D02*
X1333335Y1031931D01*
X1332305D01*
X1332120Y1032531D01*
Y1032705D01*
X1333520D01*
Y1032531D01*
G37*
G36*
G01X1337277D02*
X1337092Y1031931D01*
X1336062D01*
X1335877Y1032531D01*
Y1032705D01*
X1337277D01*
Y1032531D01*
G37*
G36*
G01X1344687D02*
X1344502Y1031931D01*
X1343472D01*
X1343287Y1032531D01*
Y1032705D01*
X1344687D01*
Y1032531D01*
G37*
G36*
G01X1340987D02*
X1340802Y1031931D01*
X1339772D01*
X1339587Y1032531D01*
Y1032705D01*
X1340987D01*
Y1032531D01*
G37*
G36*
G01X1333520D02*
X1333335Y1031931D01*
X1332305D01*
X1332120Y1032531D01*
Y1032705D01*
X1333520D01*
Y1032531D01*
G37*
G36*
G01X1337277D02*
X1337092Y1031931D01*
X1336062D01*
X1335877Y1032531D01*
Y1032705D01*
X1337277D01*
Y1032531D01*
G37*
G36*
G01X1344687D02*
X1344502Y1031931D01*
X1343472D01*
X1343287Y1032531D01*
Y1032705D01*
X1344687D01*
Y1032531D01*
G37*
G36*
G01X1340987D02*
X1340802Y1031931D01*
X1339772D01*
X1339587Y1032531D01*
Y1032705D01*
X1340987D01*
Y1032531D01*
G37*
G36*
G01X1330327Y1034127D02*
X1330512Y1034727D01*
X1331542D01*
X1331727Y1034127D01*
Y1033953D01*
X1330327D01*
Y1034127D01*
G37*
G36*
G01X1334027D02*
X1334212Y1034727D01*
X1335242D01*
X1335427Y1034127D01*
Y1033952D01*
X1334027D01*
Y1034127D01*
G37*
G36*
G01X1345070D02*
X1345255Y1034727D01*
X1346285D01*
X1346470Y1034127D01*
Y1033953D01*
X1345070D01*
Y1034127D01*
G37*
G36*
G01X1341370D02*
X1341555Y1034727D01*
X1342585D01*
X1342770Y1034127D01*
Y1033953D01*
X1341370D01*
Y1034127D01*
G37*
G36*
G01X1337670D02*
X1337855Y1034727D01*
X1338885D01*
X1339070Y1034127D01*
Y1033953D01*
X1337670D01*
Y1034127D01*
G37*
G36*
G01X1330327D02*
X1330512Y1034727D01*
X1331542D01*
X1331727Y1034127D01*
Y1033953D01*
X1330327D01*
Y1034127D01*
G37*
G36*
G01X1334027D02*
X1334212Y1034727D01*
X1335242D01*
X1335427Y1034127D01*
Y1033952D01*
X1334027D01*
Y1034127D01*
G37*
G36*
G01X1345070D02*
X1345255Y1034727D01*
X1346285D01*
X1346470Y1034127D01*
Y1033953D01*
X1345070D01*
Y1034127D01*
G37*
G36*
G01X1341370D02*
X1341555Y1034727D01*
X1342585D01*
X1342770Y1034127D01*
Y1033953D01*
X1341370D01*
Y1034127D01*
G37*
G36*
G01X1337670D02*
X1337855Y1034727D01*
X1338885D01*
X1339070Y1034127D01*
Y1033953D01*
X1337670D01*
Y1034127D01*
G37*
G36*
G01X1332153Y1030923D02*
X1332338Y1031523D01*
X1333368D01*
X1333553Y1030923D01*
Y1030748D01*
X1332153D01*
Y1030923D01*
G37*
G36*
G01X1335877D02*
X1336062Y1031523D01*
X1337092D01*
X1337277Y1030923D01*
Y1030749D01*
X1335877D01*
Y1030923D01*
G37*
G36*
G01X1339587D02*
X1339772Y1031523D01*
X1340802D01*
X1340987Y1030923D01*
Y1030749D01*
X1339587D01*
Y1030923D01*
G37*
G36*
G01X1343287D02*
X1343472Y1031523D01*
X1344502D01*
X1344687Y1030923D01*
Y1030749D01*
X1343287D01*
Y1030923D01*
G37*
G36*
G01X1332153D02*
X1332338Y1031523D01*
X1333368D01*
X1333553Y1030923D01*
Y1030748D01*
X1332153D01*
Y1030923D01*
G37*
G36*
G01X1335877D02*
X1336062Y1031523D01*
X1337092D01*
X1337277Y1030923D01*
Y1030749D01*
X1335877D01*
Y1030923D01*
G37*
G36*
G01X1339587D02*
X1339772Y1031523D01*
X1340802D01*
X1340987Y1030923D01*
Y1030749D01*
X1339587D01*
Y1030923D01*
G37*
G36*
G01X1343287D02*
X1343472Y1031523D01*
X1344502D01*
X1344687Y1030923D01*
Y1030749D01*
X1343287D01*
Y1030923D01*
G37*
G36*
G01X1333980Y1040537D02*
X1334165Y1041137D01*
X1335195D01*
X1335380Y1040537D01*
Y1040362D01*
X1333980D01*
Y1040537D01*
G37*
G36*
G01X1330303Y1040535D02*
X1330488Y1041135D01*
X1331518D01*
X1331703Y1040535D01*
Y1040361D01*
X1330303D01*
Y1040535D01*
G37*
G36*
G01X1337680D02*
X1337865Y1041135D01*
X1338895D01*
X1339080Y1040535D01*
Y1040361D01*
X1337680D01*
Y1040535D01*
G37*
G36*
G01X1341370Y1040537D02*
X1341555Y1041137D01*
X1342585D01*
X1342770Y1040537D01*
Y1040362D01*
X1341370D01*
Y1040537D01*
G37*
G36*
G01X1345070D02*
X1345255Y1041137D01*
X1346285D01*
X1346470Y1040537D01*
Y1040362D01*
X1345070D01*
Y1040537D01*
G37*
G36*
G01X1333980D02*
X1334165Y1041137D01*
X1335195D01*
X1335380Y1040537D01*
Y1040362D01*
X1333980D01*
Y1040537D01*
G37*
G36*
G01X1330303Y1040535D02*
X1330488Y1041135D01*
X1331518D01*
X1331703Y1040535D01*
Y1040361D01*
X1330303D01*
Y1040535D01*
G37*
G36*
G01X1337680D02*
X1337865Y1041135D01*
X1338895D01*
X1339080Y1040535D01*
Y1040361D01*
X1337680D01*
Y1040535D01*
G37*
G36*
G01X1341370Y1040537D02*
X1341555Y1041137D01*
X1342585D01*
X1342770Y1040537D01*
Y1040362D01*
X1341370D01*
Y1040537D01*
G37*
G36*
G01X1345070D02*
X1345255Y1041137D01*
X1346285D01*
X1346470Y1040537D01*
Y1040362D01*
X1345070D01*
Y1040537D01*
G37*
G36*
G01X1332140Y1037331D02*
X1332325Y1037931D01*
X1333355D01*
X1333540Y1037331D01*
Y1037156D01*
X1332140D01*
Y1037331D01*
G37*
G36*
G01X1343240D02*
X1343425Y1037931D01*
X1344455D01*
X1344640Y1037331D01*
Y1037156D01*
X1343240D01*
Y1037331D01*
G37*
G36*
G01X1339540D02*
X1339725Y1037931D01*
X1340755D01*
X1340940Y1037331D01*
Y1037156D01*
X1339540D01*
Y1037331D01*
G37*
G36*
G01X1335840D02*
X1336025Y1037931D01*
X1337055D01*
X1337240Y1037331D01*
Y1037156D01*
X1335840D01*
Y1037331D01*
G37*
G36*
G01X1332140D02*
X1332325Y1037931D01*
X1333355D01*
X1333540Y1037331D01*
Y1037156D01*
X1332140D01*
Y1037331D01*
G37*
G36*
G01X1343240D02*
X1343425Y1037931D01*
X1344455D01*
X1344640Y1037331D01*
Y1037156D01*
X1343240D01*
Y1037331D01*
G37*
G36*
G01X1339540D02*
X1339725Y1037931D01*
X1340755D01*
X1340940Y1037331D01*
Y1037156D01*
X1339540D01*
Y1037331D01*
G37*
G36*
G01X1335840D02*
X1336025Y1037931D01*
X1337055D01*
X1337240Y1037331D01*
Y1037156D01*
X1335840D01*
Y1037331D01*
G37*
G36*
G01X1333577Y1038939D02*
X1333392Y1038339D01*
X1332362D01*
X1332177Y1038939D01*
Y1039114D01*
X1333577D01*
Y1038939D01*
G37*
G36*
G01X1340987D02*
X1340802Y1038339D01*
X1339772D01*
X1339587Y1038939D01*
Y1039114D01*
X1340987D01*
Y1038939D01*
G37*
G36*
G01X1344687D02*
X1344502Y1038339D01*
X1343472D01*
X1343287Y1038939D01*
Y1039114D01*
X1344687D01*
Y1038939D01*
G37*
G36*
G01X1337254Y1038941D02*
X1337069Y1038341D01*
X1336039D01*
X1335854Y1038941D01*
Y1039115D01*
X1337254D01*
Y1038941D01*
G37*
G36*
G01X1333577Y1038939D02*
X1333392Y1038339D01*
X1332362D01*
X1332177Y1038939D01*
Y1039114D01*
X1333577D01*
Y1038939D01*
G37*
G36*
G01X1340987D02*
X1340802Y1038339D01*
X1339772D01*
X1339587Y1038939D01*
Y1039114D01*
X1340987D01*
Y1038939D01*
G37*
G36*
G01X1344687D02*
X1344502Y1038339D01*
X1343472D01*
X1343287Y1038939D01*
Y1039114D01*
X1344687D01*
Y1038939D01*
G37*
G36*
G01X1337254Y1038941D02*
X1337069Y1038341D01*
X1336039D01*
X1335854Y1038941D01*
Y1039115D01*
X1337254D01*
Y1038941D01*
G37*
G36*
G01X1335417Y1035737D02*
X1335232Y1035137D01*
X1334202D01*
X1334017Y1035737D01*
Y1035911D01*
X1335417D01*
Y1035737D01*
G37*
G36*
G01X1331712Y1035735D02*
X1331527Y1035135D01*
X1330497D01*
X1330312Y1035735D01*
Y1035910D01*
X1331712D01*
Y1035735D01*
G37*
G36*
G01X1339117Y1035737D02*
X1338932Y1035137D01*
X1337902D01*
X1337717Y1035737D01*
Y1035911D01*
X1339117D01*
Y1035737D01*
G37*
G36*
G01X1346517D02*
X1346332Y1035137D01*
X1345302D01*
X1345117Y1035737D01*
Y1035911D01*
X1346517D01*
Y1035737D01*
G37*
G36*
G01X1342817D02*
X1342632Y1035137D01*
X1341602D01*
X1341417Y1035737D01*
Y1035911D01*
X1342817D01*
Y1035737D01*
G37*
G36*
G01X1335417D02*
X1335232Y1035137D01*
X1334202D01*
X1334017Y1035737D01*
Y1035911D01*
X1335417D01*
Y1035737D01*
G37*
G36*
G01X1331712Y1035735D02*
X1331527Y1035135D01*
X1330497D01*
X1330312Y1035735D01*
Y1035910D01*
X1331712D01*
Y1035735D01*
G37*
G36*
G01X1339117Y1035737D02*
X1338932Y1035137D01*
X1337902D01*
X1337717Y1035737D01*
Y1035911D01*
X1339117D01*
Y1035737D01*
G37*
G36*
G01X1346517D02*
X1346332Y1035137D01*
X1345302D01*
X1345117Y1035737D01*
Y1035911D01*
X1346517D01*
Y1035737D01*
G37*
G36*
G01X1342817D02*
X1342632Y1035137D01*
X1341602D01*
X1341417Y1035737D01*
Y1035911D01*
X1342817D01*
Y1035737D01*
G37*
G36*
G01X1333577Y1045347D02*
X1333392Y1044747D01*
X1332362D01*
X1332177Y1045347D01*
Y1045522D01*
X1333577D01*
Y1045347D01*
G37*
G36*
G01X1337277Y1045349D02*
X1337092Y1044749D01*
X1336062D01*
X1335877Y1045349D01*
Y1045523D01*
X1337277D01*
Y1045349D01*
G37*
G36*
G01X1340977Y1045347D02*
X1340792Y1044747D01*
X1339762D01*
X1339577Y1045347D01*
Y1045522D01*
X1340977D01*
Y1045347D01*
G37*
G36*
G01X1344687D02*
X1344502Y1044747D01*
X1343472D01*
X1343287Y1045347D01*
Y1045522D01*
X1344687D01*
Y1045347D01*
G37*
G36*
G01X1333577D02*
X1333392Y1044747D01*
X1332362D01*
X1332177Y1045347D01*
Y1045522D01*
X1333577D01*
Y1045347D01*
G37*
G36*
G01X1337277Y1045349D02*
X1337092Y1044749D01*
X1336062D01*
X1335877Y1045349D01*
Y1045523D01*
X1337277D01*
Y1045349D01*
G37*
G36*
G01X1340977Y1045347D02*
X1340792Y1044747D01*
X1339762D01*
X1339577Y1045347D01*
Y1045522D01*
X1340977D01*
Y1045347D01*
G37*
G36*
G01X1344687D02*
X1344502Y1044747D01*
X1343472D01*
X1343287Y1045347D01*
Y1045522D01*
X1344687D01*
Y1045347D01*
G37*
G36*
G01X1332177Y1043741D02*
X1332362Y1044341D01*
X1333392D01*
X1333577Y1043741D01*
Y1043566D01*
X1332177D01*
Y1043741D01*
G37*
G36*
G01X1335830Y1043739D02*
X1336015Y1044339D01*
X1337045D01*
X1337230Y1043739D01*
Y1043565D01*
X1335830D01*
Y1043739D01*
G37*
G36*
G01X1339577Y1043741D02*
X1339762Y1044341D01*
X1340792D01*
X1340977Y1043741D01*
Y1043566D01*
X1339577D01*
Y1043741D01*
G37*
G36*
G01X1343287D02*
X1343472Y1044341D01*
X1344502D01*
X1344687Y1043741D01*
Y1043566D01*
X1343287D01*
Y1043741D01*
G37*
G36*
G01X1332177D02*
X1332362Y1044341D01*
X1333392D01*
X1333577Y1043741D01*
Y1043566D01*
X1332177D01*
Y1043741D01*
G37*
G36*
G01X1335830Y1043739D02*
X1336015Y1044339D01*
X1337045D01*
X1337230Y1043739D01*
Y1043565D01*
X1335830D01*
Y1043739D01*
G37*
G36*
G01X1339577Y1043741D02*
X1339762Y1044341D01*
X1340792D01*
X1340977Y1043741D01*
Y1043566D01*
X1339577D01*
Y1043741D01*
G37*
G36*
G01X1343287D02*
X1343472Y1044341D01*
X1344502D01*
X1344687Y1043741D01*
Y1043566D01*
X1343287D01*
Y1043741D01*
G37*
G36*
G01X1333970Y1046945D02*
X1334155Y1047545D01*
X1335185D01*
X1335370Y1046945D01*
Y1046770D01*
X1333970D01*
Y1046945D01*
G37*
G36*
G01X1330303Y1046943D02*
X1330488Y1047543D01*
X1331518D01*
X1331703Y1046943D01*
Y1046769D01*
X1330303D01*
Y1046943D01*
G37*
G36*
G01X1337703D02*
X1337888Y1047543D01*
X1338918D01*
X1339103Y1046943D01*
Y1046769D01*
X1337703D01*
Y1046943D01*
G37*
G36*
G01X1341370Y1046945D02*
X1341555Y1047545D01*
X1342585D01*
X1342770Y1046945D01*
Y1046771D01*
X1341370D01*
Y1046945D01*
G37*
G36*
G01X1345072D02*
X1345257Y1047545D01*
X1346287D01*
X1346472Y1046945D01*
Y1046770D01*
X1345072D01*
Y1046945D01*
G37*
G36*
G01X1333970D02*
X1334155Y1047545D01*
X1335185D01*
X1335370Y1046945D01*
Y1046770D01*
X1333970D01*
Y1046945D01*
G37*
G36*
G01X1330303Y1046943D02*
X1330488Y1047543D01*
X1331518D01*
X1331703Y1046943D01*
Y1046769D01*
X1330303D01*
Y1046943D01*
G37*
G36*
G01X1337703D02*
X1337888Y1047543D01*
X1338918D01*
X1339103Y1046943D01*
Y1046769D01*
X1337703D01*
Y1046943D01*
G37*
G36*
G01X1341370Y1046945D02*
X1341555Y1047545D01*
X1342585D01*
X1342770Y1046945D01*
Y1046771D01*
X1341370D01*
Y1046945D01*
G37*
G36*
G01X1345072D02*
X1345257Y1047545D01*
X1346287D01*
X1346472Y1046945D01*
Y1046770D01*
X1345072D01*
Y1046945D01*
G37*
G36*
G01X1331703Y1042145D02*
X1331518Y1041545D01*
X1330488D01*
X1330303Y1042145D01*
Y1042319D01*
X1331703D01*
Y1042145D01*
G37*
G36*
G01X1335380Y1042143D02*
X1335195Y1041543D01*
X1334165D01*
X1333980Y1042143D01*
Y1042318D01*
X1335380D01*
Y1042143D01*
G37*
G36*
G01X1346470D02*
X1346285Y1041543D01*
X1345255D01*
X1345070Y1042143D01*
Y1042318D01*
X1346470D01*
Y1042143D01*
G37*
G36*
G01X1339127Y1042145D02*
X1338942Y1041545D01*
X1337912D01*
X1337727Y1042145D01*
Y1042319D01*
X1339127D01*
Y1042145D01*
G37*
G36*
G01X1342770Y1042143D02*
X1342585Y1041543D01*
X1341555D01*
X1341370Y1042143D01*
Y1042318D01*
X1342770D01*
Y1042143D01*
G37*
G36*
G01X1331703Y1042145D02*
X1331518Y1041545D01*
X1330488D01*
X1330303Y1042145D01*
Y1042319D01*
X1331703D01*
Y1042145D01*
G37*
G36*
G01X1335380Y1042143D02*
X1335195Y1041543D01*
X1334165D01*
X1333980Y1042143D01*
Y1042318D01*
X1335380D01*
Y1042143D01*
G37*
G36*
G01X1346470D02*
X1346285Y1041543D01*
X1345255D01*
X1345070Y1042143D01*
Y1042318D01*
X1346470D01*
Y1042143D01*
G37*
G36*
G01X1339127Y1042145D02*
X1338942Y1041545D01*
X1337912D01*
X1337727Y1042145D01*
Y1042319D01*
X1339127D01*
Y1042145D01*
G37*
G36*
G01X1342770Y1042143D02*
X1342585Y1041543D01*
X1341555D01*
X1341370Y1042143D01*
Y1042318D01*
X1342770D01*
Y1042143D01*
G37*
G36*
G01X1337680Y1059761D02*
X1337865Y1060361D01*
X1338895D01*
X1339080Y1059761D01*
Y1059586D01*
X1337680D01*
Y1059761D01*
G37*
G36*
G01X1341370D02*
X1341555Y1060361D01*
X1342585D01*
X1342770Y1059761D01*
Y1059587D01*
X1341370D01*
Y1059761D01*
G37*
G36*
G01X1345070D02*
X1345255Y1060361D01*
X1346285D01*
X1346470Y1059761D01*
Y1059587D01*
X1345070D01*
Y1059761D01*
G37*
G36*
G01X1337680D02*
X1337865Y1060361D01*
X1338895D01*
X1339080Y1059761D01*
Y1059586D01*
X1337680D01*
Y1059761D01*
G37*
G36*
G01X1341370D02*
X1341555Y1060361D01*
X1342585D01*
X1342770Y1059761D01*
Y1059587D01*
X1341370D01*
Y1059761D01*
G37*
G36*
G01X1345070D02*
X1345255Y1060361D01*
X1346285D01*
X1346470Y1059761D01*
Y1059587D01*
X1345070D01*
Y1059761D01*
G37*
G36*
G01X1330303D02*
X1330488Y1060361D01*
X1331518D01*
X1331703Y1059761D01*
Y1059586D01*
X1330303D01*
Y1059761D01*
G37*
G36*
G01X1333980D02*
X1334165Y1060361D01*
X1335195D01*
X1335380Y1059761D01*
Y1059587D01*
X1333980D01*
Y1059761D01*
G37*
G36*
G01X1330303D02*
X1330488Y1060361D01*
X1331518D01*
X1331703Y1059761D01*
Y1059586D01*
X1330303D01*
Y1059761D01*
G37*
G36*
G01X1333980D02*
X1334165Y1060361D01*
X1335195D01*
X1335380Y1059761D01*
Y1059587D01*
X1333980D01*
Y1059761D01*
G37*
G36*
G01X1332130Y1056557D02*
X1332315Y1057157D01*
X1333345D01*
X1333530Y1056557D01*
Y1056383D01*
X1332130D01*
Y1056557D01*
G37*
G36*
G01X1335887D02*
X1336072Y1057157D01*
X1337102D01*
X1337287Y1056557D01*
Y1056383D01*
X1335887D01*
Y1056557D01*
G37*
G36*
G01X1339587D02*
X1339772Y1057157D01*
X1340802D01*
X1340987Y1056557D01*
Y1056383D01*
X1339587D01*
Y1056557D01*
G37*
G36*
G01X1343287D02*
X1343472Y1057157D01*
X1344502D01*
X1344687Y1056557D01*
Y1056383D01*
X1343287D01*
Y1056557D01*
G37*
G36*
G01X1332130D02*
X1332315Y1057157D01*
X1333345D01*
X1333530Y1056557D01*
Y1056383D01*
X1332130D01*
Y1056557D01*
G37*
G36*
G01X1335887D02*
X1336072Y1057157D01*
X1337102D01*
X1337287Y1056557D01*
Y1056383D01*
X1335887D01*
Y1056557D01*
G37*
G36*
G01X1339587D02*
X1339772Y1057157D01*
X1340802D01*
X1340987Y1056557D01*
Y1056383D01*
X1339587D01*
Y1056557D01*
G37*
G36*
G01X1343287D02*
X1343472Y1057157D01*
X1344502D01*
X1344687Y1056557D01*
Y1056383D01*
X1343287D01*
Y1056557D01*
G37*
G36*
G01X1333577Y1058165D02*
X1333392Y1057565D01*
X1332362D01*
X1332177Y1058165D01*
Y1058339D01*
X1333577D01*
Y1058165D01*
G37*
G36*
G01X1337254D02*
X1337069Y1057565D01*
X1336039D01*
X1335854Y1058165D01*
Y1058340D01*
X1337254D01*
Y1058165D01*
G37*
G36*
G01X1340987D02*
X1340802Y1057565D01*
X1339772D01*
X1339587Y1058165D01*
Y1058339D01*
X1340987D01*
Y1058165D01*
G37*
G36*
G01X1344687D02*
X1344502Y1057565D01*
X1343472D01*
X1343287Y1058165D01*
Y1058339D01*
X1344687D01*
Y1058165D01*
G37*
G36*
G01X1333577D02*
X1333392Y1057565D01*
X1332362D01*
X1332177Y1058165D01*
Y1058339D01*
X1333577D01*
Y1058165D01*
G37*
G36*
G01X1337254D02*
X1337069Y1057565D01*
X1336039D01*
X1335854Y1058165D01*
Y1058340D01*
X1337254D01*
Y1058165D01*
G37*
G36*
G01X1340987D02*
X1340802Y1057565D01*
X1339772D01*
X1339587Y1058165D01*
Y1058339D01*
X1340987D01*
Y1058165D01*
G37*
G36*
G01X1344687D02*
X1344502Y1057565D01*
X1343472D01*
X1343287Y1058165D01*
Y1058339D01*
X1344687D01*
Y1058165D01*
G37*
G36*
G01X1331727Y1054961D02*
X1331542Y1054361D01*
X1330512D01*
X1330327Y1054961D01*
Y1055135D01*
X1331727D01*
Y1054961D01*
G37*
G36*
G01X1335380D02*
X1335195Y1054361D01*
X1334165D01*
X1333980Y1054961D01*
Y1055136D01*
X1335380D01*
Y1054961D01*
G37*
G36*
G01X1339070D02*
X1338885Y1054361D01*
X1337855D01*
X1337670Y1054961D01*
Y1055135D01*
X1339070D01*
Y1054961D01*
G37*
G36*
G01X1342770D02*
X1342585Y1054361D01*
X1341555D01*
X1341370Y1054961D01*
Y1055135D01*
X1342770D01*
Y1054961D01*
G37*
G36*
G01X1346470D02*
X1346285Y1054361D01*
X1345255D01*
X1345070Y1054961D01*
Y1055135D01*
X1346470D01*
Y1054961D01*
G37*
G36*
G01X1331727D02*
X1331542Y1054361D01*
X1330512D01*
X1330327Y1054961D01*
Y1055135D01*
X1331727D01*
Y1054961D01*
G37*
G36*
G01X1335380D02*
X1335195Y1054361D01*
X1334165D01*
X1333980Y1054961D01*
Y1055136D01*
X1335380D01*
Y1054961D01*
G37*
G36*
G01X1339070D02*
X1338885Y1054361D01*
X1337855D01*
X1337670Y1054961D01*
Y1055135D01*
X1339070D01*
Y1054961D01*
G37*
G36*
G01X1342770D02*
X1342585Y1054361D01*
X1341555D01*
X1341370Y1054961D01*
Y1055135D01*
X1342770D01*
Y1054961D01*
G37*
G36*
G01X1346470D02*
X1346285Y1054361D01*
X1345255D01*
X1345070Y1054961D01*
Y1055135D01*
X1346470D01*
Y1054961D01*
G37*
G36*
G01X1334027Y1053353D02*
X1334212Y1053953D01*
X1335242D01*
X1335427Y1053353D01*
Y1053178D01*
X1334027D01*
Y1053353D01*
G37*
G36*
G01X1330327D02*
X1330512Y1053953D01*
X1331542D01*
X1331727Y1053353D01*
Y1053179D01*
X1330327D01*
Y1053353D01*
G37*
G36*
G01X1337670D02*
X1337855Y1053953D01*
X1338885D01*
X1339070Y1053353D01*
Y1053179D01*
X1337670D01*
Y1053353D01*
G37*
G36*
G01X1345070D02*
X1345255Y1053953D01*
X1346285D01*
X1346470Y1053353D01*
Y1053179D01*
X1345070D01*
Y1053353D01*
G37*
G36*
G01X1341370D02*
X1341555Y1053953D01*
X1342585D01*
X1342770Y1053353D01*
Y1053179D01*
X1341370D01*
Y1053353D01*
G37*
G36*
G01X1334027D02*
X1334212Y1053953D01*
X1335242D01*
X1335427Y1053353D01*
Y1053178D01*
X1334027D01*
Y1053353D01*
G37*
G36*
G01X1330327D02*
X1330512Y1053953D01*
X1331542D01*
X1331727Y1053353D01*
Y1053179D01*
X1330327D01*
Y1053353D01*
G37*
G36*
G01X1337670D02*
X1337855Y1053953D01*
X1338885D01*
X1339070Y1053353D01*
Y1053179D01*
X1337670D01*
Y1053353D01*
G37*
G36*
G01X1345070D02*
X1345255Y1053953D01*
X1346285D01*
X1346470Y1053353D01*
Y1053179D01*
X1345070D01*
Y1053353D01*
G37*
G36*
G01X1341370D02*
X1341555Y1053953D01*
X1342585D01*
X1342770Y1053353D01*
Y1053179D01*
X1341370D01*
Y1053353D01*
G37*
G36*
G01X1332153Y1050149D02*
X1332338Y1050749D01*
X1333368D01*
X1333553Y1050149D01*
Y1049974D01*
X1332153D01*
Y1050149D01*
G37*
G36*
G01X1343287D02*
X1343472Y1050749D01*
X1344502D01*
X1344687Y1050149D01*
Y1049975D01*
X1343287D01*
Y1050149D01*
G37*
G36*
G01X1339587D02*
X1339772Y1050749D01*
X1340802D01*
X1340987Y1050149D01*
Y1049975D01*
X1339587D01*
Y1050149D01*
G37*
G36*
G01X1335877D02*
X1336062Y1050749D01*
X1337092D01*
X1337277Y1050149D01*
Y1049975D01*
X1335877D01*
Y1050149D01*
G37*
G36*
G01X1332153D02*
X1332338Y1050749D01*
X1333368D01*
X1333553Y1050149D01*
Y1049974D01*
X1332153D01*
Y1050149D01*
G37*
G36*
G01X1343287D02*
X1343472Y1050749D01*
X1344502D01*
X1344687Y1050149D01*
Y1049975D01*
X1343287D01*
Y1050149D01*
G37*
G36*
G01X1339587D02*
X1339772Y1050749D01*
X1340802D01*
X1340987Y1050149D01*
Y1049975D01*
X1339587D01*
Y1050149D01*
G37*
G36*
G01X1335877D02*
X1336062Y1050749D01*
X1337092D01*
X1337277Y1050149D01*
Y1049975D01*
X1335877D01*
Y1050149D01*
G37*
G36*
G01X1333520Y1051755D02*
X1333335Y1051155D01*
X1332305D01*
X1332120Y1051755D01*
Y1051930D01*
X1333520D01*
Y1051755D01*
G37*
G36*
G01X1344687D02*
X1344502Y1051155D01*
X1343472D01*
X1343287Y1051755D01*
Y1051930D01*
X1344687D01*
Y1051755D01*
G37*
G36*
G01X1340987D02*
X1340802Y1051155D01*
X1339772D01*
X1339587Y1051755D01*
Y1051930D01*
X1340987D01*
Y1051755D01*
G37*
G36*
G01X1337277D02*
X1337092Y1051155D01*
X1336062D01*
X1335877Y1051755D01*
Y1051930D01*
X1337277D01*
Y1051755D01*
G37*
G36*
G01X1333520D02*
X1333335Y1051155D01*
X1332305D01*
X1332120Y1051755D01*
Y1051930D01*
X1333520D01*
Y1051755D01*
G37*
G36*
G01X1344687D02*
X1344502Y1051155D01*
X1343472D01*
X1343287Y1051755D01*
Y1051930D01*
X1344687D01*
Y1051755D01*
G37*
G36*
G01X1340987D02*
X1340802Y1051155D01*
X1339772D01*
X1339587Y1051755D01*
Y1051930D01*
X1340987D01*
Y1051755D01*
G37*
G36*
G01X1337277D02*
X1337092Y1051155D01*
X1336062D01*
X1335877Y1051755D01*
Y1051930D01*
X1337277D01*
Y1051755D01*
G37*
G36*
G01X1335403Y1048553D02*
X1335218Y1047953D01*
X1334188D01*
X1334003Y1048553D01*
Y1048727D01*
X1335403D01*
Y1048553D01*
G37*
G36*
G01X1331703D02*
X1331518Y1047953D01*
X1330488D01*
X1330303Y1048553D01*
Y1048727D01*
X1331703D01*
Y1048553D01*
G37*
G36*
G01X1346470Y1048551D02*
X1346285Y1047951D01*
X1345255D01*
X1345070Y1048551D01*
Y1048726D01*
X1346470D01*
Y1048551D01*
G37*
G36*
G01X1342770D02*
X1342585Y1047951D01*
X1341555D01*
X1341370Y1048551D01*
Y1048726D01*
X1342770D01*
Y1048551D01*
G37*
G36*
G01X1339070D02*
X1338885Y1047951D01*
X1337855D01*
X1337670Y1048551D01*
Y1048726D01*
X1339070D01*
Y1048551D01*
G37*
G36*
G01X1335403Y1048553D02*
X1335218Y1047953D01*
X1334188D01*
X1334003Y1048553D01*
Y1048727D01*
X1335403D01*
Y1048553D01*
G37*
G36*
G01X1331703D02*
X1331518Y1047953D01*
X1330488D01*
X1330303Y1048553D01*
Y1048727D01*
X1331703D01*
Y1048553D01*
G37*
G36*
G01X1346470Y1048551D02*
X1346285Y1047951D01*
X1345255D01*
X1345070Y1048551D01*
Y1048726D01*
X1346470D01*
Y1048551D01*
G37*
G36*
G01X1342770D02*
X1342585Y1047951D01*
X1341555D01*
X1341370Y1048551D01*
Y1048726D01*
X1342770D01*
Y1048551D01*
G37*
G36*
G01X1339070D02*
X1338885Y1047951D01*
X1337855D01*
X1337670Y1048551D01*
Y1048726D01*
X1339070D01*
Y1048551D01*
G37*
G36*
G01X1343287Y1062967D02*
X1343472Y1063567D01*
X1344502D01*
X1344687Y1062967D01*
Y1062792D01*
X1343287D01*
Y1062967D01*
G37*
G36*
G01X1335830Y1062965D02*
X1336015Y1063565D01*
X1337045D01*
X1337230Y1062965D01*
Y1062791D01*
X1335830D01*
Y1062965D01*
G37*
G36*
G01X1339577Y1062967D02*
X1339762Y1063567D01*
X1340792D01*
X1340977Y1062967D01*
Y1062792D01*
X1339577D01*
Y1062967D01*
G37*
G36*
G01X1343287D02*
X1343472Y1063567D01*
X1344502D01*
X1344687Y1062967D01*
Y1062792D01*
X1343287D01*
Y1062967D01*
G37*
G36*
G01X1335830Y1062965D02*
X1336015Y1063565D01*
X1337045D01*
X1337230Y1062965D01*
Y1062791D01*
X1335830D01*
Y1062965D01*
G37*
G36*
G01X1339577Y1062967D02*
X1339762Y1063567D01*
X1340792D01*
X1340977Y1062967D01*
Y1062792D01*
X1339577D01*
Y1062967D01*
G37*
G36*
G01X1332177D02*
X1332362Y1063567D01*
X1333392D01*
X1333577Y1062967D01*
Y1062792D01*
X1332177D01*
Y1062967D01*
G37*
G36*
G01D02*
X1332362Y1063567D01*
X1333392D01*
X1333577Y1062967D01*
Y1062792D01*
X1332177D01*
Y1062967D01*
G37*
G36*
G01X1339127Y1061369D02*
X1338942Y1060769D01*
X1337912D01*
X1337727Y1061369D01*
Y1061544D01*
X1339127D01*
Y1061369D01*
G37*
G36*
G01X1342770D02*
X1342585Y1060769D01*
X1341555D01*
X1341370Y1061369D01*
Y1061543D01*
X1342770D01*
Y1061369D01*
G37*
G36*
G01X1346470D02*
X1346285Y1060769D01*
X1345255D01*
X1345070Y1061369D01*
Y1061543D01*
X1346470D01*
Y1061369D01*
G37*
G36*
G01X1339127D02*
X1338942Y1060769D01*
X1337912D01*
X1337727Y1061369D01*
Y1061544D01*
X1339127D01*
Y1061369D01*
G37*
G36*
G01X1342770D02*
X1342585Y1060769D01*
X1341555D01*
X1341370Y1061369D01*
Y1061543D01*
X1342770D01*
Y1061369D01*
G37*
G36*
G01X1346470D02*
X1346285Y1060769D01*
X1345255D01*
X1345070Y1061369D01*
Y1061543D01*
X1346470D01*
Y1061369D01*
G37*
G36*
G01X1335380D02*
X1335195Y1060769D01*
X1334165D01*
X1333980Y1061369D01*
Y1061543D01*
X1335380D01*
Y1061369D01*
G37*
G36*
G01X1331703D02*
X1331518Y1060769D01*
X1330488D01*
X1330303Y1061369D01*
Y1061544D01*
X1331703D01*
Y1061369D01*
G37*
G36*
G01X1335380D02*
X1335195Y1060769D01*
X1334165D01*
X1333980Y1061369D01*
Y1061543D01*
X1335380D01*
Y1061369D01*
G37*
G36*
G01X1331703D02*
X1331518Y1060769D01*
X1330488D01*
X1330303Y1061369D01*
Y1061544D01*
X1331703D01*
Y1061369D01*
G37*
G36*
G01X1333520Y1070981D02*
X1333335Y1070381D01*
X1332305D01*
X1332120Y1070981D01*
Y1071156D01*
X1333520D01*
Y1070981D01*
G37*
G36*
G01X1340987D02*
X1340802Y1070381D01*
X1339772D01*
X1339587Y1070981D01*
Y1071156D01*
X1340987D01*
Y1070981D01*
G37*
G36*
G01X1344687D02*
X1344502Y1070381D01*
X1343472D01*
X1343287Y1070981D01*
Y1071156D01*
X1344687D01*
Y1070981D01*
G37*
G36*
G01X1337277D02*
X1337092Y1070381D01*
X1336062D01*
X1335877Y1070981D01*
Y1071156D01*
X1337277D01*
Y1070981D01*
G37*
G36*
G01X1333520D02*
X1333335Y1070381D01*
X1332305D01*
X1332120Y1070981D01*
Y1071156D01*
X1333520D01*
Y1070981D01*
G37*
G36*
G01X1340987D02*
X1340802Y1070381D01*
X1339772D01*
X1339587Y1070981D01*
Y1071156D01*
X1340987D01*
Y1070981D01*
G37*
G36*
G01X1344687D02*
X1344502Y1070381D01*
X1343472D01*
X1343287Y1070981D01*
Y1071156D01*
X1344687D01*
Y1070981D01*
G37*
G36*
G01X1337277D02*
X1337092Y1070381D01*
X1336062D01*
X1335877Y1070981D01*
Y1071156D01*
X1337277D01*
Y1070981D01*
G37*
G36*
G01X1331703Y1067779D02*
X1331518Y1067179D01*
X1330488D01*
X1330303Y1067779D01*
Y1067953D01*
X1331703D01*
Y1067779D01*
G37*
G36*
G01X1335403D02*
X1335218Y1067179D01*
X1334188D01*
X1334003Y1067779D01*
Y1067953D01*
X1335403D01*
Y1067779D01*
G37*
G36*
G01X1339070Y1067777D02*
X1338885Y1067177D01*
X1337855D01*
X1337670Y1067777D01*
Y1067952D01*
X1339070D01*
Y1067777D01*
G37*
G36*
G01X1342770D02*
X1342585Y1067177D01*
X1341555D01*
X1341370Y1067777D01*
Y1067952D01*
X1342770D01*
Y1067777D01*
G37*
G36*
G01X1346480D02*
X1346295Y1067177D01*
X1345265D01*
X1345080Y1067777D01*
Y1067952D01*
X1346480D01*
Y1067777D01*
G37*
G36*
G01X1331703Y1067779D02*
X1331518Y1067179D01*
X1330488D01*
X1330303Y1067779D01*
Y1067953D01*
X1331703D01*
Y1067779D01*
G37*
G36*
G01X1335403D02*
X1335218Y1067179D01*
X1334188D01*
X1334003Y1067779D01*
Y1067953D01*
X1335403D01*
Y1067779D01*
G37*
G36*
G01X1339070Y1067777D02*
X1338885Y1067177D01*
X1337855D01*
X1337670Y1067777D01*
Y1067952D01*
X1339070D01*
Y1067777D01*
G37*
G36*
G01X1342770D02*
X1342585Y1067177D01*
X1341555D01*
X1341370Y1067777D01*
Y1067952D01*
X1342770D01*
Y1067777D01*
G37*
G36*
G01X1346480D02*
X1346295Y1067177D01*
X1345265D01*
X1345080Y1067777D01*
Y1067952D01*
X1346480D01*
Y1067777D01*
G37*
G36*
G01X1330327Y1072579D02*
X1330512Y1073179D01*
X1331542D01*
X1331727Y1072579D01*
Y1072405D01*
X1330327D01*
Y1072579D01*
G37*
G36*
G01X1334027D02*
X1334212Y1073179D01*
X1335242D01*
X1335427Y1072579D01*
Y1072404D01*
X1334027D01*
Y1072579D01*
G37*
G36*
G01X1345070D02*
X1345255Y1073179D01*
X1346285D01*
X1346470Y1072579D01*
Y1072405D01*
X1345070D01*
Y1072579D01*
G37*
G36*
G01X1341370D02*
X1341555Y1073179D01*
X1342585D01*
X1342770Y1072579D01*
Y1072405D01*
X1341370D01*
Y1072579D01*
G37*
G36*
G01X1337670D02*
X1337855Y1073179D01*
X1338885D01*
X1339070Y1072579D01*
Y1072405D01*
X1337670D01*
Y1072579D01*
G37*
G36*
G01X1330327D02*
X1330512Y1073179D01*
X1331542D01*
X1331727Y1072579D01*
Y1072405D01*
X1330327D01*
Y1072579D01*
G37*
G36*
G01X1334027D02*
X1334212Y1073179D01*
X1335242D01*
X1335427Y1072579D01*
Y1072404D01*
X1334027D01*
Y1072579D01*
G37*
G36*
G01X1345070D02*
X1345255Y1073179D01*
X1346285D01*
X1346470Y1072579D01*
Y1072405D01*
X1345070D01*
Y1072579D01*
G37*
G36*
G01X1341370D02*
X1341555Y1073179D01*
X1342585D01*
X1342770Y1072579D01*
Y1072405D01*
X1341370D01*
Y1072579D01*
G37*
G36*
G01X1337670D02*
X1337855Y1073179D01*
X1338885D01*
X1339070Y1072579D01*
Y1072405D01*
X1337670D01*
Y1072579D01*
G37*
G36*
G01X1332153Y1069373D02*
X1332338Y1069973D01*
X1333368D01*
X1333553Y1069373D01*
Y1069199D01*
X1332153D01*
Y1069373D01*
G37*
G36*
G01X1335877Y1069375D02*
X1336062Y1069975D01*
X1337092D01*
X1337277Y1069375D01*
Y1069200D01*
X1335877D01*
Y1069375D01*
G37*
G36*
G01X1339587D02*
X1339772Y1069975D01*
X1340802D01*
X1340987Y1069375D01*
Y1069200D01*
X1339587D01*
Y1069375D01*
G37*
G36*
G01X1343287D02*
X1343472Y1069975D01*
X1344502D01*
X1344687Y1069375D01*
Y1069200D01*
X1343287D01*
Y1069375D01*
G37*
G36*
G01X1332153Y1069373D02*
X1332338Y1069973D01*
X1333368D01*
X1333553Y1069373D01*
Y1069199D01*
X1332153D01*
Y1069373D01*
G37*
G36*
G01X1335877Y1069375D02*
X1336062Y1069975D01*
X1337092D01*
X1337277Y1069375D01*
Y1069200D01*
X1335877D01*
Y1069375D01*
G37*
G36*
G01X1339587D02*
X1339772Y1069975D01*
X1340802D01*
X1340987Y1069375D01*
Y1069200D01*
X1339587D01*
Y1069375D01*
G37*
G36*
G01X1343287D02*
X1343472Y1069975D01*
X1344502D01*
X1344687Y1069375D01*
Y1069200D01*
X1343287D01*
Y1069375D01*
G37*
G36*
G01X1337277Y1064575D02*
X1337092Y1063975D01*
X1336062D01*
X1335877Y1064575D01*
Y1064749D01*
X1337277D01*
Y1064575D01*
G37*
G36*
G01X1340977Y1064573D02*
X1340792Y1063973D01*
X1339762D01*
X1339577Y1064573D01*
Y1064748D01*
X1340977D01*
Y1064573D01*
G37*
G36*
G01X1344687D02*
X1344502Y1063973D01*
X1343472D01*
X1343287Y1064573D01*
Y1064748D01*
X1344687D01*
Y1064573D01*
G37*
G36*
G01X1337277Y1064575D02*
X1337092Y1063975D01*
X1336062D01*
X1335877Y1064575D01*
Y1064749D01*
X1337277D01*
Y1064575D01*
G37*
G36*
G01X1340977Y1064573D02*
X1340792Y1063973D01*
X1339762D01*
X1339577Y1064573D01*
Y1064748D01*
X1340977D01*
Y1064573D01*
G37*
G36*
G01X1344687D02*
X1344502Y1063973D01*
X1343472D01*
X1343287Y1064573D01*
Y1064748D01*
X1344687D01*
Y1064573D01*
G37*
G36*
G01X1333577D02*
X1333392Y1063973D01*
X1332362D01*
X1332177Y1064573D01*
Y1064748D01*
X1333577D01*
Y1064573D01*
G37*
G36*
G01D02*
X1333392Y1063973D01*
X1332362D01*
X1332177Y1064573D01*
Y1064748D01*
X1333577D01*
Y1064573D01*
G37*
G36*
G01X1333970Y1066171D02*
X1334155Y1066771D01*
X1335185D01*
X1335370Y1066171D01*
Y1065996D01*
X1333970D01*
Y1066171D01*
G37*
G36*
G01X1330303Y1066169D02*
X1330488Y1066769D01*
X1331518D01*
X1331703Y1066169D01*
Y1065995D01*
X1330303D01*
Y1066169D01*
G37*
G36*
G01X1337703D02*
X1337888Y1066769D01*
X1338918D01*
X1339103Y1066169D01*
Y1065995D01*
X1337703D01*
Y1066169D01*
G37*
G36*
G01X1341370Y1066171D02*
X1341555Y1066771D01*
X1342585D01*
X1342770Y1066171D01*
Y1065996D01*
X1341370D01*
Y1066171D01*
G37*
G36*
G01X1345072D02*
X1345257Y1066771D01*
X1346287D01*
X1346472Y1066171D01*
Y1065996D01*
X1345072D01*
Y1066171D01*
G37*
G36*
G01X1333970D02*
X1334155Y1066771D01*
X1335185D01*
X1335370Y1066171D01*
Y1065996D01*
X1333970D01*
Y1066171D01*
G37*
G36*
G01X1330303Y1066169D02*
X1330488Y1066769D01*
X1331518D01*
X1331703Y1066169D01*
Y1065995D01*
X1330303D01*
Y1066169D01*
G37*
G36*
G01X1337703D02*
X1337888Y1066769D01*
X1338918D01*
X1339103Y1066169D01*
Y1065995D01*
X1337703D01*
Y1066169D01*
G37*
G36*
G01X1341370Y1066171D02*
X1341555Y1066771D01*
X1342585D01*
X1342770Y1066171D01*
Y1065996D01*
X1341370D01*
Y1066171D01*
G37*
G36*
G01X1345072D02*
X1345257Y1066771D01*
X1346287D01*
X1346472Y1066171D01*
Y1065996D01*
X1345072D01*
Y1066171D01*
G37*
G36*
G01X1330303Y1078987D02*
X1330488Y1079587D01*
X1331518D01*
X1331703Y1078987D01*
Y1078812D01*
X1330303D01*
Y1078987D01*
G37*
G36*
G01X1333980D02*
X1334165Y1079587D01*
X1335195D01*
X1335380Y1078987D01*
Y1078813D01*
X1333980D01*
Y1078987D01*
G37*
G36*
G01X1345070D02*
X1345255Y1079587D01*
X1346285D01*
X1346470Y1078987D01*
Y1078813D01*
X1345070D01*
Y1078987D01*
G37*
G36*
G01X1341370D02*
X1341555Y1079587D01*
X1342585D01*
X1342770Y1078987D01*
Y1078813D01*
X1341370D01*
Y1078987D01*
G37*
G36*
G01X1337680D02*
X1337865Y1079587D01*
X1338895D01*
X1339080Y1078987D01*
Y1078812D01*
X1337680D01*
Y1078987D01*
G37*
G36*
G01X1330303D02*
X1330488Y1079587D01*
X1331518D01*
X1331703Y1078987D01*
Y1078812D01*
X1330303D01*
Y1078987D01*
G37*
G36*
G01X1333980D02*
X1334165Y1079587D01*
X1335195D01*
X1335380Y1078987D01*
Y1078813D01*
X1333980D01*
Y1078987D01*
G37*
G36*
G01X1345070D02*
X1345255Y1079587D01*
X1346285D01*
X1346470Y1078987D01*
Y1078813D01*
X1345070D01*
Y1078987D01*
G37*
G36*
G01X1341370D02*
X1341555Y1079587D01*
X1342585D01*
X1342770Y1078987D01*
Y1078813D01*
X1341370D01*
Y1078987D01*
G37*
G36*
G01X1337680D02*
X1337865Y1079587D01*
X1338895D01*
X1339080Y1078987D01*
Y1078812D01*
X1337680D01*
Y1078987D01*
G37*
G36*
G01X1332130Y1075783D02*
X1332315Y1076383D01*
X1333345D01*
X1333530Y1075783D01*
Y1075609D01*
X1332130D01*
Y1075783D01*
G37*
G36*
G01X1343287D02*
X1343472Y1076383D01*
X1344502D01*
X1344687Y1075783D01*
Y1075609D01*
X1343287D01*
Y1075783D01*
G37*
G36*
G01X1339587D02*
X1339772Y1076383D01*
X1340802D01*
X1340987Y1075783D01*
Y1075609D01*
X1339587D01*
Y1075783D01*
G37*
G36*
G01X1335887D02*
X1336072Y1076383D01*
X1337102D01*
X1337287Y1075783D01*
Y1075609D01*
X1335887D01*
Y1075783D01*
G37*
G36*
G01X1332130D02*
X1332315Y1076383D01*
X1333345D01*
X1333530Y1075783D01*
Y1075609D01*
X1332130D01*
Y1075783D01*
G37*
G36*
G01X1343287D02*
X1343472Y1076383D01*
X1344502D01*
X1344687Y1075783D01*
Y1075609D01*
X1343287D01*
Y1075783D01*
G37*
G36*
G01X1339587D02*
X1339772Y1076383D01*
X1340802D01*
X1340987Y1075783D01*
Y1075609D01*
X1339587D01*
Y1075783D01*
G37*
G36*
G01X1335887D02*
X1336072Y1076383D01*
X1337102D01*
X1337287Y1075783D01*
Y1075609D01*
X1335887D01*
Y1075783D01*
G37*
G36*
G01X1333577Y1077391D02*
X1333392Y1076791D01*
X1332362D01*
X1332177Y1077391D01*
Y1077565D01*
X1333577D01*
Y1077391D01*
G37*
G36*
G01X1344687D02*
X1344502Y1076791D01*
X1343472D01*
X1343287Y1077391D01*
Y1077565D01*
X1344687D01*
Y1077391D01*
G37*
G36*
G01X1340987D02*
X1340802Y1076791D01*
X1339772D01*
X1339587Y1077391D01*
Y1077565D01*
X1340987D01*
Y1077391D01*
G37*
G36*
G01X1337254D02*
X1337069Y1076791D01*
X1336039D01*
X1335854Y1077391D01*
Y1077566D01*
X1337254D01*
Y1077391D01*
G37*
G36*
G01X1333577D02*
X1333392Y1076791D01*
X1332362D01*
X1332177Y1077391D01*
Y1077565D01*
X1333577D01*
Y1077391D01*
G37*
G36*
G01X1344687D02*
X1344502Y1076791D01*
X1343472D01*
X1343287Y1077391D01*
Y1077565D01*
X1344687D01*
Y1077391D01*
G37*
G36*
G01X1340987D02*
X1340802Y1076791D01*
X1339772D01*
X1339587Y1077391D01*
Y1077565D01*
X1340987D01*
Y1077391D01*
G37*
G36*
G01X1337254D02*
X1337069Y1076791D01*
X1336039D01*
X1335854Y1077391D01*
Y1077566D01*
X1337254D01*
Y1077391D01*
G37*
G36*
G01X1331727Y1074187D02*
X1331542Y1073587D01*
X1330512D01*
X1330327Y1074187D01*
Y1074361D01*
X1331727D01*
Y1074187D01*
G37*
G36*
G01X1335380D02*
X1335195Y1073587D01*
X1334165D01*
X1333980Y1074187D01*
Y1074362D01*
X1335380D01*
Y1074187D01*
G37*
G36*
G01X1346470D02*
X1346285Y1073587D01*
X1345255D01*
X1345070Y1074187D01*
Y1074361D01*
X1346470D01*
Y1074187D01*
G37*
G36*
G01X1342770D02*
X1342585Y1073587D01*
X1341555D01*
X1341370Y1074187D01*
Y1074361D01*
X1342770D01*
Y1074187D01*
G37*
G36*
G01X1339070D02*
X1338885Y1073587D01*
X1337855D01*
X1337670Y1074187D01*
Y1074361D01*
X1339070D01*
Y1074187D01*
G37*
G36*
G01X1331727D02*
X1331542Y1073587D01*
X1330512D01*
X1330327Y1074187D01*
Y1074361D01*
X1331727D01*
Y1074187D01*
G37*
G36*
G01X1335380D02*
X1335195Y1073587D01*
X1334165D01*
X1333980Y1074187D01*
Y1074362D01*
X1335380D01*
Y1074187D01*
G37*
G36*
G01X1346470D02*
X1346285Y1073587D01*
X1345255D01*
X1345070Y1074187D01*
Y1074361D01*
X1346470D01*
Y1074187D01*
G37*
G36*
G01X1342770D02*
X1342585Y1073587D01*
X1341555D01*
X1341370Y1074187D01*
Y1074361D01*
X1342770D01*
Y1074187D01*
G37*
G36*
G01X1339070D02*
X1338885Y1073587D01*
X1337855D01*
X1337670Y1074187D01*
Y1074361D01*
X1339070D01*
Y1074187D01*
G37*
G36*
G01X1334568Y1094438D02*
X1335180Y1094578D01*
X1335695Y1093686D01*
X1335268Y1093226D01*
X1335117Y1093139D01*
X1334417Y1094351D01*
X1334568Y1094438D01*
G37*
G36*
G01X1345070Y1091804D02*
X1345255Y1092404D01*
X1346285D01*
X1346470Y1091804D01*
Y1091630D01*
X1345070D01*
Y1091804D01*
G37*
G36*
G01X1337670D02*
X1337855Y1092404D01*
X1338885D01*
X1339070Y1091804D01*
Y1091630D01*
X1337670D01*
Y1091804D01*
G37*
G36*
G01X1341370D02*
X1341555Y1092404D01*
X1342585D01*
X1342770Y1091804D01*
Y1091630D01*
X1341370D01*
Y1091804D01*
G37*
G36*
G01X1334568Y1094438D02*
X1335180Y1094578D01*
X1335695Y1093686D01*
X1335268Y1093226D01*
X1335117Y1093139D01*
X1334417Y1094351D01*
X1334568Y1094438D01*
G37*
G36*
G01X1345070Y1091804D02*
X1345255Y1092404D01*
X1346285D01*
X1346470Y1091804D01*
Y1091630D01*
X1345070D01*
Y1091804D01*
G37*
G36*
G01X1337670D02*
X1337855Y1092404D01*
X1338885D01*
X1339070Y1091804D01*
Y1091630D01*
X1337670D01*
Y1091804D01*
G37*
G36*
G01X1341370D02*
X1341555Y1092404D01*
X1342585D01*
X1342770Y1091804D01*
Y1091630D01*
X1341370D01*
Y1091804D01*
G37*
G36*
G01X1332717Y1091236D02*
X1333329Y1091376D01*
X1333844Y1090484D01*
X1333417Y1090024D01*
X1333266Y1089937D01*
X1332566Y1091149D01*
X1332717Y1091236D01*
G37*
G36*
G01X1330874Y1094427D02*
X1331486Y1094567D01*
X1332001Y1093675D01*
X1331574Y1093215D01*
X1331423Y1093128D01*
X1330723Y1094340D01*
X1330874Y1094427D01*
G37*
G36*
G01X1343287Y1088600D02*
X1343472Y1089200D01*
X1344502D01*
X1344687Y1088600D01*
Y1088426D01*
X1343287D01*
Y1088600D01*
G37*
G36*
G01X1339587D02*
X1339772Y1089200D01*
X1340802D01*
X1340987Y1088600D01*
Y1088426D01*
X1339587D01*
Y1088600D01*
G37*
G36*
G01X1335877D02*
X1336062Y1089200D01*
X1337092D01*
X1337277Y1088600D01*
Y1088426D01*
X1335877D01*
Y1088600D01*
G37*
G36*
G01X1332717Y1091236D02*
X1333329Y1091376D01*
X1333844Y1090484D01*
X1333417Y1090024D01*
X1333266Y1089937D01*
X1332566Y1091149D01*
X1332717Y1091236D01*
G37*
G36*
G01X1330874Y1094427D02*
X1331486Y1094567D01*
X1332001Y1093675D01*
X1331574Y1093215D01*
X1331423Y1093128D01*
X1330723Y1094340D01*
X1330874Y1094427D01*
G37*
G36*
G01X1343287Y1088600D02*
X1343472Y1089200D01*
X1344502D01*
X1344687Y1088600D01*
Y1088426D01*
X1343287D01*
Y1088600D01*
G37*
G36*
G01X1339587D02*
X1339772Y1089200D01*
X1340802D01*
X1340987Y1088600D01*
Y1088426D01*
X1339587D01*
Y1088600D01*
G37*
G36*
G01X1335877D02*
X1336062Y1089200D01*
X1337092D01*
X1337277Y1088600D01*
Y1088426D01*
X1335877D01*
Y1088600D01*
G37*
G36*
G01X1334835Y1090786D02*
X1334223Y1090646D01*
X1333708Y1091538D01*
X1334135Y1091998D01*
X1334286Y1092085D01*
X1334986Y1090873D01*
X1334835Y1090786D01*
G37*
G36*
G01X1332989Y1093983D02*
X1332377Y1093843D01*
X1331862Y1094735D01*
X1332289Y1095195D01*
X1332440Y1095282D01*
X1333140Y1094070D01*
X1332989Y1093983D01*
G37*
G36*
G01X1344687Y1090207D02*
X1344502Y1089607D01*
X1343472D01*
X1343287Y1090207D01*
Y1090382D01*
X1344687D01*
Y1090207D01*
G37*
G36*
G01X1340987D02*
X1340802Y1089607D01*
X1339772D01*
X1339587Y1090207D01*
Y1090382D01*
X1340987D01*
Y1090207D01*
G37*
G36*
G01X1337277D02*
X1337092Y1089607D01*
X1336062D01*
X1335877Y1090207D01*
Y1090382D01*
X1337277D01*
Y1090207D01*
G37*
G36*
G01X1334835Y1090786D02*
X1334223Y1090646D01*
X1333708Y1091538D01*
X1334135Y1091998D01*
X1334286Y1092085D01*
X1334986Y1090873D01*
X1334835Y1090786D01*
G37*
G36*
G01X1332989Y1093983D02*
X1332377Y1093843D01*
X1331862Y1094735D01*
X1332289Y1095195D01*
X1332440Y1095282D01*
X1333140Y1094070D01*
X1332989Y1093983D01*
G37*
G36*
G01X1344687Y1090207D02*
X1344502Y1089607D01*
X1343472D01*
X1343287Y1090207D01*
Y1090382D01*
X1344687D01*
Y1090207D01*
G37*
G36*
G01X1340987D02*
X1340802Y1089607D01*
X1339772D01*
X1339587Y1090207D01*
Y1090382D01*
X1340987D01*
Y1090207D01*
G37*
G36*
G01X1337277D02*
X1337092Y1089607D01*
X1336062D01*
X1335877Y1090207D01*
Y1090382D01*
X1337277D01*
Y1090207D01*
G37*
G36*
G01X1332985Y1087582D02*
X1332373Y1087442D01*
X1331858Y1088334D01*
X1332285Y1088794D01*
X1332436Y1088881D01*
X1333136Y1087669D01*
X1332985Y1087582D01*
G37*
G36*
G01X1335403Y1087005D02*
X1335218Y1086405D01*
X1334188D01*
X1334003Y1087005D01*
Y1087179D01*
X1335403D01*
Y1087005D01*
G37*
G36*
G01X1346480Y1087003D02*
X1346295Y1086403D01*
X1345265D01*
X1345080Y1087003D01*
Y1087178D01*
X1346480D01*
Y1087003D01*
G37*
G36*
G01X1339070D02*
X1338885Y1086403D01*
X1337855D01*
X1337670Y1087003D01*
Y1087178D01*
X1339070D01*
Y1087003D01*
G37*
G36*
G01X1342770D02*
X1342585Y1086403D01*
X1341555D01*
X1341370Y1087003D01*
Y1087178D01*
X1342770D01*
Y1087003D01*
G37*
G36*
G01X1332985Y1087582D02*
X1332373Y1087442D01*
X1331858Y1088334D01*
X1332285Y1088794D01*
X1332436Y1088881D01*
X1333136Y1087669D01*
X1332985Y1087582D01*
G37*
G36*
G01X1335403Y1087005D02*
X1335218Y1086405D01*
X1334188D01*
X1334003Y1087005D01*
Y1087179D01*
X1335403D01*
Y1087005D01*
G37*
G36*
G01X1346480Y1087003D02*
X1346295Y1086403D01*
X1345265D01*
X1345080Y1087003D01*
Y1087178D01*
X1346480D01*
Y1087003D01*
G37*
G36*
G01X1339070D02*
X1338885Y1086403D01*
X1337855D01*
X1337670Y1087003D01*
Y1087178D01*
X1339070D01*
Y1087003D01*
G37*
G36*
G01X1342770D02*
X1342585Y1086403D01*
X1341555D01*
X1341370Y1087003D01*
Y1087178D01*
X1342770D01*
Y1087003D01*
G37*
G36*
G01X1333577Y1083799D02*
X1333392Y1083199D01*
X1332362D01*
X1332177Y1083799D01*
Y1083973D01*
X1333577D01*
Y1083799D01*
G37*
G36*
G01X1337277D02*
X1337092Y1083199D01*
X1336062D01*
X1335877Y1083799D01*
Y1083974D01*
X1337277D01*
Y1083799D01*
G37*
G36*
G01X1340977D02*
X1340792Y1083199D01*
X1339762D01*
X1339577Y1083799D01*
Y1083973D01*
X1340977D01*
Y1083799D01*
G37*
G36*
G01X1344687D02*
X1344502Y1083199D01*
X1343472D01*
X1343287Y1083799D01*
Y1083973D01*
X1344687D01*
Y1083799D01*
G37*
G36*
G01X1333577D02*
X1333392Y1083199D01*
X1332362D01*
X1332177Y1083799D01*
Y1083973D01*
X1333577D01*
Y1083799D01*
G37*
G36*
G01X1337277D02*
X1337092Y1083199D01*
X1336062D01*
X1335877Y1083799D01*
Y1083974D01*
X1337277D01*
Y1083799D01*
G37*
G36*
G01X1340977D02*
X1340792Y1083199D01*
X1339762D01*
X1339577Y1083799D01*
Y1083973D01*
X1340977D01*
Y1083799D01*
G37*
G36*
G01X1344687D02*
X1344502Y1083199D01*
X1343472D01*
X1343287Y1083799D01*
Y1083973D01*
X1344687D01*
Y1083799D01*
G37*
G36*
G01X1332177Y1082191D02*
X1332362Y1082791D01*
X1333392D01*
X1333577Y1082191D01*
Y1082017D01*
X1332177D01*
Y1082191D01*
G37*
G36*
G01X1335830D02*
X1336015Y1082791D01*
X1337045D01*
X1337230Y1082191D01*
Y1082016D01*
X1335830D01*
Y1082191D01*
G37*
G36*
G01X1339577D02*
X1339762Y1082791D01*
X1340792D01*
X1340977Y1082191D01*
Y1082017D01*
X1339577D01*
Y1082191D01*
G37*
G36*
G01X1343287D02*
X1343472Y1082791D01*
X1344502D01*
X1344687Y1082191D01*
Y1082017D01*
X1343287D01*
Y1082191D01*
G37*
G36*
G01X1332177D02*
X1332362Y1082791D01*
X1333392D01*
X1333577Y1082191D01*
Y1082017D01*
X1332177D01*
Y1082191D01*
G37*
G36*
G01X1335830D02*
X1336015Y1082791D01*
X1337045D01*
X1337230Y1082191D01*
Y1082016D01*
X1335830D01*
Y1082191D01*
G37*
G36*
G01X1339577D02*
X1339762Y1082791D01*
X1340792D01*
X1340977Y1082191D01*
Y1082017D01*
X1339577D01*
Y1082191D01*
G37*
G36*
G01X1343287D02*
X1343472Y1082791D01*
X1344502D01*
X1344687Y1082191D01*
Y1082017D01*
X1343287D01*
Y1082191D01*
G37*
G36*
G01X1333970Y1085396D02*
X1334155Y1085996D01*
X1335185D01*
X1335370Y1085396D01*
Y1085221D01*
X1333970D01*
Y1085396D01*
G37*
G36*
G01X1330871Y1088022D02*
X1331483Y1088162D01*
X1331998Y1087270D01*
X1331571Y1086810D01*
X1331420Y1086723D01*
X1330720Y1087935D01*
X1330871Y1088022D01*
G37*
G36*
G01X1337703Y1085395D02*
X1337888Y1085995D01*
X1338918D01*
X1339103Y1085395D01*
Y1085220D01*
X1337703D01*
Y1085395D01*
G37*
G36*
G01X1341370Y1085396D02*
X1341555Y1085996D01*
X1342585D01*
X1342770Y1085396D01*
Y1085222D01*
X1341370D01*
Y1085396D01*
G37*
G36*
G01X1345072D02*
X1345257Y1085996D01*
X1346287D01*
X1346472Y1085396D01*
Y1085221D01*
X1345072D01*
Y1085396D01*
G37*
G36*
G01X1333970D02*
X1334155Y1085996D01*
X1335185D01*
X1335370Y1085396D01*
Y1085221D01*
X1333970D01*
Y1085396D01*
G37*
G36*
G01X1330871Y1088022D02*
X1331483Y1088162D01*
X1331998Y1087270D01*
X1331571Y1086810D01*
X1331420Y1086723D01*
X1330720Y1087935D01*
X1330871Y1088022D01*
G37*
G36*
G01X1337703Y1085395D02*
X1337888Y1085995D01*
X1338918D01*
X1339103Y1085395D01*
Y1085220D01*
X1337703D01*
Y1085395D01*
G37*
G36*
G01X1341370Y1085396D02*
X1341555Y1085996D01*
X1342585D01*
X1342770Y1085396D01*
Y1085222D01*
X1341370D01*
Y1085396D01*
G37*
G36*
G01X1345072D02*
X1345257Y1085996D01*
X1346287D01*
X1346472Y1085396D01*
Y1085221D01*
X1345072D01*
Y1085396D01*
G37*
G36*
G01X1335380Y1080595D02*
X1335195Y1079995D01*
X1334165D01*
X1333980Y1080595D01*
Y1080769D01*
X1335380D01*
Y1080595D01*
G37*
G36*
G01X1331703D02*
X1331518Y1079995D01*
X1330488D01*
X1330303Y1080595D01*
Y1080770D01*
X1331703D01*
Y1080595D01*
G37*
G36*
G01X1346470D02*
X1346285Y1079995D01*
X1345255D01*
X1345070Y1080595D01*
Y1080769D01*
X1346470D01*
Y1080595D01*
G37*
G36*
G01X1339127D02*
X1338942Y1079995D01*
X1337912D01*
X1337727Y1080595D01*
Y1080770D01*
X1339127D01*
Y1080595D01*
G37*
G36*
G01X1342770D02*
X1342585Y1079995D01*
X1341555D01*
X1341370Y1080595D01*
Y1080769D01*
X1342770D01*
Y1080595D01*
G37*
G36*
G01X1335380D02*
X1335195Y1079995D01*
X1334165D01*
X1333980Y1080595D01*
Y1080769D01*
X1335380D01*
Y1080595D01*
G37*
G36*
G01X1331703D02*
X1331518Y1079995D01*
X1330488D01*
X1330303Y1080595D01*
Y1080770D01*
X1331703D01*
Y1080595D01*
G37*
G36*
G01X1346470D02*
X1346285Y1079995D01*
X1345255D01*
X1345070Y1080595D01*
Y1080769D01*
X1346470D01*
Y1080595D01*
G37*
G36*
G01X1339127D02*
X1338942Y1079995D01*
X1337912D01*
X1337727Y1080595D01*
Y1080770D01*
X1339127D01*
Y1080595D01*
G37*
G36*
G01X1342770D02*
X1342585Y1079995D01*
X1341555D01*
X1341370Y1080595D01*
Y1080769D01*
X1342770D01*
Y1080595D01*
G37*
G36*
G01X1332721Y1097635D02*
X1333333Y1097775D01*
X1333848Y1096883D01*
X1333421Y1096423D01*
X1333270Y1096336D01*
X1332570Y1097548D01*
X1332721Y1097635D01*
G37*
G36*
G01D02*
X1333333Y1097775D01*
X1333848Y1096883D01*
X1333421Y1096423D01*
X1333270Y1096336D01*
X1332570Y1097548D01*
X1332721Y1097635D01*
G37*
G36*
G01X1330871Y1100839D02*
X1331483Y1100979D01*
X1331998Y1100087D01*
X1331571Y1099627D01*
X1331420Y1099540D01*
X1330720Y1100752D01*
X1330871Y1100839D01*
G37*
G36*
G01D02*
X1331483Y1100979D01*
X1331998Y1100087D01*
X1331571Y1099627D01*
X1331420Y1099540D01*
X1330720Y1100752D01*
X1330871Y1100839D01*
G37*
G36*
G01X1351203Y101632D02*
G03I-653J0D01*
G37*
G36*
G01X1351485Y889214D02*
X1351912Y888754D01*
X1351397Y887862D01*
X1350785Y888002D01*
X1350634Y888089D01*
X1351334Y889301D01*
X1351485Y889214D01*
G37*
G36*
G01D02*
X1351912Y888754D01*
X1351397Y887862D01*
X1350785Y888002D01*
X1350634Y888089D01*
X1351334Y889301D01*
X1351485Y889214D01*
G37*
G36*
G01X1349737Y887431D02*
X1349552Y886831D01*
X1348522D01*
X1348337Y887431D01*
Y887605D01*
X1349737D01*
Y887431D01*
G37*
G36*
G01D02*
X1349552Y886831D01*
X1348522D01*
X1348337Y887431D01*
Y887605D01*
X1349737D01*
Y887431D01*
G37*
G36*
G01X1347954Y890635D02*
X1347769Y890035D01*
X1346739D01*
X1346554Y890635D01*
Y890810D01*
X1347954D01*
Y890635D01*
G37*
G36*
G01D02*
X1347769Y890035D01*
X1346739D01*
X1346554Y890635D01*
Y890810D01*
X1347954D01*
Y890635D01*
G37*
G36*
G01X1346554Y889029D02*
X1346739Y889629D01*
X1347769D01*
X1347954Y889029D01*
Y888854D01*
X1346554D01*
Y889029D01*
G37*
G36*
G01D02*
X1346739Y889629D01*
X1347769D01*
X1347954Y889029D01*
Y888854D01*
X1346554D01*
Y889029D01*
G37*
G36*
G01Y895437D02*
X1346739Y896037D01*
X1347769D01*
X1347954Y895437D01*
Y895262D01*
X1346554D01*
Y895437D01*
G37*
G36*
G01D02*
X1346739Y896037D01*
X1347769D01*
X1347954Y895437D01*
Y895262D01*
X1346554D01*
Y895437D01*
G37*
G36*
G01X1347944Y903453D02*
X1347759Y902853D01*
X1346729D01*
X1346544Y903453D01*
Y903628D01*
X1347944D01*
Y903453D01*
G37*
G36*
G01D02*
X1347759Y902853D01*
X1346729D01*
X1346544Y903453D01*
Y903628D01*
X1347944D01*
Y903453D01*
G37*
G36*
G01X1346544Y901845D02*
X1346729Y902445D01*
X1347759D01*
X1347944Y901845D01*
Y901670D01*
X1346544D01*
Y901845D01*
G37*
G36*
G01D02*
X1346729Y902445D01*
X1347759D01*
X1347944Y901845D01*
Y901670D01*
X1346544D01*
Y901845D01*
G37*
G36*
G01X1348370Y905049D02*
X1348555Y905649D01*
X1349585D01*
X1349770Y905049D01*
Y904874D01*
X1348370D01*
Y905049D01*
G37*
G36*
G01D02*
X1348555Y905649D01*
X1349585D01*
X1349770Y905049D01*
Y904874D01*
X1348370D01*
Y905049D01*
G37*
G36*
G01X1346554Y908253D02*
X1346739Y908853D01*
X1347769D01*
X1347954Y908253D01*
Y908079D01*
X1346554D01*
Y908253D01*
G37*
G36*
G01D02*
X1346739Y908853D01*
X1347769D01*
X1347954Y908253D01*
Y908079D01*
X1346554D01*
Y908253D01*
G37*
G36*
G01X1347921Y909861D02*
X1347736Y909261D01*
X1346706D01*
X1346521Y909861D01*
Y910036D01*
X1347921D01*
Y909861D01*
G37*
G36*
G01D02*
X1347736Y909261D01*
X1346706D01*
X1346521Y909861D01*
Y910036D01*
X1347921D01*
Y909861D01*
G37*
G36*
G01X1349737Y906657D02*
X1349552Y906057D01*
X1348522D01*
X1348337Y906657D01*
Y906831D01*
X1349737D01*
Y906657D01*
G37*
G36*
G01D02*
X1349552Y906057D01*
X1348522D01*
X1348337Y906657D01*
Y906831D01*
X1349737D01*
Y906657D01*
G37*
G36*
G01X1346521Y914661D02*
X1346706Y915261D01*
X1347736D01*
X1347921Y914661D01*
Y914487D01*
X1346521D01*
Y914661D01*
G37*
G36*
G01D02*
X1346706Y915261D01*
X1347736D01*
X1347921Y914661D01*
Y914487D01*
X1346521D01*
Y914661D01*
G37*
G36*
G01X1346554Y927479D02*
X1346739Y928079D01*
X1347769D01*
X1347954Y927479D01*
Y927305D01*
X1346554D01*
Y927479D01*
G37*
G36*
G01D02*
X1346739Y928079D01*
X1347769D01*
X1347954Y927479D01*
Y927305D01*
X1346554D01*
Y927479D01*
G37*
G36*
G01X1347921Y929087D02*
X1347736Y928487D01*
X1346706D01*
X1346521Y929087D01*
Y929262D01*
X1347921D01*
Y929087D01*
G37*
G36*
G01D02*
X1347736Y928487D01*
X1346706D01*
X1346521Y929087D01*
Y929262D01*
X1347921D01*
Y929087D01*
G37*
G36*
G01X1349737Y925883D02*
X1349552Y925283D01*
X1348522D01*
X1348337Y925883D01*
Y926057D01*
X1349737D01*
Y925883D01*
G37*
G36*
G01D02*
X1349552Y925283D01*
X1348522D01*
X1348337Y925883D01*
Y926057D01*
X1349737D01*
Y925883D01*
G37*
G36*
G01X1348370Y924275D02*
X1348555Y924875D01*
X1349585D01*
X1349770Y924275D01*
Y924100D01*
X1348370D01*
Y924275D01*
G37*
G36*
G01D02*
X1348555Y924875D01*
X1349585D01*
X1349770Y924275D01*
Y924100D01*
X1348370D01*
Y924275D01*
G37*
G36*
G01X1346544Y921071D02*
X1346729Y921671D01*
X1347759D01*
X1347944Y921071D01*
Y920896D01*
X1346544D01*
Y921071D01*
G37*
G36*
G01D02*
X1346729Y921671D01*
X1347759D01*
X1347944Y921071D01*
Y920896D01*
X1346544D01*
Y921071D01*
G37*
G36*
G01X1347944Y922679D02*
X1347759Y922079D01*
X1346729D01*
X1346544Y922679D01*
Y922854D01*
X1347944D01*
Y922679D01*
G37*
G36*
G01D02*
X1347759Y922079D01*
X1346729D01*
X1346544Y922679D01*
Y922854D01*
X1347944D01*
Y922679D01*
G37*
G36*
G01Y941905D02*
X1347759Y941305D01*
X1346729D01*
X1346544Y941905D01*
Y942079D01*
X1347944D01*
Y941905D01*
G37*
G36*
G01D02*
X1347759Y941305D01*
X1346729D01*
X1346544Y941905D01*
Y942079D01*
X1347944D01*
Y941905D01*
G37*
G36*
G01X1346554Y946705D02*
X1346739Y947305D01*
X1347769D01*
X1347954Y946705D01*
Y946531D01*
X1346554D01*
Y946705D01*
G37*
G36*
G01X1350254D02*
X1350439Y947305D01*
X1351469D01*
X1351654Y946705D01*
Y946531D01*
X1350254D01*
Y946705D01*
G37*
G36*
G01X1346554D02*
X1346739Y947305D01*
X1347769D01*
X1347954Y946705D01*
Y946531D01*
X1346554D01*
Y946705D01*
G37*
G36*
G01X1350254D02*
X1350439Y947305D01*
X1351469D01*
X1351654Y946705D01*
Y946531D01*
X1350254D01*
Y946705D01*
G37*
G36*
G01X1347921Y948313D02*
X1347736Y947713D01*
X1346706D01*
X1346521Y948313D01*
Y948488D01*
X1347921D01*
Y948313D01*
G37*
G36*
G01D02*
X1347736Y947713D01*
X1346706D01*
X1346521Y948313D01*
Y948488D01*
X1347921D01*
Y948313D01*
G37*
G36*
G01X1349737Y945107D02*
X1349552Y944507D01*
X1348522D01*
X1348337Y945107D01*
Y945282D01*
X1349737D01*
Y945107D01*
G37*
G36*
G01X1353437D02*
X1353252Y944507D01*
X1352222D01*
X1352037Y945107D01*
Y945282D01*
X1353437D01*
Y945107D01*
G37*
G36*
G01X1349737D02*
X1349552Y944507D01*
X1348522D01*
X1348337Y945107D01*
Y945282D01*
X1349737D01*
Y945107D01*
G37*
G36*
G01X1353437D02*
X1353252Y944507D01*
X1352222D01*
X1352037Y945107D01*
Y945282D01*
X1353437D01*
Y945107D01*
G37*
G36*
G01X1346544Y940295D02*
X1346729Y940895D01*
X1347759D01*
X1347944Y940295D01*
Y940121D01*
X1346544D01*
Y940295D01*
G37*
G36*
G01D02*
X1346729Y940895D01*
X1347759D01*
X1347944Y940295D01*
Y940121D01*
X1346544D01*
Y940295D01*
G37*
G36*
G01X1346521Y933887D02*
X1346706Y934487D01*
X1347736D01*
X1347921Y933887D01*
Y933713D01*
X1346521D01*
Y933887D01*
G37*
G36*
G01D02*
X1346706Y934487D01*
X1347736D01*
X1347921Y933887D01*
Y933713D01*
X1346521D01*
Y933887D01*
G37*
G36*
G01X1348370Y962725D02*
X1348555Y963325D01*
X1349585D01*
X1349770Y962725D01*
Y962551D01*
X1348370D01*
Y962725D01*
G37*
G36*
G01D02*
X1348555Y963325D01*
X1349585D01*
X1349770Y962725D01*
Y962551D01*
X1348370D01*
Y962725D01*
G37*
G36*
G01X1347944Y961131D02*
X1347759Y960531D01*
X1346729D01*
X1346544Y961131D01*
Y961305D01*
X1347944D01*
Y961131D01*
G37*
G36*
G01D02*
X1347759Y960531D01*
X1346729D01*
X1346544Y961131D01*
Y961305D01*
X1347944D01*
Y961131D01*
G37*
G36*
G01X1346521Y953113D02*
X1346706Y953713D01*
X1347736D01*
X1347921Y953113D01*
Y952938D01*
X1346521D01*
Y953113D01*
G37*
G36*
G01D02*
X1346706Y953713D01*
X1347736D01*
X1347921Y953113D01*
Y952938D01*
X1346521D01*
Y953113D01*
G37*
G36*
G01X1349747Y951517D02*
X1349562Y950917D01*
X1348532D01*
X1348347Y951517D01*
Y951692D01*
X1349747D01*
Y951517D01*
G37*
G36*
G01X1353437D02*
X1353252Y950917D01*
X1352222D01*
X1352037Y951517D01*
Y951691D01*
X1353437D01*
Y951517D01*
G37*
G36*
G01X1349747D02*
X1349562Y950917D01*
X1348532D01*
X1348347Y951517D01*
Y951692D01*
X1349747D01*
Y951517D01*
G37*
G36*
G01X1353437D02*
X1353252Y950917D01*
X1352222D01*
X1352037Y951517D01*
Y951691D01*
X1353437D01*
Y951517D01*
G37*
G36*
G01X1349737Y964333D02*
X1349552Y963733D01*
X1348522D01*
X1348337Y964333D01*
Y964508D01*
X1349737D01*
Y964333D01*
G37*
G36*
G01D02*
X1349552Y963733D01*
X1348522D01*
X1348337Y964333D01*
Y964508D01*
X1349737D01*
Y964333D01*
G37*
G36*
G01X1349770Y977151D02*
X1349585Y976551D01*
X1348555D01*
X1348370Y977151D01*
Y977326D01*
X1349770D01*
Y977151D01*
G37*
G36*
G01X1353447D02*
X1353262Y976551D01*
X1352232D01*
X1352047Y977151D01*
Y977325D01*
X1353447D01*
Y977151D01*
G37*
G36*
G01X1349770D02*
X1349585Y976551D01*
X1348555D01*
X1348370Y977151D01*
Y977326D01*
X1349770D01*
Y977151D01*
G37*
G36*
G01X1353447D02*
X1353262Y976551D01*
X1352232D01*
X1352047Y977151D01*
Y977325D01*
X1353447D01*
Y977151D01*
G37*
G36*
G01X1357147D02*
X1356962Y976551D01*
X1355932D01*
X1355747Y977151D01*
Y977326D01*
X1357147D01*
Y977151D01*
G37*
G36*
G01X1360847D02*
X1360662Y976551D01*
X1359632D01*
X1359447Y977151D01*
Y977325D01*
X1360847D01*
Y977151D01*
G37*
G36*
G01X1357147D02*
X1356962Y976551D01*
X1355932D01*
X1355747Y977151D01*
Y977326D01*
X1357147D01*
Y977151D01*
G37*
G36*
G01X1360847D02*
X1360662Y976551D01*
X1359632D01*
X1359447Y977151D01*
Y977325D01*
X1360847D01*
Y977151D01*
G37*
G36*
G01X1348337Y975543D02*
X1348522Y976143D01*
X1349552D01*
X1349737Y975543D01*
Y975369D01*
X1348337D01*
Y975543D01*
G37*
G36*
G01X1352047D02*
X1352232Y976143D01*
X1353262D01*
X1353447Y975543D01*
Y975369D01*
X1352047D01*
Y975543D01*
G37*
G36*
G01X1348337D02*
X1348522Y976143D01*
X1349552D01*
X1349737Y975543D01*
Y975369D01*
X1348337D01*
Y975543D01*
G37*
G36*
G01X1352047D02*
X1352232Y976143D01*
X1353262D01*
X1353447Y975543D01*
Y975369D01*
X1352047D01*
Y975543D01*
G37*
G36*
G01X1355794D02*
X1355979Y976143D01*
X1357009D01*
X1357194Y975543D01*
Y975368D01*
X1355794D01*
Y975543D01*
G37*
G36*
G01X1359447D02*
X1359632Y976143D01*
X1360662D01*
X1360847Y975543D01*
Y975369D01*
X1359447D01*
Y975543D01*
G37*
G36*
G01X1355794D02*
X1355979Y976143D01*
X1357009D01*
X1357194Y975543D01*
Y975368D01*
X1355794D01*
Y975543D01*
G37*
G36*
G01X1359447D02*
X1359632Y976143D01*
X1360662D01*
X1360847Y975543D01*
Y975369D01*
X1359447D01*
Y975543D01*
G37*
G36*
G01X1346544Y978747D02*
X1346729Y979347D01*
X1347759D01*
X1347944Y978747D01*
Y978573D01*
X1346544D01*
Y978747D01*
G37*
G36*
G01X1350244Y978749D02*
X1350429Y979349D01*
X1351459D01*
X1351644Y978749D01*
Y978574D01*
X1350244D01*
Y978749D01*
G37*
G36*
G01X1346544Y978747D02*
X1346729Y979347D01*
X1347759D01*
X1347944Y978747D01*
Y978573D01*
X1346544D01*
Y978747D01*
G37*
G36*
G01X1350244Y978749D02*
X1350429Y979349D01*
X1351459D01*
X1351644Y978749D01*
Y978574D01*
X1350244D01*
Y978749D01*
G37*
G36*
G01X1353921Y978747D02*
X1354106Y979347D01*
X1355136D01*
X1355321Y978747D01*
Y978573D01*
X1353921D01*
Y978747D01*
G37*
G36*
G01X1357654Y978749D02*
X1357839Y979349D01*
X1358869D01*
X1359054Y978749D01*
Y978574D01*
X1357654D01*
Y978749D01*
G37*
G36*
G01X1361321Y978747D02*
X1361506Y979347D01*
X1362536D01*
X1362721Y978747D01*
Y978573D01*
X1361321D01*
Y978747D01*
G37*
G36*
G01X1353921D02*
X1354106Y979347D01*
X1355136D01*
X1355321Y978747D01*
Y978573D01*
X1353921D01*
Y978747D01*
G37*
G36*
G01X1357654Y978749D02*
X1357839Y979349D01*
X1358869D01*
X1359054Y978749D01*
Y978574D01*
X1357654D01*
Y978749D01*
G37*
G36*
G01X1361321Y978747D02*
X1361506Y979347D01*
X1362536D01*
X1362721Y978747D01*
Y978573D01*
X1361321D01*
Y978747D01*
G37*
G36*
G01X1347954Y973947D02*
X1347769Y973347D01*
X1346739D01*
X1346554Y973947D01*
Y974121D01*
X1347954D01*
Y973947D01*
G37*
G36*
G01X1351654D02*
X1351469Y973347D01*
X1350439D01*
X1350254Y973947D01*
Y974121D01*
X1351654D01*
Y973947D01*
G37*
G36*
G01X1347954D02*
X1347769Y973347D01*
X1346739D01*
X1346554Y973947D01*
Y974121D01*
X1347954D01*
Y973947D01*
G37*
G36*
G01X1351654D02*
X1351469Y973347D01*
X1350439D01*
X1350254Y973947D01*
Y974121D01*
X1351654D01*
Y973947D01*
G37*
G36*
G01X1355297D02*
X1355112Y973347D01*
X1354082D01*
X1353897Y973947D01*
Y974122D01*
X1355297D01*
Y973947D01*
G37*
G36*
G01X1359044D02*
X1358859Y973347D01*
X1357829D01*
X1357644Y973947D01*
Y974121D01*
X1359044D01*
Y973947D01*
G37*
G36*
G01X1362697D02*
X1362512Y973347D01*
X1361482D01*
X1361297Y973947D01*
Y974122D01*
X1362697D01*
Y973947D01*
G37*
G36*
G01X1355297D02*
X1355112Y973347D01*
X1354082D01*
X1353897Y973947D01*
Y974122D01*
X1355297D01*
Y973947D01*
G37*
G36*
G01X1359044D02*
X1358859Y973347D01*
X1357829D01*
X1357644Y973947D01*
Y974121D01*
X1359044D01*
Y973947D01*
G37*
G36*
G01X1362697D02*
X1362512Y973347D01*
X1361482D01*
X1361297Y973947D01*
Y974122D01*
X1362697D01*
Y973947D01*
G37*
G36*
G01X1346554Y965931D02*
X1346739Y966531D01*
X1347769D01*
X1347954Y965931D01*
Y965757D01*
X1346554D01*
Y965931D01*
G37*
G36*
G01D02*
X1346739Y966531D01*
X1347769D01*
X1347954Y965931D01*
Y965757D01*
X1346554D01*
Y965931D01*
G37*
G36*
G01X1350254Y972339D02*
X1350439Y972939D01*
X1351469D01*
X1351654Y972339D01*
Y972165D01*
X1350254D01*
Y972339D01*
G37*
G36*
G01X1348485Y970521D02*
X1348058Y970981D01*
X1348573Y971873D01*
X1349185Y971733D01*
X1349336Y971646D01*
X1348636Y970434D01*
X1348485Y970521D01*
G37*
G36*
G01X1352634Y971771D02*
X1353246Y971911D01*
X1353761Y971019D01*
X1353334Y970559D01*
X1353183Y970472D01*
X1352483Y971684D01*
X1352634Y971771D01*
G37*
G36*
G01X1350254Y972339D02*
X1350439Y972939D01*
X1351469D01*
X1351654Y972339D01*
Y972165D01*
X1350254D01*
Y972339D01*
G37*
G36*
G01X1348485Y970521D02*
X1348058Y970981D01*
X1348573Y971873D01*
X1349185Y971733D01*
X1349336Y971646D01*
X1348636Y970434D01*
X1348485Y970521D01*
G37*
G36*
G01X1352634Y971771D02*
X1353246Y971911D01*
X1353761Y971019D01*
X1353334Y970559D01*
X1353183Y970472D01*
X1352483Y971684D01*
X1352634Y971771D01*
G37*
G36*
G01X1349639Y969329D02*
X1350066Y968869D01*
X1349551Y967977D01*
X1348939Y968117D01*
X1348788Y968204D01*
X1349488Y969416D01*
X1349639Y969329D01*
G37*
G36*
G01X1347921Y967539D02*
X1347736Y966939D01*
X1346706D01*
X1346521Y967539D01*
Y967714D01*
X1347921D01*
Y967539D01*
G37*
G36*
G01X1352885Y968145D02*
X1352273Y968005D01*
X1351758Y968897D01*
X1352185Y969357D01*
X1352336Y969444D01*
X1353036Y968232D01*
X1352885Y968145D01*
G37*
G36*
G01X1349639Y969329D02*
X1350066Y968869D01*
X1349551Y967977D01*
X1348939Y968117D01*
X1348788Y968204D01*
X1349488Y969416D01*
X1349639Y969329D01*
G37*
G36*
G01X1347921Y967539D02*
X1347736Y966939D01*
X1346706D01*
X1346521Y967539D01*
Y967714D01*
X1347921D01*
Y967539D01*
G37*
G36*
G01X1352885Y968145D02*
X1352273Y968005D01*
X1351758Y968897D01*
X1352185Y969357D01*
X1352336Y969444D01*
X1353036Y968232D01*
X1352885Y968145D01*
G37*
G36*
G01X1350169Y997283D02*
X1349984Y996683D01*
X1348954D01*
X1348769Y997283D01*
Y997458D01*
X1350169D01*
Y997283D01*
G37*
G36*
G01X1347789Y997852D02*
X1347177Y997712D01*
X1346662Y998604D01*
X1347089Y999064D01*
X1347240Y999151D01*
X1347940Y997939D01*
X1347789Y997852D01*
G37*
G36*
G01X1353870Y997283D02*
X1353685Y996683D01*
X1352655D01*
X1352470Y997283D01*
Y997458D01*
X1353870D01*
Y997283D01*
G37*
G36*
G01X1350169D02*
X1349984Y996683D01*
X1348954D01*
X1348769Y997283D01*
Y997458D01*
X1350169D01*
Y997283D01*
G37*
G36*
G01X1347789Y997852D02*
X1347177Y997712D01*
X1346662Y998604D01*
X1347089Y999064D01*
X1347240Y999151D01*
X1347940Y997939D01*
X1347789Y997852D01*
G37*
G36*
G01X1353870Y997283D02*
X1353685Y996683D01*
X1352655D01*
X1352470Y997283D01*
Y997458D01*
X1353870D01*
Y997283D01*
G37*
G36*
G01X1346987Y1005289D02*
X1347172Y1005889D01*
X1348202D01*
X1348387Y1005289D01*
Y1005115D01*
X1346987D01*
Y1005289D01*
G37*
G36*
G01D02*
X1347172Y1005889D01*
X1348202D01*
X1348387Y1005289D01*
Y1005115D01*
X1346987D01*
Y1005289D01*
G37*
G36*
G01X1350686Y998881D02*
X1350871Y999481D01*
X1351901D01*
X1352086Y998881D01*
Y998706D01*
X1350686D01*
Y998881D01*
G37*
G36*
G01X1347539Y1001478D02*
X1348151Y1001618D01*
X1348666Y1000726D01*
X1348239Y1000266D01*
X1348088Y1000179D01*
X1347388Y1001391D01*
X1347539Y1001478D01*
G37*
G36*
G01X1350686Y998881D02*
X1350871Y999481D01*
X1351901D01*
X1352086Y998881D01*
Y998706D01*
X1350686D01*
Y998881D01*
G37*
G36*
G01X1347539Y1001478D02*
X1348151Y1001618D01*
X1348666Y1000726D01*
X1348239Y1000266D01*
X1348088Y1000179D01*
X1347388Y1001391D01*
X1347539Y1001478D01*
G37*
G36*
G01X1352054Y1000489D02*
X1351869Y999889D01*
X1350839D01*
X1350654Y1000489D01*
Y1000663D01*
X1352054D01*
Y1000489D01*
G37*
G36*
G01D02*
X1351869Y999889D01*
X1350839D01*
X1350654Y1000489D01*
Y1000663D01*
X1352054D01*
Y1000489D01*
G37*
G36*
G01X1350687Y1011697D02*
X1350872Y1012297D01*
X1351902D01*
X1352087Y1011697D01*
Y1011523D01*
X1350687D01*
Y1011697D01*
G37*
G36*
G01X1346954D02*
X1347139Y1012297D01*
X1348169D01*
X1348354Y1011697D01*
Y1011522D01*
X1346954D01*
Y1011697D01*
G37*
G36*
G01X1350687D02*
X1350872Y1012297D01*
X1351902D01*
X1352087Y1011697D01*
Y1011523D01*
X1350687D01*
Y1011697D01*
G37*
G36*
G01X1346954D02*
X1347139Y1012297D01*
X1348169D01*
X1348354Y1011697D01*
Y1011522D01*
X1346954D01*
Y1011697D01*
G37*
G36*
G01X1350180Y1010101D02*
X1349995Y1009501D01*
X1348965D01*
X1348780Y1010101D01*
Y1010276D01*
X1350180D01*
Y1010101D01*
G37*
G36*
G01X1353870D02*
X1353685Y1009501D01*
X1352655D01*
X1352470Y1010101D01*
Y1010275D01*
X1353870D01*
Y1010101D01*
G37*
G36*
G01X1350180D02*
X1349995Y1009501D01*
X1348965D01*
X1348780Y1010101D01*
Y1010276D01*
X1350180D01*
Y1010101D01*
G37*
G36*
G01X1353870D02*
X1353685Y1009501D01*
X1352655D01*
X1352470Y1010101D01*
Y1010275D01*
X1353870D01*
Y1010101D01*
G37*
G36*
G01X1352087Y1006897D02*
X1351902Y1006297D01*
X1350872D01*
X1350687Y1006897D01*
Y1007071D01*
X1352087D01*
Y1006897D01*
G37*
G36*
G01X1348354D02*
X1348169Y1006297D01*
X1347139D01*
X1346954Y1006897D01*
Y1007072D01*
X1348354D01*
Y1006897D01*
G37*
G36*
G01X1352087D02*
X1351902Y1006297D01*
X1350872D01*
X1350687Y1006897D01*
Y1007071D01*
X1352087D01*
Y1006897D01*
G37*
G36*
G01X1348354D02*
X1348169Y1006297D01*
X1347139D01*
X1346954Y1006897D01*
Y1007072D01*
X1348354D01*
Y1006897D01*
G37*
G36*
G01X1348377Y1019715D02*
X1348192Y1019115D01*
X1347162D01*
X1346977Y1019715D01*
Y1019889D01*
X1348377D01*
Y1019715D01*
G37*
G36*
G01D02*
X1348192Y1019115D01*
X1347162D01*
X1346977Y1019715D01*
Y1019889D01*
X1348377D01*
Y1019715D01*
G37*
G36*
G01X1351924Y1018303D02*
X1352351Y1017843D01*
X1351836Y1016951D01*
X1351224Y1017091D01*
X1351073Y1017178D01*
X1351773Y1018390D01*
X1351924Y1018303D01*
G37*
G36*
G01X1350203Y1016509D02*
X1350018Y1015909D01*
X1348988D01*
X1348803Y1016509D01*
Y1016684D01*
X1350203D01*
Y1016509D01*
G37*
G36*
G01X1351924Y1018303D02*
X1352351Y1017843D01*
X1351836Y1016951D01*
X1351224Y1017091D01*
X1351073Y1017178D01*
X1351773Y1018390D01*
X1351924Y1018303D01*
G37*
G36*
G01X1350203Y1016509D02*
X1350018Y1015909D01*
X1348988D01*
X1348803Y1016509D01*
Y1016684D01*
X1350203D01*
Y1016509D01*
G37*
G36*
G01X1346977Y1018105D02*
X1347162Y1018705D01*
X1348192D01*
X1348377Y1018105D01*
Y1017931D01*
X1346977D01*
Y1018105D01*
G37*
G36*
G01X1350768Y1019491D02*
X1350341Y1019951D01*
X1350856Y1020843D01*
X1351468Y1020703D01*
X1351619Y1020616D01*
X1350919Y1019404D01*
X1350768Y1019491D01*
G37*
G36*
G01X1346977Y1018105D02*
X1347162Y1018705D01*
X1348192D01*
X1348377Y1018105D01*
Y1017931D01*
X1346977D01*
Y1018105D01*
G37*
G36*
G01X1350768Y1019491D02*
X1350341Y1019951D01*
X1350856Y1020843D01*
X1351468Y1020703D01*
X1351619Y1020616D01*
X1350919Y1019404D01*
X1350768Y1019491D01*
G37*
G36*
G01X1348836Y1027719D02*
X1349021Y1028319D01*
X1350051D01*
X1350236Y1027719D01*
Y1027545D01*
X1348836D01*
Y1027719D01*
G37*
G36*
G01D02*
X1349021Y1028319D01*
X1350051D01*
X1350236Y1027719D01*
Y1027545D01*
X1348836D01*
Y1027719D01*
G37*
G36*
G01X1348353Y1026123D02*
X1348168Y1025523D01*
X1347138D01*
X1346953Y1026123D01*
Y1026297D01*
X1348353D01*
Y1026123D01*
G37*
G36*
G01D02*
X1348168Y1025523D01*
X1347138D01*
X1346953Y1026123D01*
Y1026297D01*
X1348353D01*
Y1026123D01*
G37*
G36*
G01X1352087Y1032531D02*
X1351902Y1031931D01*
X1350872D01*
X1350687Y1032531D01*
Y1032705D01*
X1352087D01*
Y1032531D01*
G37*
G36*
G01X1348387D02*
X1348202Y1031931D01*
X1347172D01*
X1346987Y1032531D01*
Y1032705D01*
X1348387D01*
Y1032531D01*
G37*
G36*
G01X1352087D02*
X1351902Y1031931D01*
X1350872D01*
X1350687Y1032531D01*
Y1032705D01*
X1352087D01*
Y1032531D01*
G37*
G36*
G01X1348387D02*
X1348202Y1031931D01*
X1347172D01*
X1346987Y1032531D01*
Y1032705D01*
X1348387D01*
Y1032531D01*
G37*
G36*
G01X1348770Y1034127D02*
X1348955Y1034727D01*
X1349985D01*
X1350170Y1034127D01*
Y1033953D01*
X1348770D01*
Y1034127D01*
G37*
G36*
G01X1352470D02*
X1352655Y1034727D01*
X1353685D01*
X1353870Y1034127D01*
Y1033953D01*
X1352470D01*
Y1034127D01*
G37*
G36*
G01X1348770D02*
X1348955Y1034727D01*
X1349985D01*
X1350170Y1034127D01*
Y1033953D01*
X1348770D01*
Y1034127D01*
G37*
G36*
G01X1352470D02*
X1352655Y1034727D01*
X1353685D01*
X1353870Y1034127D01*
Y1033953D01*
X1352470D01*
Y1034127D01*
G37*
G36*
G01X1350687Y1030923D02*
X1350872Y1031523D01*
X1351902D01*
X1352087Y1030923D01*
Y1030749D01*
X1350687D01*
Y1030923D01*
G37*
G36*
G01X1346987D02*
X1347172Y1031523D01*
X1348202D01*
X1348387Y1030923D01*
Y1030749D01*
X1346987D01*
Y1030923D01*
G37*
G36*
G01X1350687D02*
X1350872Y1031523D01*
X1351902D01*
X1352087Y1030923D01*
Y1030749D01*
X1350687D01*
Y1030923D01*
G37*
G36*
G01X1346987D02*
X1347172Y1031523D01*
X1348202D01*
X1348387Y1030923D01*
Y1030749D01*
X1346987D01*
Y1030923D01*
G37*
G36*
G01X1346940Y1037331D02*
X1347125Y1037931D01*
X1348155D01*
X1348340Y1037331D01*
Y1037156D01*
X1346940D01*
Y1037331D01*
G37*
G36*
G01D02*
X1347125Y1037931D01*
X1348155D01*
X1348340Y1037331D01*
Y1037156D01*
X1346940D01*
Y1037331D01*
G37*
G36*
G01X1348377Y1038941D02*
X1348192Y1038341D01*
X1347162D01*
X1346977Y1038941D01*
Y1039115D01*
X1348377D01*
Y1038941D01*
G37*
G36*
G01D02*
X1348192Y1038341D01*
X1347162D01*
X1346977Y1038941D01*
Y1039115D01*
X1348377D01*
Y1038941D01*
G37*
G36*
G01X1350217Y1035737D02*
X1350032Y1035137D01*
X1349002D01*
X1348817Y1035737D01*
Y1035911D01*
X1350217D01*
Y1035737D01*
G37*
G36*
G01D02*
X1350032Y1035137D01*
X1349002D01*
X1348817Y1035737D01*
Y1035911D01*
X1350217D01*
Y1035737D01*
G37*
G36*
G01X1346987Y1043741D02*
X1347172Y1044341D01*
X1348202D01*
X1348387Y1043741D01*
Y1043566D01*
X1346987D01*
Y1043741D01*
G37*
G36*
G01D02*
X1347172Y1044341D01*
X1348202D01*
X1348387Y1043741D01*
Y1043566D01*
X1346987D01*
Y1043741D01*
G37*
G36*
G01X1350677Y1056557D02*
X1350862Y1057157D01*
X1351892D01*
X1352077Y1056557D01*
Y1056383D01*
X1350677D01*
Y1056557D01*
G37*
G36*
G01X1346977D02*
X1347162Y1057157D01*
X1348192D01*
X1348377Y1056557D01*
Y1056382D01*
X1346977D01*
Y1056557D01*
G37*
G36*
G01X1350677D02*
X1350862Y1057157D01*
X1351892D01*
X1352077Y1056557D01*
Y1056383D01*
X1350677D01*
Y1056557D01*
G37*
G36*
G01X1346977D02*
X1347162Y1057157D01*
X1348192D01*
X1348377Y1056557D01*
Y1056382D01*
X1346977D01*
Y1056557D01*
G37*
G36*
G01X1352020Y1058165D02*
X1351835Y1057565D01*
X1350805D01*
X1350620Y1058165D01*
Y1058339D01*
X1352020D01*
Y1058165D01*
G37*
G36*
G01X1348377D02*
X1348192Y1057565D01*
X1347162D01*
X1346977Y1058165D01*
Y1058340D01*
X1348377D01*
Y1058165D01*
G37*
G36*
G01X1352020D02*
X1351835Y1057565D01*
X1350805D01*
X1350620Y1058165D01*
Y1058339D01*
X1352020D01*
Y1058165D01*
G37*
G36*
G01X1348377D02*
X1348192Y1057565D01*
X1347162D01*
X1346977Y1058165D01*
Y1058340D01*
X1348377D01*
Y1058165D01*
G37*
G36*
G01X1350203Y1054961D02*
X1350018Y1054361D01*
X1348988D01*
X1348803Y1054961D01*
Y1055136D01*
X1350203D01*
Y1054961D01*
G37*
G36*
G01D02*
X1350018Y1054361D01*
X1348988D01*
X1348803Y1054961D01*
Y1055136D01*
X1350203D01*
Y1054961D01*
G37*
G36*
G01X1348770Y1053353D02*
X1348955Y1053953D01*
X1349985D01*
X1350170Y1053353D01*
Y1053179D01*
X1348770D01*
Y1053353D01*
G37*
G36*
G01D02*
X1348955Y1053953D01*
X1349985D01*
X1350170Y1053353D01*
Y1053179D01*
X1348770D01*
Y1053353D01*
G37*
G36*
G01X1346987Y1050149D02*
X1347172Y1050749D01*
X1348202D01*
X1348387Y1050149D01*
Y1049975D01*
X1346987D01*
Y1050149D01*
G37*
G36*
G01D02*
X1347172Y1050749D01*
X1348202D01*
X1348387Y1050149D01*
Y1049975D01*
X1346987D01*
Y1050149D01*
G37*
G36*
G01X1348387Y1051755D02*
X1348202Y1051155D01*
X1347172D01*
X1346987Y1051755D01*
Y1051930D01*
X1348387D01*
Y1051755D01*
G37*
G36*
G01D02*
X1348202Y1051155D01*
X1347172D01*
X1346987Y1051755D01*
Y1051930D01*
X1348387D01*
Y1051755D01*
G37*
G36*
G01X1346987Y1062967D02*
X1347172Y1063567D01*
X1348202D01*
X1348387Y1062967D01*
Y1062792D01*
X1346987D01*
Y1062967D01*
G37*
G36*
G01D02*
X1347172Y1063567D01*
X1348202D01*
X1348387Y1062967D01*
Y1062792D01*
X1346987D01*
Y1062967D01*
G37*
G36*
G01X1348387Y1070981D02*
X1348202Y1070381D01*
X1347172D01*
X1346987Y1070981D01*
Y1071156D01*
X1348387D01*
Y1070981D01*
G37*
G36*
G01D02*
X1348202Y1070381D01*
X1347172D01*
X1346987Y1070981D01*
Y1071156D01*
X1348387D01*
Y1070981D01*
G37*
G36*
G01X1348770Y1072579D02*
X1348955Y1073179D01*
X1349985D01*
X1350170Y1072579D01*
Y1072405D01*
X1348770D01*
Y1072579D01*
G37*
G36*
G01D02*
X1348955Y1073179D01*
X1349985D01*
X1350170Y1072579D01*
Y1072405D01*
X1348770D01*
Y1072579D01*
G37*
G36*
G01X1346954Y1069373D02*
X1347139Y1069973D01*
X1348169D01*
X1348354Y1069373D01*
Y1069199D01*
X1346954D01*
Y1069373D01*
G37*
G36*
G01D02*
X1347139Y1069973D01*
X1348169D01*
X1348354Y1069373D01*
Y1069199D01*
X1346954D01*
Y1069373D01*
G37*
G36*
G01X1346977Y1075783D02*
X1347162Y1076383D01*
X1348192D01*
X1348377Y1075783D01*
Y1075608D01*
X1346977D01*
Y1075783D01*
G37*
G36*
G01D02*
X1347162Y1076383D01*
X1348192D01*
X1348377Y1075783D01*
Y1075608D01*
X1346977D01*
Y1075783D01*
G37*
G36*
G01X1350677D02*
X1350862Y1076383D01*
X1351892D01*
X1352077Y1075783D01*
Y1075609D01*
X1350677D01*
Y1075783D01*
G37*
G36*
G01D02*
X1350862Y1076383D01*
X1351892D01*
X1352077Y1075783D01*
Y1075609D01*
X1350677D01*
Y1075783D01*
G37*
G36*
G01X1348377Y1077391D02*
X1348192Y1076791D01*
X1347162D01*
X1346977Y1077391D01*
Y1077566D01*
X1348377D01*
Y1077391D01*
G37*
G36*
G01D02*
X1348192Y1076791D01*
X1347162D01*
X1346977Y1077391D01*
Y1077566D01*
X1348377D01*
Y1077391D01*
G37*
G36*
G01X1352020D02*
X1351835Y1076791D01*
X1350805D01*
X1350620Y1077391D01*
Y1077565D01*
X1352020D01*
Y1077391D01*
G37*
G36*
G01D02*
X1351835Y1076791D01*
X1350805D01*
X1350620Y1077391D01*
Y1077565D01*
X1352020D01*
Y1077391D01*
G37*
G36*
G01X1350203Y1074187D02*
X1350018Y1073587D01*
X1348988D01*
X1348803Y1074187D01*
Y1074362D01*
X1350203D01*
Y1074187D01*
G37*
G36*
G01D02*
X1350018Y1073587D01*
X1348988D01*
X1348803Y1074187D01*
Y1074362D01*
X1350203D01*
Y1074187D01*
G37*
G36*
G01X1348804Y1091803D02*
X1348989Y1092403D01*
X1350019D01*
X1350204Y1091803D01*
Y1091629D01*
X1348804D01*
Y1091803D01*
G37*
G36*
G01D02*
X1348989Y1092403D01*
X1350019D01*
X1350204Y1091803D01*
Y1091629D01*
X1348804D01*
Y1091803D01*
G37*
G36*
G01X1346987Y1082191D02*
X1347172Y1082791D01*
X1348202D01*
X1348387Y1082191D01*
Y1082017D01*
X1346987D01*
Y1082191D01*
G37*
G36*
G01D02*
X1347172Y1082791D01*
X1348202D01*
X1348387Y1082191D01*
Y1082017D01*
X1346987D01*
Y1082191D01*
G37*
G36*
G01X1350687D02*
X1350872Y1082791D01*
X1351902D01*
X1352087Y1082191D01*
Y1082017D01*
X1350687D01*
Y1082191D01*
G37*
G36*
G01D02*
X1350872Y1082791D01*
X1351902D01*
X1352087Y1082191D01*
Y1082017D01*
X1350687D01*
Y1082191D01*
G37*
G36*
G01X1393187Y875141D02*
G03X1394025Y873935I3983J1874D01*
G03X1394019Y873810I1295J-125D01*
G03X1394781Y872626I1301J0D01*
G03X1395407Y871296I4239J1183D01*
G01X1395443Y871245D01*
Y869968D01*
X1395407Y869916D01*
G03X1394780Y868584I3613J-2514D01*
G03X1394020Y867401I541J-1183D01*
G03X1394781Y866218I1300J0D01*
G03X1395876Y864321I4239J1182D01*
G03X1395870Y864197I1295J-125D01*
G03X1396631Y863013I1302J0D01*
G03X1397711Y861132I4240J1184D01*
G02X1397724Y861117I-144J-138D01*
G03X1397718Y860993I1296J-125D01*
G03X1397724Y860869I1302J1D01*
G02X1397711Y860854I-157J123D01*
G03X1396631Y858973I3160J-3065D01*
G03X1395870Y857789I541J-1184D01*
G03X1396630Y856606I1301J0D01*
G03X1397725Y854708I4242J1182D01*
G03X1397719Y854584I1295J-125D01*
G03X1398481Y853400I1301J0D01*
G03X1399576Y851504I4240J1184D01*
G03X1399570Y851380I1295J-125D01*
G03X1399996Y850417I1301J0D01*
G01Y849376D01*
X1399980Y849339D01*
G03X1399744Y848176I2740J-1162D01*
G01Y848081D01*
X1399496Y847833D01*
G02X1398899Y847870I-282J284D01*
G03X1398767Y848027I-2343J-1836D01*
G03X1398514Y848597I-2832J-916D01*
G01X1397898Y849664D01*
G03X1397826Y849782I-2576J-1491D01*
G02X1397929Y850323I337J216D01*
G03X1398472Y851380I-757J1057D01*
G03X1397171Y852681I-1301J0D01*
G03X1395876Y851509I0J-1301D01*
G02X1395460Y851149I-398J39D01*
G03X1395320Y851152I-134J-2973D01*
G03X1395182Y851149I-4J-2976D01*
G02X1394766Y851509I-18J400D01*
G03X1393471Y852681I-1295J-129D01*
G03X1392170Y851380I0J-1301D01*
G03X1392711Y850324I1301J0D01*
G02X1392815Y849783I-233J-325D01*
G03X1392344Y848176I2506J-1607D01*
G01Y848173D01*
G03X1392376Y847739I2976J1D01*
G03X1392069Y847598I1087J-2771D01*
G01X1392025Y847574D01*
X1391705D01*
X1391646Y847665D01*
G03X1391367Y848027I-2490J-1631D01*
G03X1391114Y848597I-2832J-916D01*
G01X1390498Y849664D01*
G03X1390426Y849782I-2576J-1491D01*
G02X1390529Y850323I337J216D01*
G03X1391072Y851380I-757J1057D01*
G03X1389771Y852681I-1301J0D01*
G03X1388476Y851509I0J-1301D01*
G02X1388060Y851149I-398J39D01*
G03X1387920Y851152I-134J-2973D01*
G03X1387782Y851149I-4J-2976D01*
G02X1387366Y851509I-18J400D01*
G03X1386071Y852681I-1295J-129D01*
G03X1384770Y851380I0J-1301D01*
G03X1385311Y850324I1301J0D01*
G02X1385415Y849783I-233J-325D01*
G03X1384944Y848176I2506J-1607D01*
G01Y848173D01*
G03X1384976Y847739I2976J1D01*
G03X1384669Y847598I1087J-2771D01*
G01X1384625Y847574D01*
X1384305D01*
X1384246Y847665D01*
G03X1383967Y848027I-2490J-1631D01*
G03X1383714Y848597I-2832J-916D01*
G01X1383098Y849664D01*
G03X1383026Y849782I-2576J-1491D01*
G02X1383129Y850323I337J216D01*
G03X1383672Y851380I-757J1057D01*
G03X1382371Y852681I-1301J0D01*
G03X1381076Y851509I0J-1301D01*
G02X1380660Y851149I-398J39D01*
G03X1380520Y851152I-134J-2973D01*
G03X1380382Y851149I-4J-2976D01*
G02X1379966Y851509I-18J400D01*
G03X1378671Y852681I-1295J-129D01*
G03X1377370Y851380I0J-1301D01*
G03X1377911Y850324I1301J0D01*
G02X1378015Y849783I-233J-325D01*
G03X1377544Y848176I2506J-1607D01*
G01Y848173D01*
G03X1377576Y847739I2976J1D01*
G03X1377269Y847598I1087J-2771D01*
G01X1377225Y847574D01*
X1376905D01*
X1376846Y847665D01*
G03X1376567Y848027I-2490J-1631D01*
G03X1376314Y848597I-2832J-916D01*
G01X1375698Y849664D01*
G03X1375626Y849782I-2576J-1491D01*
G02X1375729Y850323I337J216D01*
G03X1376272Y851380I-757J1057D01*
G03X1374971Y852681I-1301J0D01*
G03X1374542Y852608I1J-1301D01*
G02X1374010Y852985I-132J378D01*
G01Y853634D01*
G03Y855534I-889J950D01*
G01Y856184D01*
G02X1374542Y856561I400J-1D01*
G03X1374731Y856510I432J1227D01*
G01X1374821Y856493D01*
X1375623Y855103D01*
X1375593Y855016D01*
G03X1375519Y854584I1227J-433D01*
G03X1378121I1301J0D01*
G03X1377060Y855863I-1301J0D01*
G01X1376970Y855880D01*
X1376168Y857270D01*
X1376198Y857357D01*
G03X1376272Y857789I-1227J433D01*
G03X1374971Y859090I-1301J0D01*
G03X1374542Y859017I1J-1301D01*
G02X1374010Y859394I-132J378D01*
G01Y860044D01*
G03X1374421Y860993I-890J949D01*
G03X1374397Y861241I-1301J-1D01*
G01X1374377Y861346D01*
X1376830Y863799D01*
G02X1377479Y863676I282J-283D01*
G03X1378671Y862896I1192J521D01*
G03X1379972Y864197I0J1301D01*
G03X1379192Y865389I-1301J0D01*
G02X1379069Y866038I160J367D01*
G01X1379549Y866518D01*
X1379689Y866401D01*
G03X1380521Y866100I832J999D01*
G03X1381822Y867401I0J1301D01*
G03X1381521Y868233I-1300J0D01*
G01X1381404Y868373D01*
X1381897Y868866D01*
G02X1382526Y868783I283J-283D01*
G01X1383023Y867920D01*
X1382993Y867833D01*
G03X1382919Y867401I1227J-433D01*
G03X1385521I1301J0D01*
G03X1384460Y868680I-1301J0D01*
G01X1384370Y868697D01*
X1383568Y870087D01*
X1383598Y870174D01*
G03X1383671Y870564I-1227J432D01*
G01X1383674Y870643D01*
X1386206Y873175D01*
G02X1386825Y873108I282J-283D01*
G03X1387680Y872531I1096J702D01*
G01X1387770Y872514D01*
X1388573Y871122D01*
X1388543Y871036D01*
G03X1388470Y870607I1228J-430D01*
G01Y870606D01*
G03X1391072I1301J0D01*
G03X1390009Y871885I-1301J0D01*
G01X1389918Y871902D01*
X1389117Y873291D01*
X1389147Y873378D01*
G03X1389221Y873810I-1227J433D01*
G03X1389009Y874522I-1302J0D01*
G02X1389343Y875141I335J219D01*
G01X1393187D01*
G37*
G36*
G01X1378331Y1027795D02*
X1379539D01*
G02X1379915Y1027260I0J-400D01*
G03X1379839Y1026821I1225J-438D01*
G03X1381140Y1025520I1301J0D01*
G03X1382315Y1026262I0J1301D01*
G02X1382959Y1026373I361J-172D01*
G01X1383817Y1025515D01*
Y1016229D01*
G02X1383372Y1015832I-400J0D01*
G03X1383226Y1015840I-144J-1293D01*
G03Y1013238I0J-1301D01*
G03X1383372Y1013246I2J1301D01*
G02X1383817Y1012849I45J-397D01*
G01Y983435D01*
X1388957Y978295D01*
Y964825D01*
X1382777Y958645D01*
Y949845D01*
G02X1382121Y949538I-400J0D01*
G03X1381287Y949840I-833J-999D01*
G03X1379986Y948539I0J-1301D01*
G03X1380328Y947659I1301J-1D01*
G02Y947119I-294J-270D01*
G03X1379986Y946239I959J-879D01*
G03X1381287Y944938I1301J0D01*
G03X1382405Y945574I0J1301D01*
G01X1382463Y945672D01*
X1382777D01*
Y945115D01*
X1382127Y944465D01*
X1374420D01*
X1374383Y944617D01*
G03X1373120Y945605I-1263J-313D01*
G03X1372241Y945263I0J-1301D01*
G02X1371687Y945275I-271J294D01*
G01X1371389Y945573D01*
G02X1371578Y946245I283J283D01*
G03X1372572Y947509I-307J1264D01*
G03X1371271Y948810I-1301J0D01*
G03X1371222Y948809I2J-1301D01*
G02X1370807Y949209I-15J400D01*
G01Y952217D01*
G02X1371222Y952617I400J0D01*
G03X1371271Y952616I51J1300D01*
G03Y955218I0J1301D01*
G03X1371222Y955217I2J-1301D01*
G02X1370807Y955617I-15J400D01*
G01Y958626D01*
G02X1371222Y959026I400J0D01*
G03X1371271Y959025I51J1300D01*
G03Y961627I0J1301D01*
G03X1371042Y961607I-2J-1301D01*
G01X1371025Y961604D01*
X1370807D01*
Y961955D01*
X1371551Y962699D01*
G02X1372137Y962678I283J-282D01*
G03X1373120Y962229I983J852D01*
G03X1374421Y963530I0J1301D01*
G03X1373972Y964513I-1301J0D01*
G02X1373951Y965099I261J303D01*
G01X1374407Y965555D01*
X1374527Y965512D01*
G03X1374971Y965434I444J1223D01*
G03X1376272Y966735I0J1301D01*
G03X1376194Y967179I-1301J0D01*
G01X1376151Y967299D01*
X1379787Y970935D01*
Y972472D01*
X1379812Y972517D01*
G03X1379972Y973143I-1141J625D01*
G03X1379812Y973769I-1301J1D01*
G01X1379787Y973814D01*
Y977477D01*
G02X1380379Y977827I400J-1D01*
G03X1381003Y977668I623J1142D01*
G03X1382304Y978969I0J1301D01*
G03X1381962Y979849I-1301J1D01*
G02Y980389I294J270D01*
G03X1382304Y981269I-959J879D01*
G03X1381003Y982570I-1301J0D01*
G03X1379743Y981593I0J-1301D01*
G02X1379073Y981409I-387J99D01*
G01X1378077Y982405D01*
X1378097Y982509D01*
G03X1378121Y982756I-1277J249D01*
G03X1376913Y984054I-1301J0D01*
G02X1376727Y984253I14J199D01*
G01Y999219D01*
X1376737Y999249D01*
G03X1376806Y999684I-1333J434D01*
G03X1376737Y1000119I-1402J1D01*
G01X1376727Y1000149D01*
Y1001192D01*
G02X1377157Y1001591I400J0D01*
G03X1377253Y1001587I102J1297D01*
G03Y1004189I0J1301D01*
G03X1376164Y1003600I0J-1301D01*
G02X1375546Y1003536I-335J219D01*
G01X1373217Y1005865D01*
Y1007597D01*
G02X1373602Y1007997I400J0D01*
G03Y1010597I-48J1300D01*
G02X1373217Y1010997I15J400D01*
G01Y1014005D01*
G02X1373602Y1014405I400J0D01*
G03Y1017005I-49J1300D01*
G02X1373217Y1017405I15J400D01*
G01Y1020414D01*
G02X1373602Y1020814I400J0D01*
G03Y1023414I-49J1300D01*
G02X1373217Y1023814I15J400D01*
G01Y1025525D01*
X1375487Y1027795D01*
X1376175D01*
G03X1378331I1078J728D01*
G37*
G36*
G01X1364547Y977151D02*
X1364362Y976551D01*
X1363332D01*
X1363147Y977151D01*
Y977326D01*
X1364547D01*
Y977151D01*
G37*
G36*
G01X1368237D02*
X1368052Y976551D01*
X1367022D01*
X1366837Y977151D01*
Y977325D01*
X1368237D01*
Y977151D01*
G37*
G36*
G01X1364547D02*
X1364362Y976551D01*
X1363332D01*
X1363147Y977151D01*
Y977326D01*
X1364547D01*
Y977151D01*
G37*
G36*
G01X1368237D02*
X1368052Y976551D01*
X1367022D01*
X1366837Y977151D01*
Y977325D01*
X1368237D01*
Y977151D01*
G37*
G36*
G01X1363194Y975543D02*
X1363379Y976143D01*
X1364409D01*
X1364594Y975543D01*
Y975368D01*
X1363194D01*
Y975543D01*
G37*
G36*
G01X1366837D02*
X1367022Y976143D01*
X1368052D01*
X1368237Y975543D01*
Y975369D01*
X1366837D01*
Y975543D01*
G37*
G36*
G01X1369306Y974937D02*
X1369918Y975077D01*
X1370433Y974185D01*
X1370006Y973725D01*
X1369855Y973638D01*
X1369155Y974850D01*
X1369306Y974937D01*
G37*
G36*
G01X1372421Y972339D02*
X1372606Y972939D01*
X1373636D01*
X1373821Y972339D01*
Y972164D01*
X1372421D01*
Y972339D01*
G37*
G36*
G01X1363194Y975543D02*
X1363379Y976143D01*
X1364409D01*
X1364594Y975543D01*
Y975368D01*
X1363194D01*
Y975543D01*
G37*
G36*
G01X1366837D02*
X1367022Y976143D01*
X1368052D01*
X1368237Y975543D01*
Y975369D01*
X1366837D01*
Y975543D01*
G37*
G36*
G01X1369306Y974937D02*
X1369918Y975077D01*
X1370433Y974185D01*
X1370006Y973725D01*
X1369855Y973638D01*
X1369155Y974850D01*
X1369306Y974937D01*
G37*
G36*
G01X1372421Y972339D02*
X1372606Y972939D01*
X1373636D01*
X1373821Y972339D01*
Y972164D01*
X1372421D01*
Y972339D01*
G37*
G36*
G01X1365054Y978749D02*
X1365239Y979349D01*
X1366269D01*
X1366454Y978749D01*
Y978574D01*
X1365054D01*
Y978749D01*
G37*
G36*
G01X1368754D02*
X1368939Y979349D01*
X1369969D01*
X1370154Y978749D01*
Y978574D01*
X1368754D01*
Y978749D01*
G37*
G36*
G01X1365054D02*
X1365239Y979349D01*
X1366269D01*
X1366454Y978749D01*
Y978574D01*
X1365054D01*
Y978749D01*
G37*
G36*
G01X1368754D02*
X1368939Y979349D01*
X1369969D01*
X1370154Y978749D01*
Y978574D01*
X1368754D01*
Y978749D01*
G37*
G36*
G01X1366444Y973947D02*
X1366259Y973347D01*
X1365229D01*
X1365044Y973947D01*
Y974121D01*
X1366444D01*
Y973947D01*
G37*
G36*
G01X1369557Y971311D02*
X1368945Y971171D01*
X1368430Y972063D01*
X1368857Y972523D01*
X1369008Y972610D01*
X1369708Y971398D01*
X1369557Y971311D01*
G37*
G36*
G01X1366444Y973947D02*
X1366259Y973347D01*
X1365229D01*
X1365044Y973947D01*
Y974121D01*
X1366444D01*
Y973947D01*
G37*
G36*
G01X1369557Y971311D02*
X1368945Y971171D01*
X1368430Y972063D01*
X1368857Y972523D01*
X1369008Y972610D01*
X1369708Y971398D01*
X1369557Y971311D01*
G37*
G36*
G01X1371947Y970743D02*
X1371762Y970143D01*
X1370732D01*
X1370547Y970743D01*
Y970917D01*
X1371947D01*
Y970743D01*
G37*
G36*
G01X1375647D02*
X1375462Y970143D01*
X1374432D01*
X1374247Y970743D01*
Y970918D01*
X1375647D01*
Y970743D01*
G37*
G36*
G01X1377406Y972561D02*
X1377833Y972101D01*
X1377318Y971209D01*
X1376706Y971349D01*
X1376555Y971436D01*
X1377255Y972648D01*
X1377406Y972561D01*
G37*
G36*
G01X1371947Y970743D02*
X1371762Y970143D01*
X1370732D01*
X1370547Y970743D01*
Y970917D01*
X1371947D01*
Y970743D01*
G37*
G36*
G01X1375647D02*
X1375462Y970143D01*
X1374432D01*
X1374247Y970743D01*
Y970918D01*
X1375647D01*
Y970743D01*
G37*
G36*
G01X1377406Y972561D02*
X1377833Y972101D01*
X1377318Y971209D01*
X1376706Y971349D01*
X1376555Y971436D01*
X1377255Y972648D01*
X1377406Y972561D01*
G37*
G36*
G01X1466379Y936839D02*
X1468561D01*
G03X1469320Y936595I759J1057D01*
G03X1469780Y936679I0J1302D01*
G01X1469900Y936725D01*
X1470354Y936271D01*
G02X1470330Y935683I-283J-283D01*
G03X1469870Y934691I840J-992D01*
G03X1471171Y933390I1301J0D01*
G03X1471534Y933442I-1J1301D01*
G02X1472046Y933058I112J-384D01*
G01Y932351D01*
G03Y930625I975J-863D01*
G01Y929916D01*
G02X1471534Y929532I-400J0D01*
G03X1471170Y929584I-364J-1248D01*
G03Y926982I0J-1301D01*
G03X1471534Y927034I0J1300D01*
G02X1472046Y926650I112J-384D01*
G01Y925942D01*
G03Y924216I975J-863D01*
G01Y923508D01*
G02X1471534Y923124I-400J0D01*
G03X1471171Y923176I-364J-1249D01*
G03Y920574I0J-1301D01*
G03X1471534Y920626I-1J1301D01*
G02X1472046Y920242I112J-384D01*
G01Y919531D01*
G03Y917809I974J-861D01*
G01Y917099D01*
G02X1471534Y916715I-400J0D01*
G03X1471171Y916767I-364J-1249D01*
G03Y914165I0J-1301D01*
G03X1471534Y914217I-1J1301D01*
G02X1472046Y913833I112J-384D01*
G01Y913125D01*
G03Y911399I975J-863D01*
G01Y910690D01*
G02X1471534Y910306I-400J0D01*
G03X1471171Y910358I-364J-1249D01*
G03Y907756I0J-1301D01*
G03X1471534Y907808I-1J1301D01*
G02X1472046Y907424I112J-384D01*
G01Y906716D01*
G03Y904990I975J-863D01*
G01Y904282D01*
G02X1471534Y903898I-400J0D01*
G03X1471171Y903950I-364J-1249D01*
G03Y901348I0J-1301D01*
G03X1472003Y901649I0J1300D01*
G02X1472541Y901624I255J-308D01*
G01X1472810Y901355D01*
G02X1472643Y900690I-283J-282D01*
G03X1471720Y899445I378J-1245D01*
G03X1473021Y898144I1301J0D01*
G03X1474266Y899067I0J1301D01*
G02X1474931Y899234I383J-116D01*
G01X1477381Y896784D01*
X1477340Y896665D01*
G03X1477269Y896240I1230J-424D01*
G03X1478570Y894939I1301J0D01*
G03X1478995Y895010I1J1301D01*
G01X1479114Y895051D01*
X1479574Y894591D01*
G02X1479557Y894009I-283J-283D01*
G03X1479120Y893036I865J-973D01*
G03X1480421Y891735I1301J0D01*
G03X1481394Y892172I0J1302D01*
G02X1481976Y892189I299J-266D01*
G01X1481986Y892179D01*
X1483141D01*
G03X1485099I979J857D01*
G01X1486841D01*
G03X1488799I979J857D01*
G01X1490542D01*
G03X1492500I979J857D01*
G01X1494241D01*
G03X1496199I979J857D01*
G01X1497941D01*
G03X1499899I979J857D01*
G01X1501642D01*
G03X1503600I979J857D01*
G01X1504846D01*
X1506166Y890859D01*
Y889766D01*
X1505783D01*
X1505767Y889948D01*
G03X1504471Y891133I-1296J-116D01*
G03Y888531I0J-1301D01*
G03X1505462Y888989I0J1301D01*
G02X1506166Y888729I304J-260D01*
G01Y887928D01*
X1506013Y887891D01*
G03X1505020Y886627I308J-1264D01*
G03X1505094Y886195I1301J1D01*
G01X1505124Y886108D01*
X1504323Y884719D01*
X1504232Y884702D01*
G03X1503170Y883423I239J-1279D01*
G03X1504471Y882122I1301J0D01*
G03X1505462Y882580I0J1301D01*
G02X1506166Y882320I304J-260D01*
G01Y881520D01*
X1506013Y881483D01*
G03Y878955I308J-1264D01*
G01X1506166Y878918D01*
Y878117D01*
G02X1505462Y877857I-400J0D01*
G03X1504471Y878315I-991J-843D01*
G03Y875713I0J-1301D01*
G03X1505462Y876171I0J1301D01*
G02X1506166Y875911I304J-260D01*
G01Y875111D01*
X1506013Y875074D01*
G03Y872546I308J-1264D01*
G01X1506166Y872509D01*
Y871709D01*
G02X1505462Y871449I-400J0D01*
G03X1504471Y871907I-991J-843D01*
G03X1503170Y870606I0J-1301D01*
G03X1503244Y870174I1301J1D01*
G01X1503274Y870087D01*
X1502472Y868697D01*
X1502382Y868680D01*
G03X1501320Y867401I239J-1279D01*
G03X1503922I1301J0D01*
G03X1503848Y867833I-1301J-1D01*
G01X1503818Y867919D01*
X1504621Y869310D01*
X1504711Y869327D01*
G03X1505462Y869763I-240J1279D01*
G02X1506166Y869503I304J-260D01*
G01Y868702D01*
X1506013Y868665D01*
G03X1505019Y867401I307J-1264D01*
G03X1506201Y866105I1301J0D01*
G01X1506346Y866092D01*
X1507107Y862736D01*
G02X1506623Y862258I-390J-89D01*
G03X1506321Y862294I-304J-1265D01*
G03Y859692I0J-1301D01*
G03X1507140Y859982I0J1301D01*
G02X1507781Y859759I251J-311D01*
G01X1507935Y859081D01*
X1507762Y859024D01*
G03X1506869Y857789I407J-1235D01*
G03X1508170Y856488I1301J0D01*
G03X1508335Y856498I4J1301D01*
G01X1508515Y856522D01*
X1508833Y855118D01*
X1508811Y855061D01*
G03X1508720Y854584I1210J-478D01*
G03X1509135Y853632I1301J1D01*
G01X1509180Y853590D01*
X1509315Y852993D01*
G02X1508748Y852546I-390J-88D01*
G03X1508171Y852681I-577J-1166D01*
G03Y850079I0J-1301D01*
G03X1509194Y850576I0J1301D01*
G02X1509899Y850418I315J-247D01*
G01X1510043Y849781D01*
X1512906Y846919D01*
X1513386D01*
X1513409Y846913D01*
G03X1513722Y846875I312J1263D01*
G03X1514035Y846913I1J1301D01*
G01X1514058Y846919D01*
X1516857D01*
X1545097Y818679D01*
Y807418D01*
X1597726Y754789D01*
X1602269D01*
X1602301Y754778D01*
G03X1602788Y754697I487J1421D01*
G03X1603275Y754778I0J1502D01*
G01X1603307Y754789D01*
X1606269D01*
X1606301Y754778D01*
G03X1606788Y754697I487J1421D01*
G03X1607275Y754778I0J1502D01*
G01X1607307Y754789D01*
X1610269D01*
X1610301Y754778D01*
G03X1610788Y754697I487J1421D01*
G03X1611275Y754778I0J1502D01*
G01X1611307Y754789D01*
X1614269D01*
X1614301Y754778D01*
G03X1614788Y754697I487J1421D01*
G03X1615275Y754778I0J1502D01*
G01X1615307Y754789D01*
X1618269D01*
X1618301Y754778D01*
G03X1618788Y754697I487J1421D01*
G03X1619275Y754778I0J1502D01*
G01X1619307Y754789D01*
X1630409D01*
X1630441Y754778D01*
G03X1630928Y754697I487J1421D01*
G03X1631415Y754778I0J1502D01*
G01X1631447Y754789D01*
X1634409D01*
X1634441Y754778D01*
G03X1634928Y754697I487J1421D01*
G03X1635415Y754778I0J1502D01*
G01X1635447Y754789D01*
X1638409D01*
X1638441Y754778D01*
G03X1638928Y754697I487J1421D01*
G03X1639415Y754778I0J1502D01*
G01X1639447Y754789D01*
X1670783D01*
X1670917Y754924D01*
X1672229D01*
X1672306Y754847D01*
X1680630D01*
G02X1680879Y754133I1J-400D01*
G03X1680308Y752955I930J-1178D01*
G03X1683312I1502J0D01*
G03X1682741Y754133I-1501J0D01*
G02X1682990Y754847I248J314D01*
G01X1703717D01*
G02X1703981Y754147I0J-400D01*
G03X1703471Y753019I992J-1128D01*
G03X1706475I1502J0D01*
G03X1705965Y754147I-1502J0D01*
G02X1706229Y754847I264J300D01*
G01X1744255D01*
X1748127Y750975D01*
Y741715D01*
X1751035Y738807D01*
X1755676D01*
X1759413Y735070D01*
Y690989D01*
X1757523Y689099D01*
X1739386D01*
X1726216Y702269D01*
Y717949D01*
X1719456Y724709D01*
X1715896D01*
Y724710D01*
X1675134D01*
G02X1674866Y725407I0J400D01*
G03X1675362Y726522I-1005J1115D01*
G03X1672358I-1502J0D01*
G03X1672854Y725407I1501J0D01*
G02X1672586Y724710I-268J-297D01*
G01X1618887D01*
Y724709D01*
X1613332D01*
Y724897D01*
X1612839Y725390D01*
G03X1611477Y725752I-992J-990D01*
G03X1610109Y726654I-1377J-600D01*
G03X1608721Y727864I-1388J-191D01*
G01X1587532D01*
X1581089Y734307D01*
X1574095D01*
X1561857Y746545D01*
Y751527D01*
X1541630Y771754D01*
X1526677Y776635D01*
X1523693Y778698D01*
X1519201Y785112D01*
G03X1518638Y785675I-1877J-1314D01*
G01X1504048Y795891D01*
G02X1504117Y796585I230J328D01*
G03X1505016Y797961I-604J1376D01*
G03X1504188Y799304I-1503J0D01*
G02Y800018I179J357D01*
G03X1505016Y801361I-675J1343D01*
G03X1504850Y802047I-1502J0D01*
G02X1505301Y802618I356J183D01*
G03X1507381Y802368I2077J8504D01*
G03X1498626Y811122I0J8755D01*
G03X1503073Y803501I8754J0D01*
G02X1503010Y802776I-197J-348D01*
G03X1502012Y801361I504J-1415D01*
G03X1502840Y800018I1503J0D01*
G02Y799304I-179J-357D01*
G03X1502015Y798057I674J-1342D01*
G02X1501387Y797755I-399J26D01*
G01X1496541Y801148D01*
X1486277Y814855D01*
X1484929Y818585D01*
X1484797Y818755D01*
X1478236Y834549D01*
Y844355D01*
X1475837Y850502D01*
X1475905Y850591D01*
G03X1476172Y851380I-1034J790D01*
G03X1475097Y852661I-1301J0D01*
G01X1474987Y852681D01*
X1474311Y854413D01*
X1474315Y854460D01*
G03X1474321Y854584I-1295J125D01*
G03X1474248Y855015I-1301J1D01*
G01X1474217Y855101D01*
X1475021Y856493D01*
X1475111Y856510D01*
G03X1476172Y857789I-240J1279D01*
G03X1473570I-1301J0D01*
G03X1473644Y857357I1301J1D01*
G01X1473674Y857270D01*
X1473597Y857136D01*
G02X1473237Y857163I-174J100D01*
G01X1472459Y859157D01*
G02X1472876Y859700I373J145D01*
G03X1473020Y859692I144J1292D01*
G03Y862294I0J1301D01*
G03X1472038Y861847I0J-1302D01*
G02X1471364Y861964I-302J262D01*
G01X1471195Y862397D01*
G02X1471474Y862932I372J146D01*
G03X1472472Y864197I-303J1265D01*
G03X1471171Y865498I-1301J0D01*
G03X1470537Y865333I0J-1301D01*
G02X1469969Y865537I-195J349D01*
G01X1469729Y866152D01*
X1469894Y866233D01*
G03X1470622Y867401I-573J1168D01*
G03X1469321Y868702I-1301J0D01*
G03X1468952Y868648I2J-1301D01*
G01X1468775Y868596D01*
X1468363Y869651D01*
X1468445Y869743D01*
G03X1468772Y870606I-975J863D01*
G03X1468010Y871790I-1301J0D01*
G03X1466915Y873686I-4239J-1184D01*
G03X1466921Y873810I-1295J125D01*
G03X1466359Y874880I-1300J0D01*
G01X1466309Y874915D01*
X1465803Y876212D01*
X1465073Y876942D01*
X1465072Y877024D01*
G03X1464312Y878197I-1301J-10D01*
G03X1463216Y880095I-4241J-1183D01*
G03X1463222Y880219I-1295J125D01*
G03X1462460Y881403I-1301J0D01*
G03X1461366Y883299I-4240J-1183D01*
G03X1461372Y883423I-1295J125D01*
G03X1461366Y883548I-1301J0D01*
G03X1462460Y885443I-3146J3079D01*
G03X1463221Y886627I-541J1184D01*
G03X1462461Y887810I-1301J0D01*
G03X1461366Y889708I-4242J-1182D01*
G03X1461372Y889832I-1295J125D01*
G03X1460610Y891016I-1301J0D01*
G03X1459515Y892912I-4239J-1184D01*
G03X1459521Y893036I-1295J125D01*
G03X1458760Y894219I-1300J0D01*
G03X1457665Y896116I-4239J-1182D01*
G03X1457671Y896240I-1295J125D01*
G03X1456911Y897423I-1301J0D01*
G03X1455815Y899321I-4240J-1183D01*
G03X1455821Y899445I-1295J125D01*
G03X1455060Y900629I-1302J0D01*
G03X1453966Y902524I-4240J-1184D01*
G03X1453972Y902649I-1295J125D01*
G03X1453210Y903833I-1301J0D01*
G03X1452115Y905729I-4239J-1184D01*
G03X1452121Y905853I-1295J125D01*
G03X1450820Y907154I-1301J0D01*
G03X1450066Y906913I0J-1300D01*
G03X1449861Y906961I-1106J-4261D01*
G01X1449802Y906973D01*
X1449497Y907278D01*
G02X1449590Y907913I283J283D01*
G03X1450272Y909057I-618J1144D01*
G03X1448971Y910358I-1301J0D01*
G03X1447827Y909676I0J-1300D01*
G02X1447192Y909583I-352J190D01*
G01X1446836Y909939D01*
X1446227D01*
G03X1445271Y910358I-956J-881D01*
G03X1444517Y910117I0J-1300D01*
G01X1442325D01*
G03X1441571Y910358I-754J-1059D01*
G03X1440816Y910117I-1J-1301D01*
G03X1438625I-1096J-4264D01*
G03X1437871Y910358I-754J-1059D01*
G03X1437116Y910117I-1J-1301D01*
G03X1434926I-1095J-4264D01*
G03X1434171Y910358I-754J-1060D01*
G03X1432870Y909057I0J-1301D01*
G03X1432876Y908934I1301J2D01*
G03X1432642Y908675I3147J-3078D01*
G01X1431276Y907309D01*
Y906629D01*
G03X1431019Y905853I1043J-776D01*
G03X1431025Y905728I1301J0D01*
G03X1430018Y904108I3146J-3079D01*
G01X1430003Y904066D01*
X1428706Y902769D01*
G02X1428035Y902957I-283J283D01*
G03X1426771Y903950I-1264J-308D01*
G03X1425470Y902649I0J-1301D01*
G03X1425566Y902158I1301J0D01*
G02X1425153Y901609I-370J-151D01*
G03X1424920Y901622I-238J-2164D01*
G03X1424689Y901609I7J-2177D01*
G02X1424276Y902158I-43J398D01*
G03X1424372Y902649I-1205J491D01*
G03X1421770I-1301J0D01*
G03X1421866Y902158I1301J0D01*
G02X1421453Y901609I-370J-151D01*
G03X1421220Y901622I-238J-2164D01*
G01X1420952D01*
G02X1420580Y902169I0J400D01*
G03X1420672Y902649I-1209J481D01*
G03X1418070I-1301J0D01*
G03X1418162Y902169I1301J1D01*
G02X1417790Y901622I-372J-147D01*
G01X1417520D01*
G03X1417288Y901609I6J-2177D01*
G02X1416875Y902158I-43J398D01*
G03X1416971Y902649I-1205J491D01*
G03X1414369I-1301J0D01*
G03X1414539Y902006I1301J0D01*
G02X1414191Y901409I-348J-197D01*
G01X1413450D01*
G02X1413102Y902006I0J400D01*
G03X1413272Y902649I-1131J643D01*
G03X1410670I-1301J0D01*
G03X1410766Y902158I1301J0D01*
G02X1410353Y901609I-370J-151D01*
G03X1410120Y901622I-238J-2164D01*
G03X1409889Y901609I7J-2177D01*
G02X1409476Y902158I-43J398D01*
G03X1409572Y902649I-1205J491D01*
G03X1406970I-1301J0D01*
G03X1408093Y901360I1301J0D01*
G02X1408362Y900728I-54J-396D01*
G03X1408235Y900533I1758J-1284D01*
G01X1407619Y899466D01*
G03X1407387Y898884I1885J-1089D01*
G03X1407002Y898395I1500J-1577D01*
G01X1406796Y898039D01*
X1405826D01*
X1404916Y898949D01*
Y900649D01*
X1404816Y900749D01*
G02X1404975Y901412I283J283D01*
G03X1405872Y902649I-404J1237D01*
G03X1403270I-1301J0D01*
G03X1403366Y902158I1301J0D01*
G02X1402953Y901609I-370J-151D01*
G03X1402720Y901622I-238J-2164D01*
G03X1402489Y901609I7J-2177D01*
G02X1402076Y902158I-43J398D01*
G03X1402172Y902649I-1205J491D01*
G03X1400871Y901348I-1301J0D01*
G01X1400890D01*
X1400974Y901349D01*
X1401175Y901148D01*
X1400876Y900849D01*
Y900603D01*
X1400848Y900555D01*
G03X1400835Y900533I1867J-1118D01*
G01X1400219Y899466D01*
G03X1399987Y898884I1885J-1089D01*
G03X1399602Y898395I1500J-1577D01*
G01X1399316Y897899D01*
X1398582D01*
X1398527Y897943D01*
G03X1397874Y898300I-1355J-1703D01*
G01X1397830Y898315D01*
X1397496Y898649D01*
Y899400D01*
Y899445D01*
Y900149D01*
X1397303Y900342D01*
G03X1397078Y900728I-1983J-897D01*
G02X1397347Y901360I323J236D01*
G03X1398472Y902649I-176J1289D01*
G03X1395870I-1301J0D01*
G03X1395966Y902158I1301J0D01*
G02X1395553Y901609I-370J-151D01*
G03X1395320Y901622I-238J-2164D01*
G03X1395089Y901609I7J-2177D01*
G02X1394676Y902158I-43J398D01*
G03X1394772Y902649I-1205J491D01*
G03X1392170I-1301J0D01*
G03X1393293Y901360I1301J0D01*
G02X1393562Y900728I-54J-396D01*
G03X1393454Y900566I1755J-1287D01*
G01X1393441Y900544D01*
X1393046Y900149D01*
X1393152Y900043D01*
X1392819Y899466D01*
G03X1392587Y898884I1885J-1089D01*
G03X1392202Y898395I1500J-1577D01*
G01X1392025Y898089D01*
X1391076D01*
X1390286Y898879D01*
Y899869D01*
X1389966Y900189D01*
X1389950Y900229D01*
G03X1389858Y900436I-2032J-779D01*
G01X1389836Y900479D01*
Y901339D01*
X1390001Y901368D01*
G03Y903930I-231J1281D01*
G01X1389836Y903959D01*
Y907747D01*
X1390001Y907776D01*
G03Y910338I-231J1281D01*
G01X1389836Y910367D01*
Y914156D01*
X1390001Y914185D01*
G03Y916747I-231J1281D01*
G01X1389836Y916776D01*
Y934974D01*
X1391701Y936839D01*
X1402315D01*
G02X1402715Y936446I0J-400D01*
G03X1404016Y935168I1301J23D01*
G03X1405317Y936469I0J1301D01*
G03X1405309Y936616I-1301J3D01*
G01X1405307Y936628D01*
Y936839D01*
X1405659D01*
X1405709Y936806D01*
G03X1406420Y936595I710J1090D01*
G03X1407179Y936839I0J1301D01*
G01X1409361D01*
G03X1410120Y936595I759J1057D01*
G03X1410879Y936839I0J1301D01*
G01X1413061D01*
G03X1413820Y936595I759J1057D01*
G03X1414579Y936839I0J1301D01*
G01X1416761D01*
G03X1417520Y936595I759J1057D01*
G03X1418279Y936839I0J1301D01*
G01X1420461D01*
G03X1421220Y936595I759J1057D01*
G03X1421979Y936839I0J1301D01*
G01X1424161D01*
G03X1424920Y936595I759J1057D01*
G03X1425679Y936839I0J1301D01*
G01X1453761D01*
G03X1454520Y936595I759J1057D01*
G03X1455279Y936839I0J1301D01*
G01X1457461D01*
G03X1458220Y936595I759J1057D01*
G03X1458979Y936839I0J1301D01*
G01X1461161D01*
G03X1461920Y936595I759J1057D01*
G03X1462679Y936839I0J1301D01*
G01X1464861D01*
G03X1465620Y936595I759J1057D01*
G03X1466379Y936839I0J1301D01*
G37*
G36*
G01X1402162Y1423657D02*
X1406294Y1427790D01*
G02X1406977Y1427507I283J-283D01*
G01Y1405945D01*
X1411056Y1401866D01*
Y1401807D01*
X1410689Y1401439D01*
G03X1410482Y1400942I495J-498D01*
G01Y1399830D01*
X1410220Y1399568D01*
G02X1409844Y1399034I-376J-134D01*
G01X1405714D01*
X1402162Y1402586D01*
Y1423657D01*
G37*
G36*
G01X1418890Y1437200D02*
X1420639D01*
X1421228Y1436611D01*
Y1432385D01*
X1418459Y1429616D01*
X1417093D01*
X1415623Y1428146D01*
X1415492Y1428216D01*
G03X1414787Y1428392I-706J-1326D01*
G01X1414786D01*
G03X1413284Y1426890I0J-1502D01*
G03X1413817Y1425742I1503J0D01*
G01Y1425707D01*
G03X1412989Y1422404I6174J-3303D01*
G01Y1422403D01*
G03X1413794Y1419144I7002J1D01*
G01X1413817Y1419101D01*
Y1415550D01*
X1419501Y1409866D01*
X1423792D01*
X1425716Y1407942D01*
X1427407D01*
X1427925Y1407424D01*
Y1404609D01*
X1427833Y1404517D01*
Y1403800D01*
X1425966Y1402450D01*
X1424816D01*
X1423898Y1401532D01*
X1420976D01*
X1418360Y1398916D01*
Y1395022D01*
X1416710Y1393372D01*
X1410980D01*
X1410410Y1393942D01*
Y1396362D01*
X1410940Y1396892D01*
X1413420D01*
X1414200Y1396112D01*
Y1395692D01*
X1414750Y1395142D01*
X1416600D01*
X1417190Y1395732D01*
Y1398462D01*
X1416400Y1399252D01*
X1411300D01*
X1410957Y1399595D01*
X1410984Y1399622D01*
Y1400942D01*
G02X1411043Y1401084I200J0D01*
G01X1411558Y1401599D01*
Y1402366D01*
X1410820Y1403104D01*
G02X1411105Y1403787I283J283D01*
G01X1411115D01*
G03X1409613Y1405289I0J1502D01*
G01Y1405279D01*
G02X1408930Y1404994I-400J-2D01*
G01X1407780Y1406144D01*
Y1427449D01*
X1409242Y1428910D01*
X1410378D01*
X1411330Y1429862D01*
Y1432142D01*
X1412625Y1433437D01*
G03X1413954Y1434238I0J1503D01*
G01X1414010Y1434345D01*
X1414785D01*
G03X1414733Y1433949I1487J-397D01*
G03X1417811I1539J0D01*
G03X1417759Y1434345I-1539J-1D01*
G01X1418191D01*
X1418339Y1434493D01*
Y1436649D01*
X1418890Y1437200D01*
G37*
G36*
G01X1461228Y1030645D02*
X1461777D01*
X1462028Y1030394D01*
G02X1461888Y1029738I-283J-283D01*
G03X1461052Y1028523I465J-1215D01*
G03X1462353Y1027222I1301J0D01*
G03X1463640Y1028331I0J1301D01*
G01X1463650Y1028396D01*
X1463838Y1028584D01*
X1464167Y1028255D01*
Y1026630D01*
X1463999Y1026603D01*
G03Y1024033I205J-1285D01*
G01X1464167Y1024006D01*
Y1020222D01*
X1463999Y1020195D01*
G03Y1017625I205J-1285D01*
G01X1464167Y1017598D01*
Y1016735D01*
X1463943Y1016511D01*
G02X1463353Y1016538I-283J283D01*
G03X1462353Y1017006I-1000J-834D01*
G03X1461052Y1015705I0J-1301D01*
G03X1461520Y1014705I1302J0D01*
G02X1461547Y1014115I-256J-307D01*
G01X1461098Y1013666D01*
X1460976Y1013713D01*
G03X1460504Y1013802I-473J-1212D01*
G03X1459388Y1013170I0J-1301D01*
G01X1457920D01*
G03X1455688I-1116J-669D01*
G01X1455252D01*
X1454007Y1011925D01*
Y1010910D01*
X1453677D01*
X1453624Y1011029D01*
G03X1453344Y1011431I-1188J-529D01*
G02X1453342Y1012001I279J286D01*
G03X1453727Y1012925I-916J924D01*
G03X1451125I-1301J0D01*
G03X1451518Y1011993I1302J0D01*
G02X1451520Y1011423I-279J-286D01*
G03X1451135Y1010499I916J-924D01*
G03X1452436Y1009198I1301J0D01*
G03X1453006Y1009329I1J1301D01*
G02X1453574Y1009042I175J-359D01*
G03X1454267Y1008074I1379J255D01*
G01X1454291Y1008061D01*
X1457862Y1004490D01*
G02X1457832Y1003897I-283J-283D01*
G03X1457352Y1002888I821J-1009D01*
G03X1458653Y1001587I1301J0D01*
G03X1459662Y1002067I0J1301D01*
G02X1460255Y1002097I310J-253D01*
G01X1460377Y1001975D01*
Y1000989D01*
X1460220Y1000954D01*
G03Y998414I283J-1270D01*
G01X1460377Y998379D01*
Y981250D01*
G02X1459999Y980851I-400J0D01*
G03Y978253I71J-1299D01*
G02X1460377Y977854I-22J-399D01*
G01Y974841D01*
G02X1459999Y974442I-400J0D01*
G03Y971844I72J-1299D01*
G02X1460377Y971445I-22J-399D01*
G01Y968433D01*
G02X1459999Y968034I-400J0D01*
G03Y965436I72J-1299D01*
G02X1460377Y965037I-22J-399D01*
G01Y962024D01*
G02X1459999Y961625I-400J0D01*
G03Y959027I71J-1299D01*
G02X1460377Y958628I-22J-399D01*
G01Y955615D01*
G02X1459999Y955216I-400J0D01*
G03Y952618I72J-1299D01*
G02X1460377Y952219I-22J-399D01*
G01Y949207D01*
G02X1459999Y948808I-400J0D01*
G03Y946210I71J-1299D01*
G02X1460377Y945811I-22J-399D01*
G01Y942798D01*
G02X1459999Y942399I-400J0D01*
G03X1458970Y941795I71J-1299D01*
G01X1457471D01*
G03X1455271I-1100J-695D01*
G01X1451727D01*
X1451295Y942227D01*
X1451289Y942301D01*
G03X1450098Y943492I-1297J-106D01*
G01X1450024Y943498D01*
X1449777Y943745D01*
Y964955D01*
X1444117Y970615D01*
Y977445D01*
X1450167Y983495D01*
Y1002065D01*
X1449357Y1002875D01*
Y1021455D01*
X1450469Y1022567D01*
G02X1451143Y1022367I283J-283D01*
G03X1452416Y1021334I1273J268D01*
G03X1453717Y1022635I0J1301D01*
G03X1453584Y1023207I-1301J-1D01*
G01X1453564Y1023249D01*
Y1023495D01*
X1453877D01*
X1454007Y1023625D01*
Y1029405D01*
X1455247Y1030645D01*
X1456082D01*
G03X1457526I722J1081D01*
G01X1459781D01*
G03X1460503Y1030426I722J1081D01*
G03X1461180Y1030616I0J1301D01*
G01X1461228Y1030645D01*
G37*
G36*
G01X1441716Y1065669D02*
X1461916D01*
X1463105Y1064480D01*
X1463040Y1064352D01*
G03X1462903Y1063770I1164J-581D01*
G03X1463116Y1063057I1300J0D01*
G01Y1062227D01*
G02X1462631Y1061836I-400J0D01*
G03X1462353Y1061866I-278J-1271D01*
G03Y1059264I0J-1301D01*
G03X1462631Y1059294I0J1301D01*
G02X1463116Y1058903I85J-391D01*
G01Y1058074D01*
G03Y1056648I1087J-713D01*
G01Y1055819D01*
G02X1462631Y1055428I-400J0D01*
G03X1462353Y1055458I-278J-1271D01*
G03Y1052856I0J-1301D01*
G03X1462631Y1052886I0J1301D01*
G02X1463116Y1052495I85J-391D01*
G01Y1051665D01*
G03Y1050239I1087J-713D01*
G01Y1049411D01*
G02X1462631Y1049020I-400J0D01*
G03X1462353Y1049050I-278J-1271D01*
G03Y1046448I0J-1301D01*
G03X1462631Y1046478I0J1301D01*
G02X1463116Y1046087I85J-391D01*
G01Y1045257D01*
G03Y1043831I1087J-713D01*
G01Y1043002D01*
G02X1462631Y1042611I-400J0D01*
G03X1462353Y1042641I-278J-1271D01*
G03Y1040039I0J-1301D01*
G03X1462631Y1040069I0J1301D01*
G02X1463116Y1039678I85J-391D01*
G01Y1038849D01*
G03Y1037423I1087J-713D01*
G01Y1036593D01*
G02X1462631Y1036202I-400J0D01*
G03X1462353Y1036232I-278J-1271D01*
G03Y1033630I0J-1301D01*
G03X1462631Y1033660I0J1301D01*
G02X1463116Y1033269I85J-391D01*
G01Y1032440D01*
G03X1462983Y1032177I1087J-715D01*
G01X1462968Y1032136D01*
X1462457Y1031625D01*
X1461813D01*
X1461801Y1031812D01*
G03X1459205I-1298J-85D01*
G01X1459193Y1031625D01*
X1458114D01*
X1458102Y1031812D01*
G03X1455506I-1298J-85D01*
G01X1455494Y1031625D01*
X1454757D01*
X1453407Y1030275D01*
Y1024809D01*
X1453067Y1024469D01*
X1444543D01*
X1442060Y1026952D01*
G02X1442220Y1027616I283J283D01*
G03X1443122Y1028854I-399J1238D01*
G03X1441821Y1030155I-1301J0D01*
G03X1440865Y1029736I0J-1300D01*
G02X1440277I-294J272D01*
G03X1439663Y1030109I-956J-882D01*
G01X1439516Y1030149D01*
Y1035762D01*
X1439676Y1035795D01*
G03Y1038343I-263J1274D01*
G01X1439516Y1038376D01*
Y1039656D01*
G02X1439972Y1040052I400J0D01*
G03X1440153Y1040039I183J1288D01*
G03Y1042641I0J1301D01*
G03X1439972Y1042628I2J-1301D01*
G02X1439516Y1043024I-56J396D01*
G01Y1044070D01*
X1439528Y1044103D01*
G03Y1044985I-1224J441D01*
G01X1439516Y1045018D01*
Y1046065D01*
G02X1439972Y1046461I400J0D01*
G03X1440153Y1046448I183J1288D01*
G03Y1049050I0J1301D01*
G03X1439972Y1049037I2J-1301D01*
G02X1439516Y1049433I-56J396D01*
G01Y1050478D01*
X1439528Y1050511D01*
G03Y1051393I-1224J441D01*
G01X1439516Y1051426D01*
Y1052473D01*
G02X1439972Y1052869I400J0D01*
G03X1440153Y1052856I183J1288D01*
G03Y1055458I0J1301D01*
G03X1439972Y1055445I2J-1301D01*
G02X1439516Y1055841I-56J396D01*
G01Y1056889D01*
X1439528Y1056922D01*
G03X1439604Y1057361I-1225J438D01*
G03X1439528Y1057800I-1301J1D01*
G01X1439516Y1057833D01*
Y1058881D01*
G02X1439972Y1059277I400J0D01*
G03X1440154Y1059264I183J1288D01*
G03Y1061866I0J1301D01*
G03X1439972Y1061853I1J-1301D01*
G02X1439516Y1062249I-56J396D01*
G01Y1063298D01*
X1439528Y1063331D01*
G03X1439572Y1063481I-1224J441D01*
G01X1439584Y1063537D01*
X1440022Y1063975D01*
G02X1440704Y1063710I283J-283D01*
G03X1442004Y1062469I1300J60D01*
G03Y1065071I0J1301D01*
G03X1441585Y1065002I-1J-1301D01*
G01X1441468Y1064962D01*
X1441238Y1065191D01*
X1441716Y1065669D01*
G37*
G36*
G01X1443300Y1642600D02*
X1463400D01*
X1465800Y1640200D01*
Y1637200D01*
X1457800Y1629200D01*
Y1587669D01*
G02X1457131Y1587373I-400J0D01*
G03X1456120Y1587764I-1011J-1112D01*
G03Y1584760I0J-1502D01*
G03X1457131Y1585151I0J1503D01*
G02X1457800Y1584855I269J-296D01*
G01Y1575300D01*
X1460000Y1573100D01*
X1651500D01*
X1661400Y1583000D01*
X1668100D01*
X1669500Y1581600D01*
Y1556800D01*
X1668400Y1555700D01*
X1664700D01*
X1660500Y1559900D01*
X1459708D01*
X1459701Y1560093D01*
G03X1456699I-1501J-56D01*
G01X1456692Y1559900D01*
X1455700D01*
X1453700Y1561900D01*
X1444700D01*
X1442500Y1564100D01*
Y1570600D01*
X1445000Y1573100D01*
X1445200D01*
Y1573500D01*
G03X1445452Y1574252I-1000J753D01*
G01Y1593652D01*
G02X1446009Y1594019I400J-1D01*
G03X1446600Y1593898I591J1381D01*
G03X1448102Y1595400I0J1502D01*
G03X1447562Y1596554I-1503J0D01*
G02X1447583Y1597185I256J307D01*
G03X1448202Y1598400I-883J1215D01*
G03X1446700Y1599902I-1502J0D01*
G03X1446030Y1599744I1J-1502D01*
G02X1445452Y1600102I-178J358D01*
G01Y1608982D01*
G02X1446048Y1609331I400J1D01*
G03X1446786Y1609137I738J1307D01*
G03Y1612141I0J1502D01*
G03X1446048Y1611947I0J-1501D01*
G02X1445452Y1612296I-196J348D01*
G01Y1633962D01*
G03X1445235Y1634666I-1252J0D01*
G01X1445200Y1634717D01*
Y1634900D01*
X1442572Y1637529D01*
Y1641871D01*
X1443300Y1642600D01*
G37*
G36*
G01X1466747Y981953D02*
X1466932Y982553D01*
X1467962D01*
X1468147Y981953D01*
Y981778D01*
X1466747D01*
Y981953D01*
G37*
G36*
G01X1470447Y981951D02*
X1470632Y982551D01*
X1471662D01*
X1471847Y981951D01*
Y981777D01*
X1470447D01*
Y981951D01*
G37*
G36*
G01X1474137Y981953D02*
X1474322Y982553D01*
X1475352D01*
X1475537Y981953D01*
Y981778D01*
X1474137D01*
Y981953D01*
G37*
G36*
G01X1466747D02*
X1466932Y982553D01*
X1467962D01*
X1468147Y981953D01*
Y981778D01*
X1466747D01*
Y981953D01*
G37*
G36*
G01X1470447Y981951D02*
X1470632Y982551D01*
X1471662D01*
X1471847Y981951D01*
Y981777D01*
X1470447D01*
Y981951D01*
G37*
G36*
G01X1474137Y981953D02*
X1474322Y982553D01*
X1475352D01*
X1475537Y981953D01*
Y981778D01*
X1474137D01*
Y981953D01*
G37*
G36*
G01X1476054Y978749D02*
X1476239Y979349D01*
X1477269D01*
X1477454Y978749D01*
Y978574D01*
X1476054D01*
Y978749D01*
G37*
G36*
G01D02*
X1476239Y979349D01*
X1477269D01*
X1477454Y978749D01*
Y978574D01*
X1476054D01*
Y978749D01*
G37*
G36*
G01X1468654D02*
X1468839Y979349D01*
X1469869D01*
X1470054Y978749D01*
Y978574D01*
X1468654D01*
Y978749D01*
G37*
G36*
G01X1472321Y978747D02*
X1472506Y979347D01*
X1473536D01*
X1473721Y978747D01*
Y978573D01*
X1472321D01*
Y978747D01*
G37*
G36*
G01X1468654Y978749D02*
X1468839Y979349D01*
X1469869D01*
X1470054Y978749D01*
Y978574D01*
X1468654D01*
Y978749D01*
G37*
G36*
G01X1472321Y978747D02*
X1472506Y979347D01*
X1473536D01*
X1473721Y978747D01*
Y978573D01*
X1472321D01*
Y978747D01*
G37*
G36*
G01X1477454Y980355D02*
X1477269Y979755D01*
X1476239D01*
X1476054Y980355D01*
Y980530D01*
X1477454D01*
Y980355D01*
G37*
G36*
G01D02*
X1477269Y979755D01*
X1476239D01*
X1476054Y980355D01*
Y980530D01*
X1477454D01*
Y980355D01*
G37*
G36*
G01X1473754D02*
X1473569Y979755D01*
X1472539D01*
X1472354Y980355D01*
Y980530D01*
X1473754D01*
Y980355D01*
G37*
G36*
G01D02*
X1473569Y979755D01*
X1472539D01*
X1472354Y980355D01*
Y980530D01*
X1473754D01*
Y980355D01*
G37*
G36*
G01X1475547Y977151D02*
X1475362Y976551D01*
X1474332D01*
X1474147Y977151D01*
Y977326D01*
X1475547D01*
Y977151D01*
G37*
G36*
G01D02*
X1475362Y976551D01*
X1474332D01*
X1474147Y977151D01*
Y977326D01*
X1475547D01*
Y977151D01*
G37*
G36*
G01X1485838Y901267D02*
X1486450Y901407D01*
X1486965Y900515D01*
X1486538Y900055D01*
X1486387Y899968D01*
X1485687Y901180D01*
X1485838Y901267D01*
G37*
G36*
G01D02*
X1486450Y901407D01*
X1486965Y900515D01*
X1486538Y900055D01*
X1486387Y899968D01*
X1485687Y901180D01*
X1485838Y901267D01*
G37*
G36*
G01X1492637Y898641D02*
X1492822Y899241D01*
X1493852D01*
X1494037Y898641D01*
Y898467D01*
X1492637D01*
Y898641D01*
G37*
G36*
G01X1488937D02*
X1489122Y899241D01*
X1490152D01*
X1490337Y898641D01*
Y898467D01*
X1488937D01*
Y898641D01*
G37*
G36*
G01X1492637D02*
X1492822Y899241D01*
X1493852D01*
X1494037Y898641D01*
Y898467D01*
X1492637D01*
Y898641D01*
G37*
G36*
G01X1488937D02*
X1489122Y899241D01*
X1490152D01*
X1490337Y898641D01*
Y898467D01*
X1488937D01*
Y898641D01*
G37*
G36*
G01X1483991Y898059D02*
X1484603Y898199D01*
X1485118Y897307D01*
X1484691Y896847D01*
X1484540Y896760D01*
X1483840Y897972D01*
X1483991Y898059D01*
G37*
G36*
G01X1487154Y895437D02*
X1487339Y896037D01*
X1488369D01*
X1488554Y895437D01*
Y895262D01*
X1487154D01*
Y895437D01*
G37*
G36*
G01X1490821Y895435D02*
X1491006Y896035D01*
X1492036D01*
X1492221Y895435D01*
Y895261D01*
X1490821D01*
Y895435D01*
G37*
G36*
G01X1483991Y898059D02*
X1484603Y898199D01*
X1485118Y897307D01*
X1484691Y896847D01*
X1484540Y896760D01*
X1483840Y897972D01*
X1483991Y898059D01*
G37*
G36*
G01X1487154Y895437D02*
X1487339Y896037D01*
X1488369D01*
X1488554Y895437D01*
Y895262D01*
X1487154D01*
Y895437D01*
G37*
G36*
G01X1490821Y895435D02*
X1491006Y896035D01*
X1492036D01*
X1492221Y895435D01*
Y895261D01*
X1490821D01*
Y895435D01*
G37*
G36*
G01X1486106Y897615D02*
X1485494Y897475D01*
X1484979Y898367D01*
X1485406Y898827D01*
X1485557Y898914D01*
X1486257Y897702D01*
X1486106Y897615D01*
G37*
G36*
G01X1488554Y897043D02*
X1488369Y896443D01*
X1487339D01*
X1487154Y897043D01*
Y897218D01*
X1488554D01*
Y897043D01*
G37*
G36*
G01X1492254D02*
X1492069Y896443D01*
X1491039D01*
X1490854Y897043D01*
Y897218D01*
X1492254D01*
Y897043D01*
G37*
G36*
G01X1486106Y897615D02*
X1485494Y897475D01*
X1484979Y898367D01*
X1485406Y898827D01*
X1485557Y898914D01*
X1486257Y897702D01*
X1486106Y897615D01*
G37*
G36*
G01X1488554Y897043D02*
X1488369Y896443D01*
X1487339D01*
X1487154Y897043D01*
Y897218D01*
X1488554D01*
Y897043D01*
G37*
G36*
G01X1492254D02*
X1492069Y896443D01*
X1491039D01*
X1490854Y897043D01*
Y897218D01*
X1492254D01*
Y897043D01*
G37*
G36*
G01X1484235Y894447D02*
X1483623Y894307D01*
X1483108Y895199D01*
X1483535Y895659D01*
X1483686Y895746D01*
X1484386Y894534D01*
X1484235Y894447D01*
G37*
G36*
G01X1486637Y893839D02*
X1486452Y893239D01*
X1485422D01*
X1485237Y893839D01*
Y894014D01*
X1486637D01*
Y893839D01*
G37*
G36*
G01X1490347D02*
X1490162Y893239D01*
X1489132D01*
X1488947Y893839D01*
Y894014D01*
X1490347D01*
Y893839D01*
G37*
G36*
G01X1494047Y893841D02*
X1493862Y893241D01*
X1492832D01*
X1492647Y893841D01*
Y894015D01*
X1494047D01*
Y893841D01*
G37*
G36*
G01X1484235Y894447D02*
X1483623Y894307D01*
X1483108Y895199D01*
X1483535Y895659D01*
X1483686Y895746D01*
X1484386Y894534D01*
X1484235Y894447D01*
G37*
G36*
G01X1486637Y893839D02*
X1486452Y893239D01*
X1485422D01*
X1485237Y893839D01*
Y894014D01*
X1486637D01*
Y893839D01*
G37*
G36*
G01X1490347D02*
X1490162Y893239D01*
X1489132D01*
X1488947Y893839D01*
Y894014D01*
X1490347D01*
Y893839D01*
G37*
G36*
G01X1494047Y893841D02*
X1493862Y893241D01*
X1492832D01*
X1492647Y893841D01*
Y894015D01*
X1494047D01*
Y893841D01*
G37*
G36*
G01X1494037Y900249D02*
X1493852Y899649D01*
X1492822D01*
X1492637Y900249D01*
Y900423D01*
X1494037D01*
Y900249D01*
G37*
G36*
G01X1490337D02*
X1490152Y899649D01*
X1489122D01*
X1488937Y900249D01*
Y900423D01*
X1490337D01*
Y900249D01*
G37*
G36*
G01X1494037D02*
X1493852Y899649D01*
X1492822D01*
X1492637Y900249D01*
Y900423D01*
X1494037D01*
Y900249D01*
G37*
G36*
G01X1490337D02*
X1490152Y899649D01*
X1489122D01*
X1488937Y900249D01*
Y900423D01*
X1490337D01*
Y900249D01*
G37*
G36*
G01X1484854Y916269D02*
X1484669Y915669D01*
X1483639D01*
X1483454Y916269D01*
Y916444D01*
X1484854D01*
Y916269D01*
G37*
G36*
G01X1481154D02*
X1480969Y915669D01*
X1479939D01*
X1479754Y916269D01*
Y916444D01*
X1481154D01*
Y916269D01*
G37*
G36*
G01X1488554D02*
X1488369Y915669D01*
X1487339D01*
X1487154Y916269D01*
Y916444D01*
X1488554D01*
Y916269D01*
G37*
G36*
G01X1492254D02*
X1492069Y915669D01*
X1491039D01*
X1490854Y916269D01*
Y916444D01*
X1492254D01*
Y916269D01*
G37*
G36*
G01X1484854D02*
X1484669Y915669D01*
X1483639D01*
X1483454Y916269D01*
Y916444D01*
X1484854D01*
Y916269D01*
G37*
G36*
G01X1481154D02*
X1480969Y915669D01*
X1479939D01*
X1479754Y916269D01*
Y916444D01*
X1481154D01*
Y916269D01*
G37*
G36*
G01X1488554D02*
X1488369Y915669D01*
X1487339D01*
X1487154Y916269D01*
Y916444D01*
X1488554D01*
Y916269D01*
G37*
G36*
G01X1492254D02*
X1492069Y915669D01*
X1491039D01*
X1490854Y916269D01*
Y916444D01*
X1492254D01*
Y916269D01*
G37*
G36*
G01X1483421Y914661D02*
X1483606Y915261D01*
X1484636D01*
X1484821Y914661D01*
Y914487D01*
X1483421D01*
Y914661D01*
G37*
G36*
G01X1487154Y914663D02*
X1487339Y915263D01*
X1488369D01*
X1488554Y914663D01*
Y914488D01*
X1487154D01*
Y914663D01*
G37*
G36*
G01X1490854D02*
X1491039Y915263D01*
X1492069D01*
X1492254Y914663D01*
Y914488D01*
X1490854D01*
Y914663D01*
G37*
G36*
G01X1483421Y914661D02*
X1483606Y915261D01*
X1484636D01*
X1484821Y914661D01*
Y914487D01*
X1483421D01*
Y914661D01*
G37*
G36*
G01X1487154Y914663D02*
X1487339Y915263D01*
X1488369D01*
X1488554Y914663D01*
Y914488D01*
X1487154D01*
Y914663D01*
G37*
G36*
G01X1490854D02*
X1491039Y915263D01*
X1492069D01*
X1492254Y914663D01*
Y914488D01*
X1490854D01*
Y914663D01*
G37*
G36*
G01X1485247Y911457D02*
X1485432Y912057D01*
X1486462D01*
X1486647Y911457D01*
Y911283D01*
X1485247D01*
Y911457D01*
G37*
G36*
G01X1488937Y911459D02*
X1489122Y912059D01*
X1490152D01*
X1490337Y911459D01*
Y911284D01*
X1488937D01*
Y911459D01*
G37*
G36*
G01X1491385Y910887D02*
X1491997Y911027D01*
X1492512Y910135D01*
X1492085Y909675D01*
X1491934Y909588D01*
X1491234Y910800D01*
X1491385Y910887D01*
G37*
G36*
G01X1485247Y911457D02*
X1485432Y912057D01*
X1486462D01*
X1486647Y911457D01*
Y911283D01*
X1485247D01*
Y911457D01*
G37*
G36*
G01X1488937Y911459D02*
X1489122Y912059D01*
X1490152D01*
X1490337Y911459D01*
Y911284D01*
X1488937D01*
Y911459D01*
G37*
G36*
G01X1491385Y910887D02*
X1491997Y911027D01*
X1492512Y910135D01*
X1492085Y909675D01*
X1491934Y909588D01*
X1491234Y910800D01*
X1491385Y910887D01*
G37*
G36*
G01X1493506Y910432D02*
X1492894Y910292D01*
X1492379Y911184D01*
X1492806Y911644D01*
X1492957Y911731D01*
X1493657Y910519D01*
X1493506Y910432D01*
G37*
G36*
G01X1490337Y913065D02*
X1490152Y912465D01*
X1489122D01*
X1488937Y913065D01*
Y913240D01*
X1490337D01*
Y913065D01*
G37*
G36*
G01X1486647Y913067D02*
X1486462Y912467D01*
X1485432D01*
X1485247Y913067D01*
Y913241D01*
X1486647D01*
Y913067D01*
G37*
G36*
G01X1493506Y910432D02*
X1492894Y910292D01*
X1492379Y911184D01*
X1492806Y911644D01*
X1492957Y911731D01*
X1493657Y910519D01*
X1493506Y910432D01*
G37*
G36*
G01X1490337Y913065D02*
X1490152Y912465D01*
X1489122D01*
X1488937Y913065D01*
Y913240D01*
X1490337D01*
Y913065D01*
G37*
G36*
G01X1486647Y913067D02*
X1486462Y912467D01*
X1485432D01*
X1485247Y913067D01*
Y913241D01*
X1486647D01*
Y913067D01*
G37*
G36*
G01X1491657Y907225D02*
X1491045Y907085D01*
X1490530Y907977D01*
X1490957Y908437D01*
X1491108Y908524D01*
X1491808Y907312D01*
X1491657Y907225D01*
G37*
G36*
G01X1488554Y909861D02*
X1488369Y909261D01*
X1487339D01*
X1487154Y909861D01*
Y910035D01*
X1488554D01*
Y909861D01*
G37*
G36*
G01X1494047Y906657D02*
X1493862Y906057D01*
X1492832D01*
X1492647Y906657D01*
Y906831D01*
X1494047D01*
Y906657D01*
G37*
G36*
G01X1491657Y907225D02*
X1491045Y907085D01*
X1490530Y907977D01*
X1490957Y908437D01*
X1491108Y908524D01*
X1491808Y907312D01*
X1491657Y907225D01*
G37*
G36*
G01X1488554Y909861D02*
X1488369Y909261D01*
X1487339D01*
X1487154Y909861D01*
Y910035D01*
X1488554D01*
Y909861D01*
G37*
G36*
G01X1494047Y906657D02*
X1493862Y906057D01*
X1492832D01*
X1492647Y906657D01*
Y906831D01*
X1494047D01*
Y906657D01*
G37*
G36*
G01X1489785Y904059D02*
X1489173Y903919D01*
X1488658Y904811D01*
X1489085Y905271D01*
X1489236Y905358D01*
X1489936Y904146D01*
X1489785Y904059D01*
G37*
G36*
G01X1486637Y906657D02*
X1486452Y906057D01*
X1485422D01*
X1485237Y906657D01*
Y906831D01*
X1486637D01*
Y906657D01*
G37*
G36*
G01X1492254Y903453D02*
X1492069Y902853D01*
X1491039D01*
X1490854Y903453D01*
Y903627D01*
X1492254D01*
Y903453D01*
G37*
G36*
G01X1489785Y904059D02*
X1489173Y903919D01*
X1488658Y904811D01*
X1489085Y905271D01*
X1489236Y905358D01*
X1489936Y904146D01*
X1489785Y904059D01*
G37*
G36*
G01X1486637Y906657D02*
X1486452Y906057D01*
X1485422D01*
X1485237Y906657D01*
Y906831D01*
X1486637D01*
Y906657D01*
G37*
G36*
G01X1492254Y903453D02*
X1492069Y902853D01*
X1491039D01*
X1490854Y903453D01*
Y903627D01*
X1492254D01*
Y903453D01*
G37*
G36*
G01X1490854Y901845D02*
X1491039Y902445D01*
X1492069D01*
X1492254Y901845D01*
Y901671D01*
X1490854D01*
Y901845D01*
G37*
G36*
G01X1487713Y904431D02*
X1488325Y904571D01*
X1488840Y903679D01*
X1488413Y903219D01*
X1488262Y903132D01*
X1487562Y904344D01*
X1487713Y904431D01*
G37*
G36*
G01X1490854Y901845D02*
X1491039Y902445D01*
X1492069D01*
X1492254Y901845D01*
Y901671D01*
X1490854D01*
Y901845D01*
G37*
G36*
G01X1487713Y904431D02*
X1488325Y904571D01*
X1488840Y903679D01*
X1488413Y903219D01*
X1488262Y903132D01*
X1487562Y904344D01*
X1487713Y904431D01*
G37*
G36*
G01X1483454Y908253D02*
X1483639Y908853D01*
X1484669D01*
X1484854Y908253D01*
Y908079D01*
X1483454D01*
Y908253D01*
G37*
G36*
G01X1489534Y907685D02*
X1490146Y907825D01*
X1490661Y906933D01*
X1490234Y906473D01*
X1490083Y906386D01*
X1489383Y907598D01*
X1489534Y907685D01*
G37*
G36*
G01X1487154Y908253D02*
X1487339Y908853D01*
X1488369D01*
X1488554Y908253D01*
Y908079D01*
X1487154D01*
Y908253D01*
G37*
G36*
G01X1492647Y905049D02*
X1492832Y905649D01*
X1493862D01*
X1494047Y905049D01*
Y904875D01*
X1492647D01*
Y905049D01*
G37*
G36*
G01X1483454Y908253D02*
X1483639Y908853D01*
X1484669D01*
X1484854Y908253D01*
Y908079D01*
X1483454D01*
Y908253D01*
G37*
G36*
G01X1489534Y907685D02*
X1490146Y907825D01*
X1490661Y906933D01*
X1490234Y906473D01*
X1490083Y906386D01*
X1489383Y907598D01*
X1489534Y907685D01*
G37*
G36*
G01X1487154Y908253D02*
X1487339Y908853D01*
X1488369D01*
X1488554Y908253D01*
Y908079D01*
X1487154D01*
Y908253D01*
G37*
G36*
G01X1492647Y905049D02*
X1492832Y905649D01*
X1493862D01*
X1494047Y905049D01*
Y904875D01*
X1492647D01*
Y905049D01*
G37*
G36*
G01X1487929Y900871D02*
X1487317Y900731D01*
X1486802Y901623D01*
X1487229Y902083D01*
X1487380Y902170D01*
X1488080Y900958D01*
X1487929Y900871D01*
G37*
G36*
G01D02*
X1487317Y900731D01*
X1486802Y901623D01*
X1487229Y902083D01*
X1487380Y902170D01*
X1488080Y900958D01*
X1487929Y900871D01*
G37*
G36*
G01X1486647Y932291D02*
X1486462Y931691D01*
X1485432D01*
X1485247Y932291D01*
Y932466D01*
X1486647D01*
Y932291D01*
G37*
G36*
G01X1490337D02*
X1490152Y931691D01*
X1489122D01*
X1488937Y932291D01*
Y932465D01*
X1490337D01*
Y932291D01*
G37*
G36*
G01X1494037D02*
X1493852Y931691D01*
X1492822D01*
X1492637Y932291D01*
Y932465D01*
X1494037D01*
Y932291D01*
G37*
G36*
G01X1486647D02*
X1486462Y931691D01*
X1485432D01*
X1485247Y932291D01*
Y932466D01*
X1486647D01*
Y932291D01*
G37*
G36*
G01X1490337D02*
X1490152Y931691D01*
X1489122D01*
X1488937Y932291D01*
Y932465D01*
X1490337D01*
Y932291D01*
G37*
G36*
G01X1494037D02*
X1493852Y931691D01*
X1492822D01*
X1492637Y932291D01*
Y932465D01*
X1494037D01*
Y932291D01*
G37*
G36*
G01X1488937Y930685D02*
X1489122Y931285D01*
X1490152D01*
X1490337Y930685D01*
Y930510D01*
X1488937D01*
Y930685D01*
G37*
G36*
G01X1485247Y930683D02*
X1485432Y931283D01*
X1486462D01*
X1486647Y930683D01*
Y930509D01*
X1485247D01*
Y930683D01*
G37*
G36*
G01X1492637Y930685D02*
X1492822Y931285D01*
X1493852D01*
X1494037Y930685D01*
Y930510D01*
X1492637D01*
Y930685D01*
G37*
G36*
G01X1488937D02*
X1489122Y931285D01*
X1490152D01*
X1490337Y930685D01*
Y930510D01*
X1488937D01*
Y930685D01*
G37*
G36*
G01X1485247Y930683D02*
X1485432Y931283D01*
X1486462D01*
X1486647Y930683D01*
Y930509D01*
X1485247D01*
Y930683D01*
G37*
G36*
G01X1492637Y930685D02*
X1492822Y931285D01*
X1493852D01*
X1494037Y930685D01*
Y930510D01*
X1492637D01*
Y930685D01*
G37*
G36*
G01X1482937Y919473D02*
X1482752Y918873D01*
X1481722D01*
X1481537Y919473D01*
Y919648D01*
X1482937D01*
Y919473D01*
G37*
G36*
G01X1490337D02*
X1490152Y918873D01*
X1489122D01*
X1488937Y919473D01*
Y919648D01*
X1490337D01*
Y919473D01*
G37*
G36*
G01X1486670Y919475D02*
X1486485Y918875D01*
X1485455D01*
X1485270Y919475D01*
Y919649D01*
X1486670D01*
Y919475D01*
G37*
G36*
G01X1494037Y919473D02*
X1493852Y918873D01*
X1492822D01*
X1492637Y919473D01*
Y919648D01*
X1494037D01*
Y919473D01*
G37*
G36*
G01X1482937D02*
X1482752Y918873D01*
X1481722D01*
X1481537Y919473D01*
Y919648D01*
X1482937D01*
Y919473D01*
G37*
G36*
G01X1490337D02*
X1490152Y918873D01*
X1489122D01*
X1488937Y919473D01*
Y919648D01*
X1490337D01*
Y919473D01*
G37*
G36*
G01X1486670Y919475D02*
X1486485Y918875D01*
X1485455D01*
X1485270Y919475D01*
Y919649D01*
X1486670D01*
Y919475D01*
G37*
G36*
G01X1494037Y919473D02*
X1493852Y918873D01*
X1492822D01*
X1492637Y919473D01*
Y919648D01*
X1494037D01*
Y919473D01*
G37*
G36*
G01X1487104Y921069D02*
X1487289Y921669D01*
X1488319D01*
X1488504Y921069D01*
Y920895D01*
X1487104D01*
Y921069D01*
G37*
G36*
G01X1490804D02*
X1490989Y921669D01*
X1492019D01*
X1492204Y921069D01*
Y920895D01*
X1490804D01*
Y921069D01*
G37*
G36*
G01X1487104D02*
X1487289Y921669D01*
X1488319D01*
X1488504Y921069D01*
Y920895D01*
X1487104D01*
Y921069D01*
G37*
G36*
G01X1490804D02*
X1490989Y921669D01*
X1492019D01*
X1492204Y921069D01*
Y920895D01*
X1490804D01*
Y921069D01*
G37*
G36*
G01X1481537Y917867D02*
X1481722Y918467D01*
X1482752D01*
X1482937Y917867D01*
Y917692D01*
X1481537D01*
Y917867D01*
G37*
G36*
G01X1485237D02*
X1485422Y918467D01*
X1486452D01*
X1486637Y917867D01*
Y917692D01*
X1485237D01*
Y917867D01*
G37*
G36*
G01X1492637D02*
X1492822Y918467D01*
X1493852D01*
X1494037Y917867D01*
Y917692D01*
X1492637D01*
Y917867D01*
G37*
G36*
G01X1488937D02*
X1489122Y918467D01*
X1490152D01*
X1490337Y917867D01*
Y917692D01*
X1488937D01*
Y917867D01*
G37*
G36*
G01X1481537D02*
X1481722Y918467D01*
X1482752D01*
X1482937Y917867D01*
Y917692D01*
X1481537D01*
Y917867D01*
G37*
G36*
G01X1485237D02*
X1485422Y918467D01*
X1486452D01*
X1486637Y917867D01*
Y917692D01*
X1485237D01*
Y917867D01*
G37*
G36*
G01X1492637D02*
X1492822Y918467D01*
X1493852D01*
X1494037Y917867D01*
Y917692D01*
X1492637D01*
Y917867D01*
G37*
G36*
G01X1488937D02*
X1489122Y918467D01*
X1490152D01*
X1490337Y917867D01*
Y917692D01*
X1488937D01*
Y917867D01*
G37*
G36*
G01X1492254Y929087D02*
X1492069Y928487D01*
X1491039D01*
X1490854Y929087D01*
Y929261D01*
X1492254D01*
Y929087D01*
G37*
G36*
G01X1488554D02*
X1488369Y928487D01*
X1487339D01*
X1487154Y929087D01*
Y929261D01*
X1488554D01*
Y929087D01*
G37*
G36*
G01X1492254D02*
X1492069Y928487D01*
X1491039D01*
X1490854Y929087D01*
Y929261D01*
X1492254D01*
Y929087D01*
G37*
G36*
G01X1488554D02*
X1488369Y928487D01*
X1487339D01*
X1487154Y929087D01*
Y929261D01*
X1488554D01*
Y929087D01*
G37*
G36*
G01X1492254Y922679D02*
X1492069Y922079D01*
X1491039D01*
X1490854Y922679D01*
Y922853D01*
X1492254D01*
Y922679D01*
G37*
G36*
G01X1488544D02*
X1488359Y922079D01*
X1487329D01*
X1487144Y922679D01*
Y922853D01*
X1488544D01*
Y922679D01*
G37*
G36*
G01X1492254D02*
X1492069Y922079D01*
X1491039D01*
X1490854Y922679D01*
Y922853D01*
X1492254D01*
Y922679D01*
G37*
G36*
G01X1488544D02*
X1488359Y922079D01*
X1487329D01*
X1487144Y922679D01*
Y922853D01*
X1488544D01*
Y922679D01*
G37*
G36*
G01X1487083Y927477D02*
X1487268Y928077D01*
X1488298D01*
X1488483Y927477D01*
Y927302D01*
X1487083D01*
Y927477D01*
G37*
G36*
G01X1490807Y927479D02*
X1490992Y928079D01*
X1492022D01*
X1492207Y927479D01*
Y927304D01*
X1490807D01*
Y927479D01*
G37*
G36*
G01X1487083Y927477D02*
X1487268Y928077D01*
X1488298D01*
X1488483Y927477D01*
Y927302D01*
X1487083D01*
Y927477D01*
G37*
G36*
G01X1490807Y927479D02*
X1490992Y928079D01*
X1492022D01*
X1492207Y927479D01*
Y927304D01*
X1490807D01*
Y927479D01*
G37*
G36*
G01X1485270Y924275D02*
X1485455Y924875D01*
X1486485D01*
X1486670Y924275D01*
Y924100D01*
X1485270D01*
Y924275D01*
G37*
G36*
G01X1492647D02*
X1492832Y924875D01*
X1493862D01*
X1494047Y924275D01*
Y924101D01*
X1492647D01*
Y924275D01*
G37*
G36*
G01X1488937D02*
X1489122Y924875D01*
X1490152D01*
X1490337Y924275D01*
Y924101D01*
X1488937D01*
Y924275D01*
G37*
G36*
G01X1485270D02*
X1485455Y924875D01*
X1486485D01*
X1486670Y924275D01*
Y924100D01*
X1485270D01*
Y924275D01*
G37*
G36*
G01X1492647D02*
X1492832Y924875D01*
X1493862D01*
X1494047Y924275D01*
Y924101D01*
X1492647D01*
Y924275D01*
G37*
G36*
G01X1488937D02*
X1489122Y924875D01*
X1490152D01*
X1490337Y924275D01*
Y924101D01*
X1488937D01*
Y924275D01*
G37*
G36*
G01X1494084Y925883D02*
X1493899Y925283D01*
X1492869D01*
X1492684Y925883D01*
Y926058D01*
X1494084D01*
Y925883D01*
G37*
G36*
G01X1490384D02*
X1490199Y925283D01*
X1489169D01*
X1488984Y925883D01*
Y926058D01*
X1490384D01*
Y925883D01*
G37*
G36*
G01X1494084D02*
X1493899Y925283D01*
X1492869D01*
X1492684Y925883D01*
Y926058D01*
X1494084D01*
Y925883D01*
G37*
G36*
G01X1490384D02*
X1490199Y925283D01*
X1489169D01*
X1488984Y925883D01*
Y926058D01*
X1490384D01*
Y925883D01*
G37*
G36*
G01X1484821Y948313D02*
X1484636Y947713D01*
X1483606D01*
X1483421Y948313D01*
Y948488D01*
X1484821D01*
Y948313D01*
G37*
G36*
G01X1488554D02*
X1488369Y947713D01*
X1487339D01*
X1487154Y948313D01*
Y948487D01*
X1488554D01*
Y948313D01*
G37*
G36*
G01X1492254D02*
X1492069Y947713D01*
X1491039D01*
X1490854Y948313D01*
Y948487D01*
X1492254D01*
Y948313D01*
G37*
G36*
G01X1484821D02*
X1484636Y947713D01*
X1483606D01*
X1483421Y948313D01*
Y948488D01*
X1484821D01*
Y948313D01*
G37*
G36*
G01X1488554D02*
X1488369Y947713D01*
X1487339D01*
X1487154Y948313D01*
Y948487D01*
X1488554D01*
Y948313D01*
G37*
G36*
G01X1492254D02*
X1492069Y947713D01*
X1491039D01*
X1490854Y948313D01*
Y948487D01*
X1492254D01*
Y948313D01*
G37*
G36*
G01X1490804Y940295D02*
X1490989Y940895D01*
X1492019D01*
X1492204Y940295D01*
Y940121D01*
X1490804D01*
Y940295D01*
G37*
G36*
G01X1487104D02*
X1487289Y940895D01*
X1488319D01*
X1488504Y940295D01*
Y940121D01*
X1487104D01*
Y940295D01*
G37*
G36*
G01X1490804D02*
X1490989Y940895D01*
X1492019D01*
X1492204Y940295D01*
Y940121D01*
X1490804D01*
Y940295D01*
G37*
G36*
G01X1487104D02*
X1487289Y940895D01*
X1488319D01*
X1488504Y940295D01*
Y940121D01*
X1487104D01*
Y940295D01*
G37*
G36*
G01X1492684Y937091D02*
X1492869Y937691D01*
X1493899D01*
X1494084Y937091D01*
Y936916D01*
X1492684D01*
Y937091D01*
G37*
G36*
G01X1488984D02*
X1489169Y937691D01*
X1490199D01*
X1490384Y937091D01*
Y936916D01*
X1488984D01*
Y937091D01*
G37*
G36*
G01X1485284D02*
X1485469Y937691D01*
X1486499D01*
X1486684Y937091D01*
Y936916D01*
X1485284D01*
Y937091D01*
G37*
G36*
G01X1492684D02*
X1492869Y937691D01*
X1493899D01*
X1494084Y937091D01*
Y936916D01*
X1492684D01*
Y937091D01*
G37*
G36*
G01X1488984D02*
X1489169Y937691D01*
X1490199D01*
X1490384Y937091D01*
Y936916D01*
X1488984D01*
Y937091D01*
G37*
G36*
G01X1485284D02*
X1485469Y937691D01*
X1486499D01*
X1486684Y937091D01*
Y936916D01*
X1485284D01*
Y937091D01*
G37*
G36*
G01X1494087Y938701D02*
X1493902Y938101D01*
X1492872D01*
X1492687Y938701D01*
Y938875D01*
X1494087D01*
Y938701D01*
G37*
G36*
G01X1490387D02*
X1490202Y938101D01*
X1489172D01*
X1488987Y938701D01*
Y938875D01*
X1490387D01*
Y938701D01*
G37*
G36*
G01X1486687D02*
X1486502Y938101D01*
X1485472D01*
X1485287Y938701D01*
Y938875D01*
X1486687D01*
Y938701D01*
G37*
G36*
G01X1494087D02*
X1493902Y938101D01*
X1492872D01*
X1492687Y938701D01*
Y938875D01*
X1494087D01*
Y938701D01*
G37*
G36*
G01X1490387D02*
X1490202Y938101D01*
X1489172D01*
X1488987Y938701D01*
Y938875D01*
X1490387D01*
Y938701D01*
G37*
G36*
G01X1486687D02*
X1486502Y938101D01*
X1485472D01*
X1485287Y938701D01*
Y938875D01*
X1486687D01*
Y938701D01*
G37*
G36*
G01X1484807Y935497D02*
X1484622Y934897D01*
X1483592D01*
X1483407Y935497D01*
Y935671D01*
X1484807D01*
Y935497D01*
G37*
G36*
G01X1492207D02*
X1492022Y934897D01*
X1490992D01*
X1490807Y935497D01*
Y935671D01*
X1492207D01*
Y935497D01*
G37*
G36*
G01X1488507D02*
X1488322Y934897D01*
X1487292D01*
X1487107Y935497D01*
Y935671D01*
X1488507D01*
Y935497D01*
G37*
G36*
G01X1484807D02*
X1484622Y934897D01*
X1483592D01*
X1483407Y935497D01*
Y935671D01*
X1484807D01*
Y935497D01*
G37*
G36*
G01X1492207D02*
X1492022Y934897D01*
X1490992D01*
X1490807Y935497D01*
Y935671D01*
X1492207D01*
Y935497D01*
G37*
G36*
G01X1488507D02*
X1488322Y934897D01*
X1487292D01*
X1487107Y935497D01*
Y935671D01*
X1488507D01*
Y935497D01*
G37*
G36*
G01X1483421Y933887D02*
X1483606Y934487D01*
X1484636D01*
X1484821Y933887D01*
Y933713D01*
X1483421D01*
Y933887D01*
G37*
G36*
G01X1490854Y933889D02*
X1491039Y934489D01*
X1492069D01*
X1492254Y933889D01*
Y933714D01*
X1490854D01*
Y933889D01*
G37*
G36*
G01X1487154D02*
X1487339Y934489D01*
X1488369D01*
X1488554Y933889D01*
Y933714D01*
X1487154D01*
Y933889D01*
G37*
G36*
G01X1483421Y933887D02*
X1483606Y934487D01*
X1484636D01*
X1484821Y933887D01*
Y933713D01*
X1483421D01*
Y933887D01*
G37*
G36*
G01X1490854Y933889D02*
X1491039Y934489D01*
X1492069D01*
X1492254Y933889D01*
Y933714D01*
X1490854D01*
Y933889D01*
G37*
G36*
G01X1487154D02*
X1487339Y934489D01*
X1488369D01*
X1488554Y933889D01*
Y933714D01*
X1487154D01*
Y933889D01*
G37*
G36*
G01X1494047Y945107D02*
X1493862Y944507D01*
X1492832D01*
X1492647Y945107D01*
Y945282D01*
X1494047D01*
Y945107D01*
G37*
G36*
G01X1490337D02*
X1490152Y944507D01*
X1489122D01*
X1488937Y945107D01*
Y945282D01*
X1490337D01*
Y945107D01*
G37*
G36*
G01X1486637D02*
X1486452Y944507D01*
X1485422D01*
X1485237Y945107D01*
Y945282D01*
X1486637D01*
Y945107D01*
G37*
G36*
G01X1494047D02*
X1493862Y944507D01*
X1492832D01*
X1492647Y945107D01*
Y945282D01*
X1494047D01*
Y945107D01*
G37*
G36*
G01X1490337D02*
X1490152Y944507D01*
X1489122D01*
X1488937Y945107D01*
Y945282D01*
X1490337D01*
Y945107D01*
G37*
G36*
G01X1486637D02*
X1486452Y944507D01*
X1485422D01*
X1485237Y945107D01*
Y945282D01*
X1486637D01*
Y945107D01*
G37*
G36*
G01X1492647Y943501D02*
X1492832Y944101D01*
X1493862D01*
X1494047Y943501D01*
Y943326D01*
X1492647D01*
Y943501D01*
G37*
G36*
G01X1488937D02*
X1489122Y944101D01*
X1490152D01*
X1490337Y943501D01*
Y943326D01*
X1488937D01*
Y943501D01*
G37*
G36*
G01X1492647D02*
X1492832Y944101D01*
X1493862D01*
X1494047Y943501D01*
Y943326D01*
X1492647D01*
Y943501D01*
G37*
G36*
G01X1488937D02*
X1489122Y944101D01*
X1490152D01*
X1490337Y943501D01*
Y943326D01*
X1488937D01*
Y943501D01*
G37*
G36*
G01X1483454Y946705D02*
X1483639Y947305D01*
X1484669D01*
X1484854Y946705D01*
Y946531D01*
X1483454D01*
Y946705D01*
G37*
G36*
G01X1490854D02*
X1491039Y947305D01*
X1492069D01*
X1492254Y946705D01*
Y946531D01*
X1490854D01*
Y946705D01*
G37*
G36*
G01X1487154D02*
X1487339Y947305D01*
X1488369D01*
X1488554Y946705D01*
Y946531D01*
X1487154D01*
Y946705D01*
G37*
G36*
G01X1483454D02*
X1483639Y947305D01*
X1484669D01*
X1484854Y946705D01*
Y946531D01*
X1483454D01*
Y946705D01*
G37*
G36*
G01X1490854D02*
X1491039Y947305D01*
X1492069D01*
X1492254Y946705D01*
Y946531D01*
X1490854D01*
Y946705D01*
G37*
G36*
G01X1487154D02*
X1487339Y947305D01*
X1488369D01*
X1488554Y946705D01*
Y946531D01*
X1487154D01*
Y946705D01*
G37*
G36*
G01X1492254Y941903D02*
X1492069Y941303D01*
X1491039D01*
X1490854Y941903D01*
Y942078D01*
X1492254D01*
Y941903D01*
G37*
G36*
G01X1488520Y941905D02*
X1488335Y941305D01*
X1487305D01*
X1487120Y941905D01*
Y942080D01*
X1488520D01*
Y941905D01*
G37*
G36*
G01X1492254Y941903D02*
X1492069Y941303D01*
X1491039D01*
X1490854Y941903D01*
Y942078D01*
X1492254D01*
Y941903D01*
G37*
G36*
G01X1488520Y941905D02*
X1488335Y941305D01*
X1487305D01*
X1487120Y941905D01*
Y942080D01*
X1488520D01*
Y941905D01*
G37*
G36*
G01X1483421Y953113D02*
X1483606Y953713D01*
X1484636D01*
X1484821Y953113D01*
Y952938D01*
X1483421D01*
Y953113D01*
G37*
G36*
G01X1479754D02*
X1479939Y953713D01*
X1480969D01*
X1481154Y953113D01*
Y952939D01*
X1479754D01*
Y953113D01*
G37*
G36*
G01X1490854D02*
X1491039Y953713D01*
X1492069D01*
X1492254Y953113D01*
Y952939D01*
X1490854D01*
Y953113D01*
G37*
G36*
G01X1487154D02*
X1487339Y953713D01*
X1488369D01*
X1488554Y953113D01*
Y952939D01*
X1487154D01*
Y953113D01*
G37*
G36*
G01X1483421D02*
X1483606Y953713D01*
X1484636D01*
X1484821Y953113D01*
Y952938D01*
X1483421D01*
Y953113D01*
G37*
G36*
G01X1479754D02*
X1479939Y953713D01*
X1480969D01*
X1481154Y953113D01*
Y952939D01*
X1479754D01*
Y953113D01*
G37*
G36*
G01X1490854D02*
X1491039Y953713D01*
X1492069D01*
X1492254Y953113D01*
Y952939D01*
X1490854D01*
Y953113D01*
G37*
G36*
G01X1487154D02*
X1487339Y953713D01*
X1488369D01*
X1488554Y953113D01*
Y952939D01*
X1487154D01*
Y953113D01*
G37*
G36*
G01X1481547Y949909D02*
X1481732Y950509D01*
X1482762D01*
X1482947Y949909D01*
Y949735D01*
X1481547D01*
Y949909D01*
G37*
G36*
G01X1488937D02*
X1489122Y950509D01*
X1490152D01*
X1490337Y949909D01*
Y949735D01*
X1488937D01*
Y949909D01*
G37*
G36*
G01X1492637D02*
X1492822Y950509D01*
X1493852D01*
X1494037Y949909D01*
Y949735D01*
X1492637D01*
Y949909D01*
G37*
G36*
G01X1485247D02*
X1485432Y950509D01*
X1486462D01*
X1486647Y949909D01*
Y949734D01*
X1485247D01*
Y949909D01*
G37*
G36*
G01X1481547D02*
X1481732Y950509D01*
X1482762D01*
X1482947Y949909D01*
Y949735D01*
X1481547D01*
Y949909D01*
G37*
G36*
G01X1488937D02*
X1489122Y950509D01*
X1490152D01*
X1490337Y949909D01*
Y949735D01*
X1488937D01*
Y949909D01*
G37*
G36*
G01X1492637D02*
X1492822Y950509D01*
X1493852D01*
X1494037Y949909D01*
Y949735D01*
X1492637D01*
Y949909D01*
G37*
G36*
G01X1485247D02*
X1485432Y950509D01*
X1486462D01*
X1486647Y949909D01*
Y949734D01*
X1485247D01*
Y949909D01*
G37*
G36*
G01X1482947Y951517D02*
X1482762Y950917D01*
X1481732D01*
X1481547Y951517D01*
Y951691D01*
X1482947D01*
Y951517D01*
G37*
G36*
G01X1494037D02*
X1493852Y950917D01*
X1492822D01*
X1492637Y951517D01*
Y951691D01*
X1494037D01*
Y951517D01*
G37*
G36*
G01X1486647D02*
X1486462Y950917D01*
X1485432D01*
X1485247Y951517D01*
Y951692D01*
X1486647D01*
Y951517D01*
G37*
G36*
G01X1490337D02*
X1490152Y950917D01*
X1489122D01*
X1488937Y951517D01*
Y951691D01*
X1490337D01*
Y951517D01*
G37*
G36*
G01X1482947D02*
X1482762Y950917D01*
X1481732D01*
X1481547Y951517D01*
Y951691D01*
X1482947D01*
Y951517D01*
G37*
G36*
G01X1494037D02*
X1493852Y950917D01*
X1492822D01*
X1492637Y951517D01*
Y951691D01*
X1494037D01*
Y951517D01*
G37*
G36*
G01X1486647D02*
X1486462Y950917D01*
X1485432D01*
X1485247Y951517D01*
Y951692D01*
X1486647D01*
Y951517D01*
G37*
G36*
G01X1490337D02*
X1490152Y950917D01*
X1489122D01*
X1488937Y951517D01*
Y951691D01*
X1490337D01*
Y951517D01*
G37*
G36*
G01X1483444Y959521D02*
X1483629Y960121D01*
X1484659D01*
X1484844Y959521D01*
Y959347D01*
X1483444D01*
Y959521D01*
G37*
G36*
G01X1479754Y959523D02*
X1479939Y960123D01*
X1480969D01*
X1481154Y959523D01*
Y959348D01*
X1479754D01*
Y959523D01*
G37*
G36*
G01X1490854D02*
X1491039Y960123D01*
X1492069D01*
X1492254Y959523D01*
Y959348D01*
X1490854D01*
Y959523D01*
G37*
G36*
G01X1487144D02*
X1487329Y960123D01*
X1488359D01*
X1488544Y959523D01*
Y959348D01*
X1487144D01*
Y959523D01*
G37*
G36*
G01X1483444Y959521D02*
X1483629Y960121D01*
X1484659D01*
X1484844Y959521D01*
Y959347D01*
X1483444D01*
Y959521D01*
G37*
G36*
G01X1479754Y959523D02*
X1479939Y960123D01*
X1480969D01*
X1481154Y959523D01*
Y959348D01*
X1479754D01*
Y959523D01*
G37*
G36*
G01X1490854D02*
X1491039Y960123D01*
X1492069D01*
X1492254Y959523D01*
Y959348D01*
X1490854D01*
Y959523D01*
G37*
G36*
G01X1487144D02*
X1487329Y960123D01*
X1488359D01*
X1488544Y959523D01*
Y959348D01*
X1487144D01*
Y959523D01*
G37*
G36*
G01X1482937Y957925D02*
X1482752Y957325D01*
X1481722D01*
X1481537Y957925D01*
Y958100D01*
X1482937D01*
Y957925D01*
G37*
G36*
G01X1486670Y957927D02*
X1486485Y957327D01*
X1485455D01*
X1485270Y957927D01*
Y958101D01*
X1486670D01*
Y957927D01*
G37*
G36*
G01X1490337Y957925D02*
X1490152Y957325D01*
X1489122D01*
X1488937Y957925D01*
Y958100D01*
X1490337D01*
Y957925D01*
G37*
G36*
G01X1494037D02*
X1493852Y957325D01*
X1492822D01*
X1492637Y957925D01*
Y958100D01*
X1494037D01*
Y957925D01*
G37*
G36*
G01X1482937D02*
X1482752Y957325D01*
X1481722D01*
X1481537Y957925D01*
Y958100D01*
X1482937D01*
Y957925D01*
G37*
G36*
G01X1486670Y957927D02*
X1486485Y957327D01*
X1485455D01*
X1485270Y957927D01*
Y958101D01*
X1486670D01*
Y957927D01*
G37*
G36*
G01X1490337Y957925D02*
X1490152Y957325D01*
X1489122D01*
X1488937Y957925D01*
Y958100D01*
X1490337D01*
Y957925D01*
G37*
G36*
G01X1494037D02*
X1493852Y957325D01*
X1492822D01*
X1492637Y957925D01*
Y958100D01*
X1494037D01*
Y957925D01*
G37*
G36*
G01X1481537Y962727D02*
X1481722Y963327D01*
X1482752D01*
X1482937Y962727D01*
Y962552D01*
X1481537D01*
Y962727D01*
G37*
G36*
G01X1477847Y962725D02*
X1478032Y963325D01*
X1479062D01*
X1479247Y962725D01*
Y962551D01*
X1477847D01*
Y962725D01*
G37*
G36*
G01X1492647Y962727D02*
X1492832Y963327D01*
X1493862D01*
X1494047Y962727D01*
Y962552D01*
X1492647D01*
Y962727D01*
G37*
G36*
G01X1488937D02*
X1489122Y963327D01*
X1490152D01*
X1490337Y962727D01*
Y962552D01*
X1488937D01*
Y962727D01*
G37*
G36*
G01X1485270Y962725D02*
X1485455Y963325D01*
X1486485D01*
X1486670Y962725D01*
Y962551D01*
X1485270D01*
Y962725D01*
G37*
G36*
G01X1481537Y962727D02*
X1481722Y963327D01*
X1482752D01*
X1482937Y962727D01*
Y962552D01*
X1481537D01*
Y962727D01*
G37*
G36*
G01X1477847Y962725D02*
X1478032Y963325D01*
X1479062D01*
X1479247Y962725D01*
Y962551D01*
X1477847D01*
Y962725D01*
G37*
G36*
G01X1492647Y962727D02*
X1492832Y963327D01*
X1493862D01*
X1494047Y962727D01*
Y962552D01*
X1492647D01*
Y962727D01*
G37*
G36*
G01X1488937D02*
X1489122Y963327D01*
X1490152D01*
X1490337Y962727D01*
Y962552D01*
X1488937D01*
Y962727D01*
G37*
G36*
G01X1485270Y962725D02*
X1485455Y963325D01*
X1486485D01*
X1486670Y962725D01*
Y962551D01*
X1485270D01*
Y962725D01*
G37*
G36*
G01X1492254Y961129D02*
X1492069Y960529D01*
X1491039D01*
X1490854Y961129D01*
Y961304D01*
X1492254D01*
Y961129D01*
G37*
G36*
G01X1488544D02*
X1488359Y960529D01*
X1487329D01*
X1487144Y961129D01*
Y961304D01*
X1488544D01*
Y961129D01*
G37*
G36*
G01X1492254D02*
X1492069Y960529D01*
X1491039D01*
X1490854Y961129D01*
Y961304D01*
X1492254D01*
Y961129D01*
G37*
G36*
G01X1488544D02*
X1488359Y960529D01*
X1487329D01*
X1487144Y961129D01*
Y961304D01*
X1488544D01*
Y961129D01*
G37*
G36*
G01X1477837Y981953D02*
X1478022Y982553D01*
X1479052D01*
X1479237Y981953D01*
Y981778D01*
X1477837D01*
Y981953D01*
G37*
G36*
G01X1481537D02*
X1481722Y982553D01*
X1482752D01*
X1482937Y981953D01*
Y981778D01*
X1481537D01*
Y981953D01*
G37*
G36*
G01X1492647D02*
X1492832Y982553D01*
X1493862D01*
X1494047Y981953D01*
Y981778D01*
X1492647D01*
Y981953D01*
G37*
G36*
G01X1485270Y981951D02*
X1485455Y982551D01*
X1486485D01*
X1486670Y981951D01*
Y981777D01*
X1485270D01*
Y981951D01*
G37*
G36*
G01X1488937Y981953D02*
X1489122Y982553D01*
X1490152D01*
X1490337Y981953D01*
Y981778D01*
X1488937D01*
Y981953D01*
G37*
G36*
G01X1477837D02*
X1478022Y982553D01*
X1479052D01*
X1479237Y981953D01*
Y981778D01*
X1477837D01*
Y981953D01*
G37*
G36*
G01X1481537D02*
X1481722Y982553D01*
X1482752D01*
X1482937Y981953D01*
Y981778D01*
X1481537D01*
Y981953D01*
G37*
G36*
G01X1492647D02*
X1492832Y982553D01*
X1493862D01*
X1494047Y981953D01*
Y981778D01*
X1492647D01*
Y981953D01*
G37*
G36*
G01X1485270Y981951D02*
X1485455Y982551D01*
X1486485D01*
X1486670Y981951D01*
Y981777D01*
X1485270D01*
Y981951D01*
G37*
G36*
G01X1488937Y981953D02*
X1489122Y982553D01*
X1490152D01*
X1490337Y981953D01*
Y981778D01*
X1488937D01*
Y981953D01*
G37*
G36*
G01X1483444Y978747D02*
X1483629Y979347D01*
X1484659D01*
X1484844Y978747D01*
Y978573D01*
X1483444D01*
Y978747D01*
G37*
G36*
G01X1479754Y978749D02*
X1479939Y979349D01*
X1480969D01*
X1481154Y978749D01*
Y978574D01*
X1479754D01*
Y978749D01*
G37*
G36*
G01X1490821Y978747D02*
X1491006Y979347D01*
X1492036D01*
X1492221Y978747D01*
Y978573D01*
X1490821D01*
Y978747D01*
G37*
G36*
G01X1487144Y978749D02*
X1487329Y979349D01*
X1488359D01*
X1488544Y978749D01*
Y978574D01*
X1487144D01*
Y978749D01*
G37*
G36*
G01X1483444Y978747D02*
X1483629Y979347D01*
X1484659D01*
X1484844Y978747D01*
Y978573D01*
X1483444D01*
Y978747D01*
G37*
G36*
G01X1479754Y978749D02*
X1479939Y979349D01*
X1480969D01*
X1481154Y978749D01*
Y978574D01*
X1479754D01*
Y978749D01*
G37*
G36*
G01X1490821Y978747D02*
X1491006Y979347D01*
X1492036D01*
X1492221Y978747D01*
Y978573D01*
X1490821D01*
Y978747D01*
G37*
G36*
G01X1487144Y978749D02*
X1487329Y979349D01*
X1488359D01*
X1488544Y978749D01*
Y978574D01*
X1487144D01*
Y978749D01*
G37*
G36*
G01X1484844Y980357D02*
X1484659Y979757D01*
X1483629D01*
X1483444Y980357D01*
Y980531D01*
X1484844D01*
Y980357D01*
G37*
G36*
G01X1481154Y980355D02*
X1480969Y979755D01*
X1479939D01*
X1479754Y980355D01*
Y980530D01*
X1481154D01*
Y980355D01*
G37*
G36*
G01X1492254D02*
X1492069Y979755D01*
X1491039D01*
X1490854Y980355D01*
Y980530D01*
X1492254D01*
Y980355D01*
G37*
G36*
G01X1488544D02*
X1488359Y979755D01*
X1487329D01*
X1487144Y980355D01*
Y980530D01*
X1488544D01*
Y980355D01*
G37*
G36*
G01X1484844Y980357D02*
X1484659Y979757D01*
X1483629D01*
X1483444Y980357D01*
Y980531D01*
X1484844D01*
Y980357D01*
G37*
G36*
G01X1481154Y980355D02*
X1480969Y979755D01*
X1479939D01*
X1479754Y980355D01*
Y980530D01*
X1481154D01*
Y980355D01*
G37*
G36*
G01X1492254D02*
X1492069Y979755D01*
X1491039D01*
X1490854Y980355D01*
Y980530D01*
X1492254D01*
Y980355D01*
G37*
G36*
G01X1488544D02*
X1488359Y979755D01*
X1487329D01*
X1487144Y980355D01*
Y980530D01*
X1488544D01*
Y980355D01*
G37*
G36*
G01X1479237Y977151D02*
X1479052Y976551D01*
X1478022D01*
X1477837Y977151D01*
Y977325D01*
X1479237D01*
Y977151D01*
G37*
G36*
G01X1482937D02*
X1482752Y976551D01*
X1481722D01*
X1481537Y977151D01*
Y977325D01*
X1482937D01*
Y977151D01*
G37*
G36*
G01X1494047D02*
X1493862Y976551D01*
X1492832D01*
X1492647Y977151D01*
Y977326D01*
X1494047D01*
Y977151D01*
G37*
G36*
G01X1486670D02*
X1486485Y976551D01*
X1485455D01*
X1485270Y977151D01*
Y977326D01*
X1486670D01*
Y977151D01*
G37*
G36*
G01X1490347D02*
X1490162Y976551D01*
X1489132D01*
X1488947Y977151D01*
Y977325D01*
X1490347D01*
Y977151D01*
G37*
G36*
G01X1479237D02*
X1479052Y976551D01*
X1478022D01*
X1477837Y977151D01*
Y977325D01*
X1479237D01*
Y977151D01*
G37*
G36*
G01X1482937D02*
X1482752Y976551D01*
X1481722D01*
X1481537Y977151D01*
Y977325D01*
X1482937D01*
Y977151D01*
G37*
G36*
G01X1494047D02*
X1493862Y976551D01*
X1492832D01*
X1492647Y977151D01*
Y977326D01*
X1494047D01*
Y977151D01*
G37*
G36*
G01X1486670D02*
X1486485Y976551D01*
X1485455D01*
X1485270Y977151D01*
Y977326D01*
X1486670D01*
Y977151D01*
G37*
G36*
G01X1490347D02*
X1490162Y976551D01*
X1489132D01*
X1488947Y977151D01*
Y977325D01*
X1490347D01*
Y977151D01*
G37*
G36*
G01X1489370Y1027719D02*
X1489555Y1028319D01*
X1490585D01*
X1490770Y1027719D01*
Y1027545D01*
X1489370D01*
Y1027719D01*
G37*
G36*
G01X1485670D02*
X1485855Y1028319D01*
X1486885D01*
X1487070Y1027719D01*
Y1027545D01*
X1485670D01*
Y1027719D01*
G37*
G36*
G01X1489370D02*
X1489555Y1028319D01*
X1490585D01*
X1490770Y1027719D01*
Y1027545D01*
X1489370D01*
Y1027719D01*
G37*
G36*
G01X1485670D02*
X1485855Y1028319D01*
X1486885D01*
X1487070Y1027719D01*
Y1027545D01*
X1485670D01*
Y1027719D01*
G37*
G36*
G01X1490770Y1029327D02*
X1490585Y1028727D01*
X1489555D01*
X1489370Y1029327D01*
Y1029501D01*
X1490770D01*
Y1029327D01*
G37*
G36*
G01X1487070D02*
X1486885Y1028727D01*
X1485855D01*
X1485670Y1029327D01*
Y1029501D01*
X1487070D01*
Y1029327D01*
G37*
G36*
G01X1490770D02*
X1490585Y1028727D01*
X1489555D01*
X1489370Y1029327D01*
Y1029501D01*
X1490770D01*
Y1029327D01*
G37*
G36*
G01X1487070D02*
X1486885Y1028727D01*
X1485855D01*
X1485670Y1029327D01*
Y1029501D01*
X1487070D01*
Y1029327D01*
G37*
G36*
G01X1485287Y1026121D02*
X1485102Y1025521D01*
X1484072D01*
X1483887Y1026121D01*
Y1026296D01*
X1485287D01*
Y1026121D01*
G37*
G36*
G01X1492687D02*
X1492502Y1025521D01*
X1491472D01*
X1491287Y1026121D01*
Y1026296D01*
X1492687D01*
Y1026121D01*
G37*
G36*
G01X1488987D02*
X1488802Y1025521D01*
X1487772D01*
X1487587Y1026121D01*
Y1026296D01*
X1488987D01*
Y1026121D01*
G37*
G36*
G01X1485287D02*
X1485102Y1025521D01*
X1484072D01*
X1483887Y1026121D01*
Y1026296D01*
X1485287D01*
Y1026121D01*
G37*
G36*
G01X1492687D02*
X1492502Y1025521D01*
X1491472D01*
X1491287Y1026121D01*
Y1026296D01*
X1492687D01*
Y1026121D01*
G37*
G36*
G01X1488987D02*
X1488802Y1025521D01*
X1487772D01*
X1487587Y1026121D01*
Y1026296D01*
X1488987D01*
Y1026121D01*
G37*
G36*
G01X1482839Y1026693D02*
X1482227Y1026553D01*
X1481712Y1027445D01*
X1482139Y1027905D01*
X1482290Y1027992D01*
X1482990Y1026780D01*
X1482839Y1026693D01*
G37*
G36*
G01D02*
X1482227Y1026553D01*
X1481712Y1027445D01*
X1482139Y1027905D01*
X1482290Y1027992D01*
X1482990Y1026780D01*
X1482839Y1026693D01*
G37*
G36*
G01X1483837Y1043739D02*
X1484022Y1044339D01*
X1485052D01*
X1485237Y1043739D01*
Y1043565D01*
X1483837D01*
Y1043739D01*
G37*
G36*
G01X1487537D02*
X1487722Y1044339D01*
X1488752D01*
X1488937Y1043739D01*
Y1043565D01*
X1487537D01*
Y1043739D01*
G37*
G36*
G01X1491237D02*
X1491422Y1044339D01*
X1492452D01*
X1492637Y1043739D01*
Y1043565D01*
X1491237D01*
Y1043739D01*
G37*
G36*
G01X1483837D02*
X1484022Y1044339D01*
X1485052D01*
X1485237Y1043739D01*
Y1043565D01*
X1483837D01*
Y1043739D01*
G37*
G36*
G01X1487537D02*
X1487722Y1044339D01*
X1488752D01*
X1488937Y1043739D01*
Y1043565D01*
X1487537D01*
Y1043739D01*
G37*
G36*
G01X1491237D02*
X1491422Y1044339D01*
X1492452D01*
X1492637Y1043739D01*
Y1043565D01*
X1491237D01*
Y1043739D01*
G37*
G36*
G01X1480137D02*
X1480322Y1044339D01*
X1481352D01*
X1481537Y1043739D01*
Y1043565D01*
X1480137D01*
Y1043739D01*
G37*
G36*
G01D02*
X1480322Y1044339D01*
X1481352D01*
X1481537Y1043739D01*
Y1043565D01*
X1480137D01*
Y1043739D01*
G37*
G36*
G01X1489417Y1040535D02*
X1489602Y1041135D01*
X1490632D01*
X1490817Y1040535D01*
Y1040360D01*
X1489417D01*
Y1040535D01*
G37*
G36*
G01X1485717D02*
X1485902Y1041135D01*
X1486932D01*
X1487117Y1040535D01*
Y1040360D01*
X1485717D01*
Y1040535D01*
G37*
G36*
G01X1489417D02*
X1489602Y1041135D01*
X1490632D01*
X1490817Y1040535D01*
Y1040360D01*
X1489417D01*
Y1040535D01*
G37*
G36*
G01X1485717D02*
X1485902Y1041135D01*
X1486932D01*
X1487117Y1040535D01*
Y1040360D01*
X1485717D01*
Y1040535D01*
G37*
G36*
G01X1482017D02*
X1482202Y1041135D01*
X1483232D01*
X1483417Y1040535D01*
Y1040360D01*
X1482017D01*
Y1040535D01*
G37*
G36*
G01D02*
X1482202Y1041135D01*
X1483232D01*
X1483417Y1040535D01*
Y1040360D01*
X1482017D01*
Y1040535D01*
G37*
G36*
G01X1487120Y1042145D02*
X1486935Y1041545D01*
X1485905D01*
X1485720Y1042145D01*
Y1042319D01*
X1487120D01*
Y1042145D01*
G37*
G36*
G01X1490820D02*
X1490635Y1041545D01*
X1489605D01*
X1489420Y1042145D01*
Y1042319D01*
X1490820D01*
Y1042145D01*
G37*
G36*
G01X1487120D02*
X1486935Y1041545D01*
X1485905D01*
X1485720Y1042145D01*
Y1042319D01*
X1487120D01*
Y1042145D01*
G37*
G36*
G01X1490820D02*
X1490635Y1041545D01*
X1489605D01*
X1489420Y1042145D01*
Y1042319D01*
X1490820D01*
Y1042145D01*
G37*
G36*
G01X1492640Y1038941D02*
X1492455Y1038341D01*
X1491425D01*
X1491240Y1038941D01*
Y1039115D01*
X1492640D01*
Y1038941D01*
G37*
G36*
G01X1488940D02*
X1488755Y1038341D01*
X1487725D01*
X1487540Y1038941D01*
Y1039115D01*
X1488940D01*
Y1038941D01*
G37*
G36*
G01X1492640D02*
X1492455Y1038341D01*
X1491425D01*
X1491240Y1038941D01*
Y1039115D01*
X1492640D01*
Y1038941D01*
G37*
G36*
G01X1488940D02*
X1488755Y1038341D01*
X1487725D01*
X1487540Y1038941D01*
Y1039115D01*
X1488940D01*
Y1038941D01*
G37*
G36*
G01X1487587Y1030923D02*
X1487772Y1031523D01*
X1488802D01*
X1488987Y1030923D01*
Y1030749D01*
X1487587D01*
Y1030923D01*
G37*
G36*
G01X1491287D02*
X1491472Y1031523D01*
X1492502D01*
X1492687Y1030923D01*
Y1030749D01*
X1491287D01*
Y1030923D01*
G37*
G36*
G01X1487587D02*
X1487772Y1031523D01*
X1488802D01*
X1488987Y1030923D01*
Y1030749D01*
X1487587D01*
Y1030923D01*
G37*
G36*
G01X1491287D02*
X1491472Y1031523D01*
X1492502D01*
X1492687Y1030923D01*
Y1030749D01*
X1491287D01*
Y1030923D01*
G37*
G36*
G01X1489417Y1046943D02*
X1489602Y1047543D01*
X1490632D01*
X1490817Y1046943D01*
Y1046769D01*
X1489417D01*
Y1046943D01*
G37*
G36*
G01X1485680D02*
X1485865Y1047543D01*
X1486895D01*
X1487080Y1046943D01*
Y1046769D01*
X1485680D01*
Y1046943D01*
G37*
G36*
G01X1489417D02*
X1489602Y1047543D01*
X1490632D01*
X1490817Y1046943D01*
Y1046769D01*
X1489417D01*
Y1046943D01*
G37*
G36*
G01X1485680D02*
X1485865Y1047543D01*
X1486895D01*
X1487080Y1046943D01*
Y1046769D01*
X1485680D01*
Y1046943D01*
G37*
G36*
G01X1485240Y1045349D02*
X1485055Y1044749D01*
X1484025D01*
X1483840Y1045349D01*
Y1045524D01*
X1485240D01*
Y1045349D01*
G37*
G36*
G01X1492640D02*
X1492455Y1044749D01*
X1491425D01*
X1491240Y1045349D01*
Y1045524D01*
X1492640D01*
Y1045349D01*
G37*
G36*
G01X1488940D02*
X1488755Y1044749D01*
X1487725D01*
X1487540Y1045349D01*
Y1045524D01*
X1488940D01*
Y1045349D01*
G37*
G36*
G01X1485240D02*
X1485055Y1044749D01*
X1484025D01*
X1483840Y1045349D01*
Y1045524D01*
X1485240D01*
Y1045349D01*
G37*
G36*
G01X1492640D02*
X1492455Y1044749D01*
X1491425D01*
X1491240Y1045349D01*
Y1045524D01*
X1492640D01*
Y1045349D01*
G37*
G36*
G01X1488940D02*
X1488755Y1044749D01*
X1487725D01*
X1487540Y1045349D01*
Y1045524D01*
X1488940D01*
Y1045349D01*
G37*
G36*
G01X1487103Y1035735D02*
X1486918Y1035135D01*
X1485888D01*
X1485703Y1035735D01*
Y1035910D01*
X1487103D01*
Y1035735D01*
G37*
G36*
G01X1490770D02*
X1490585Y1035135D01*
X1489555D01*
X1489370Y1035735D01*
Y1035909D01*
X1490770D01*
Y1035735D01*
G37*
G36*
G01X1487103D02*
X1486918Y1035135D01*
X1485888D01*
X1485703Y1035735D01*
Y1035910D01*
X1487103D01*
Y1035735D01*
G37*
G36*
G01X1490770D02*
X1490585Y1035135D01*
X1489555D01*
X1489370Y1035735D01*
Y1035909D01*
X1490770D01*
Y1035735D01*
G37*
G36*
G01X1489370Y1034127D02*
X1489555Y1034727D01*
X1490585D01*
X1490770Y1034127D01*
Y1033953D01*
X1489370D01*
Y1034127D01*
G37*
G36*
G01D02*
X1489555Y1034727D01*
X1490585D01*
X1490770Y1034127D01*
Y1033953D01*
X1489370D01*
Y1034127D01*
G37*
G36*
G01X1491287Y1037333D02*
X1491472Y1037933D01*
X1492502D01*
X1492687Y1037333D01*
Y1037158D01*
X1491287D01*
Y1037333D01*
G37*
G36*
G01X1487577D02*
X1487762Y1037933D01*
X1488792D01*
X1488977Y1037333D01*
Y1037158D01*
X1487577D01*
Y1037333D01*
G37*
G36*
G01X1491287D02*
X1491472Y1037933D01*
X1492502D01*
X1492687Y1037333D01*
Y1037158D01*
X1491287D01*
Y1037333D01*
G37*
G36*
G01X1487577D02*
X1487762Y1037933D01*
X1488792D01*
X1488977Y1037333D01*
Y1037158D01*
X1487577D01*
Y1037333D01*
G37*
G36*
G01X1488987Y1032531D02*
X1488802Y1031931D01*
X1487772D01*
X1487587Y1032531D01*
Y1032705D01*
X1488987D01*
Y1032531D01*
G37*
G36*
G01X1492687D02*
X1492502Y1031931D01*
X1491472D01*
X1491287Y1032531D01*
Y1032705D01*
X1492687D01*
Y1032531D01*
G37*
G36*
G01X1488987D02*
X1488802Y1031931D01*
X1487772D01*
X1487587Y1032531D01*
Y1032705D01*
X1488987D01*
Y1032531D01*
G37*
G36*
G01X1492687D02*
X1492502Y1031931D01*
X1491472D01*
X1491287Y1032531D01*
Y1032705D01*
X1492687D01*
Y1032531D01*
G37*
G36*
G01X1483887Y1062967D02*
X1484072Y1063567D01*
X1485102D01*
X1485287Y1062967D01*
Y1062792D01*
X1483887D01*
Y1062967D01*
G37*
G36*
G01X1491287D02*
X1491472Y1063567D01*
X1492502D01*
X1492687Y1062967D01*
Y1062792D01*
X1491287D01*
Y1062967D01*
G37*
G36*
G01X1487587D02*
X1487772Y1063567D01*
X1488802D01*
X1488987Y1062967D01*
Y1062792D01*
X1487587D01*
Y1062967D01*
G37*
G36*
G01X1483887D02*
X1484072Y1063567D01*
X1485102D01*
X1485287Y1062967D01*
Y1062792D01*
X1483887D01*
Y1062967D01*
G37*
G36*
G01X1491287D02*
X1491472Y1063567D01*
X1492502D01*
X1492687Y1062967D01*
Y1062792D01*
X1491287D01*
Y1062967D01*
G37*
G36*
G01X1487587D02*
X1487772Y1063567D01*
X1488802D01*
X1488987Y1062967D01*
Y1062792D01*
X1487587D01*
Y1062967D01*
G37*
G36*
G01X1480187D02*
X1480372Y1063567D01*
X1481402D01*
X1481587Y1062967D01*
Y1062792D01*
X1480187D01*
Y1062967D01*
G37*
G36*
G01D02*
X1480372Y1063567D01*
X1481402D01*
X1481587Y1062967D01*
Y1062792D01*
X1480187D01*
Y1062967D01*
G37*
G36*
G01X1485717Y1059761D02*
X1485902Y1060361D01*
X1486932D01*
X1487117Y1059761D01*
Y1059586D01*
X1485717D01*
Y1059761D01*
G37*
G36*
G01X1489417D02*
X1489602Y1060361D01*
X1490632D01*
X1490817Y1059761D01*
Y1059586D01*
X1489417D01*
Y1059761D01*
G37*
G36*
G01X1485717D02*
X1485902Y1060361D01*
X1486932D01*
X1487117Y1059761D01*
Y1059586D01*
X1485717D01*
Y1059761D01*
G37*
G36*
G01X1489417D02*
X1489602Y1060361D01*
X1490632D01*
X1490817Y1059761D01*
Y1059586D01*
X1489417D01*
Y1059761D01*
G37*
G36*
G01X1482028Y1059757D02*
X1482213Y1060357D01*
X1483243D01*
X1483428Y1059757D01*
Y1059583D01*
X1482028D01*
Y1059757D01*
G37*
G36*
G01D02*
X1482213Y1060357D01*
X1483243D01*
X1483428Y1059757D01*
Y1059583D01*
X1482028D01*
Y1059757D01*
G37*
G36*
G01X1490770Y1061369D02*
X1490585Y1060769D01*
X1489555D01*
X1489370Y1061369D01*
Y1061543D01*
X1490770D01*
Y1061369D01*
G37*
G36*
G01X1487070D02*
X1486885Y1060769D01*
X1485855D01*
X1485670Y1061369D01*
Y1061543D01*
X1487070D01*
Y1061369D01*
G37*
G36*
G01X1490770D02*
X1490585Y1060769D01*
X1489555D01*
X1489370Y1061369D01*
Y1061543D01*
X1490770D01*
Y1061369D01*
G37*
G36*
G01X1487070D02*
X1486885Y1060769D01*
X1485855D01*
X1485670Y1061369D01*
Y1061543D01*
X1487070D01*
Y1061369D01*
G37*
G36*
G01X1492687Y1058165D02*
X1492502Y1057565D01*
X1491472D01*
X1491287Y1058165D01*
Y1058339D01*
X1492687D01*
Y1058165D01*
G37*
G36*
G01X1488987D02*
X1488802Y1057565D01*
X1487772D01*
X1487587Y1058165D01*
Y1058339D01*
X1488987D01*
Y1058165D01*
G37*
G36*
G01X1492687D02*
X1492502Y1057565D01*
X1491472D01*
X1491287Y1058165D01*
Y1058339D01*
X1492687D01*
Y1058165D01*
G37*
G36*
G01X1488987D02*
X1488802Y1057565D01*
X1487772D01*
X1487587Y1058165D01*
Y1058339D01*
X1488987D01*
Y1058165D01*
G37*
G36*
G01X1491240Y1050149D02*
X1491425Y1050749D01*
X1492455D01*
X1492640Y1050149D01*
Y1049974D01*
X1491240D01*
Y1050149D01*
G37*
G36*
G01X1487540D02*
X1487725Y1050749D01*
X1488755D01*
X1488940Y1050149D01*
Y1049974D01*
X1487540D01*
Y1050149D01*
G37*
G36*
G01X1491240D02*
X1491425Y1050749D01*
X1492455D01*
X1492640Y1050149D01*
Y1049974D01*
X1491240D01*
Y1050149D01*
G37*
G36*
G01X1487540D02*
X1487725Y1050749D01*
X1488755D01*
X1488940Y1050149D01*
Y1049974D01*
X1487540D01*
Y1050149D01*
G37*
G36*
G01X1490817Y1048553D02*
X1490632Y1047953D01*
X1489602D01*
X1489417Y1048553D01*
Y1048727D01*
X1490817D01*
Y1048553D01*
G37*
G36*
G01X1487117D02*
X1486932Y1047953D01*
X1485902D01*
X1485717Y1048553D01*
Y1048727D01*
X1487117D01*
Y1048553D01*
G37*
G36*
G01X1490817D02*
X1490632Y1047953D01*
X1489602D01*
X1489417Y1048553D01*
Y1048727D01*
X1490817D01*
Y1048553D01*
G37*
G36*
G01X1487117D02*
X1486932Y1047953D01*
X1485902D01*
X1485717Y1048553D01*
Y1048727D01*
X1487117D01*
Y1048553D01*
G37*
G36*
G01X1490770Y1054961D02*
X1490585Y1054361D01*
X1489555D01*
X1489370Y1054961D01*
Y1055135D01*
X1490770D01*
Y1054961D01*
G37*
G36*
G01X1487070D02*
X1486885Y1054361D01*
X1485855D01*
X1485670Y1054961D01*
Y1055135D01*
X1487070D01*
Y1054961D01*
G37*
G36*
G01X1490770D02*
X1490585Y1054361D01*
X1489555D01*
X1489370Y1054961D01*
Y1055135D01*
X1490770D01*
Y1054961D01*
G37*
G36*
G01X1487070D02*
X1486885Y1054361D01*
X1485855D01*
X1485670Y1054961D01*
Y1055135D01*
X1487070D01*
Y1054961D01*
G37*
G36*
G01X1489370Y1053353D02*
X1489555Y1053953D01*
X1490585D01*
X1490770Y1053353D01*
Y1053179D01*
X1489370D01*
Y1053353D01*
G37*
G36*
G01D02*
X1489555Y1053953D01*
X1490585D01*
X1490770Y1053353D01*
Y1053179D01*
X1489370D01*
Y1053353D01*
G37*
G36*
G01X1483887Y1056557D02*
X1484072Y1057157D01*
X1485102D01*
X1485287Y1056557D01*
Y1056383D01*
X1483887D01*
Y1056557D01*
G37*
G36*
G01X1491287D02*
X1491472Y1057157D01*
X1492502D01*
X1492687Y1056557D01*
Y1056383D01*
X1491287D01*
Y1056557D01*
G37*
G36*
G01X1487587D02*
X1487772Y1057157D01*
X1488802D01*
X1488987Y1056557D01*
Y1056383D01*
X1487587D01*
Y1056557D01*
G37*
G36*
G01X1483887D02*
X1484072Y1057157D01*
X1485102D01*
X1485287Y1056557D01*
Y1056383D01*
X1483887D01*
Y1056557D01*
G37*
G36*
G01X1491287D02*
X1491472Y1057157D01*
X1492502D01*
X1492687Y1056557D01*
Y1056383D01*
X1491287D01*
Y1056557D01*
G37*
G36*
G01X1487587D02*
X1487772Y1057157D01*
X1488802D01*
X1488987Y1056557D01*
Y1056383D01*
X1487587D01*
Y1056557D01*
G37*
G36*
G01X1492687Y1051757D02*
X1492502Y1051157D01*
X1491472D01*
X1491287Y1051757D01*
Y1051931D01*
X1492687D01*
Y1051757D01*
G37*
G36*
G01X1488959Y1051759D02*
X1488774Y1051159D01*
X1487744D01*
X1487559Y1051759D01*
Y1051933D01*
X1488959D01*
Y1051759D01*
G37*
G36*
G01X1492687Y1051757D02*
X1492502Y1051157D01*
X1491472D01*
X1491287Y1051757D01*
Y1051931D01*
X1492687D01*
Y1051757D01*
G37*
G36*
G01X1488959Y1051759D02*
X1488774Y1051159D01*
X1487744D01*
X1487559Y1051759D01*
Y1051933D01*
X1488959D01*
Y1051759D01*
G37*
G36*
G01X1488940Y1077391D02*
X1488755Y1076791D01*
X1487725D01*
X1487540Y1077391D01*
Y1077566D01*
X1488940D01*
Y1077391D01*
G37*
G36*
G01X1492687D02*
X1492502Y1076791D01*
X1491472D01*
X1491287Y1077391D01*
Y1077565D01*
X1492687D01*
Y1077391D01*
G37*
G36*
G01X1488940D02*
X1488755Y1076791D01*
X1487725D01*
X1487540Y1077391D01*
Y1077566D01*
X1488940D01*
Y1077391D01*
G37*
G36*
G01X1492687D02*
X1492502Y1076791D01*
X1491472D01*
X1491287Y1077391D01*
Y1077565D01*
X1492687D01*
Y1077391D01*
G37*
G36*
G01X1491240Y1069375D02*
X1491425Y1069975D01*
X1492455D01*
X1492640Y1069375D01*
Y1069200D01*
X1491240D01*
Y1069375D01*
G37*
G36*
G01X1487540D02*
X1487725Y1069975D01*
X1488755D01*
X1488940Y1069375D01*
Y1069200D01*
X1487540D01*
Y1069375D01*
G37*
G36*
G01X1491240D02*
X1491425Y1069975D01*
X1492455D01*
X1492640Y1069375D01*
Y1069200D01*
X1491240D01*
Y1069375D01*
G37*
G36*
G01X1487540D02*
X1487725Y1069975D01*
X1488755D01*
X1488940Y1069375D01*
Y1069200D01*
X1487540D01*
Y1069375D01*
G37*
G36*
G01X1485670Y1066171D02*
X1485855Y1066771D01*
X1486885D01*
X1487070Y1066171D01*
Y1065996D01*
X1485670D01*
Y1066171D01*
G37*
G36*
G01X1489370D02*
X1489555Y1066771D01*
X1490585D01*
X1490770Y1066171D01*
Y1065996D01*
X1489370D01*
Y1066171D01*
G37*
G36*
G01X1485670D02*
X1485855Y1066771D01*
X1486885D01*
X1487070Y1066171D01*
Y1065996D01*
X1485670D01*
Y1066171D01*
G37*
G36*
G01X1489370D02*
X1489555Y1066771D01*
X1490585D01*
X1490770Y1066171D01*
Y1065996D01*
X1489370D01*
Y1066171D01*
G37*
G36*
G01X1482567Y1068806D02*
X1483179Y1068946D01*
X1483694Y1068054D01*
X1483267Y1067594D01*
X1483116Y1067507D01*
X1482416Y1068719D01*
X1482567Y1068806D01*
G37*
G36*
G01D02*
X1483179Y1068946D01*
X1483694Y1068054D01*
X1483267Y1067594D01*
X1483116Y1067507D01*
X1482416Y1068719D01*
X1482567Y1068806D01*
G37*
G36*
G01X1487117Y1067779D02*
X1486932Y1067179D01*
X1485902D01*
X1485717Y1067779D01*
Y1067953D01*
X1487117D01*
Y1067779D01*
G37*
G36*
G01X1490817D02*
X1490632Y1067179D01*
X1489602D01*
X1489417Y1067779D01*
Y1067953D01*
X1490817D01*
Y1067779D01*
G37*
G36*
G01X1487117D02*
X1486932Y1067179D01*
X1485902D01*
X1485717Y1067779D01*
Y1067953D01*
X1487117D01*
Y1067779D01*
G37*
G36*
G01X1490817D02*
X1490632Y1067179D01*
X1489602D01*
X1489417Y1067779D01*
Y1067953D01*
X1490817D01*
Y1067779D01*
G37*
G36*
G01X1485287Y1064573D02*
X1485102Y1063973D01*
X1484072D01*
X1483887Y1064573D01*
Y1064748D01*
X1485287D01*
Y1064573D01*
G37*
G36*
G01X1492687D02*
X1492502Y1063973D01*
X1491472D01*
X1491287Y1064573D01*
Y1064748D01*
X1492687D01*
Y1064573D01*
G37*
G36*
G01X1488987D02*
X1488802Y1063973D01*
X1487772D01*
X1487587Y1064573D01*
Y1064748D01*
X1488987D01*
Y1064573D01*
G37*
G36*
G01X1485287D02*
X1485102Y1063973D01*
X1484072D01*
X1483887Y1064573D01*
Y1064748D01*
X1485287D01*
Y1064573D01*
G37*
G36*
G01X1492687D02*
X1492502Y1063973D01*
X1491472D01*
X1491287Y1064573D01*
Y1064748D01*
X1492687D01*
Y1064573D01*
G37*
G36*
G01X1488987D02*
X1488802Y1063973D01*
X1487772D01*
X1487587Y1064573D01*
Y1064748D01*
X1488987D01*
Y1064573D01*
G37*
G36*
G01X1482818Y1065180D02*
X1482206Y1065040D01*
X1481691Y1065932D01*
X1482118Y1066392D01*
X1482269Y1066479D01*
X1482969Y1065267D01*
X1482818Y1065180D01*
G37*
G36*
G01D02*
X1482206Y1065040D01*
X1481691Y1065932D01*
X1482118Y1066392D01*
X1482269Y1066479D01*
X1482969Y1065267D01*
X1482818Y1065180D01*
G37*
G36*
G01X1489417Y1078987D02*
X1489602Y1079587D01*
X1490632D01*
X1490817Y1078987D01*
Y1078812D01*
X1489417D01*
Y1078987D01*
G37*
G36*
G01X1485717D02*
X1485902Y1079587D01*
X1486932D01*
X1487117Y1078987D01*
Y1078812D01*
X1485717D01*
Y1078987D01*
G37*
G36*
G01X1489417D02*
X1489602Y1079587D01*
X1490632D01*
X1490817Y1078987D01*
Y1078812D01*
X1489417D01*
Y1078987D01*
G37*
G36*
G01X1485717D02*
X1485902Y1079587D01*
X1486932D01*
X1487117Y1078987D01*
Y1078812D01*
X1485717D01*
Y1078987D01*
G37*
G36*
G01X1490770Y1074187D02*
X1490585Y1073587D01*
X1489555D01*
X1489370Y1074187D01*
Y1074361D01*
X1490770D01*
Y1074187D01*
G37*
G36*
G01X1487070D02*
X1486885Y1073587D01*
X1485855D01*
X1485670Y1074187D01*
Y1074361D01*
X1487070D01*
Y1074187D01*
G37*
G36*
G01X1490770D02*
X1490585Y1073587D01*
X1489555D01*
X1489370Y1074187D01*
Y1074361D01*
X1490770D01*
Y1074187D01*
G37*
G36*
G01X1487070D02*
X1486885Y1073587D01*
X1485855D01*
X1485670Y1074187D01*
Y1074361D01*
X1487070D01*
Y1074187D01*
G37*
G36*
G01X1489370Y1072579D02*
X1489555Y1073179D01*
X1490585D01*
X1490770Y1072579D01*
Y1072405D01*
X1489370D01*
Y1072579D01*
G37*
G36*
G01D02*
X1489555Y1073179D01*
X1490585D01*
X1490770Y1072579D01*
Y1072405D01*
X1489370D01*
Y1072579D01*
G37*
G36*
G01X1491287Y1075783D02*
X1491472Y1076383D01*
X1492502D01*
X1492687Y1075783D01*
Y1075609D01*
X1491287D01*
Y1075783D01*
G37*
G36*
G01X1487587D02*
X1487772Y1076383D01*
X1488802D01*
X1488987Y1075783D01*
Y1075609D01*
X1487587D01*
Y1075783D01*
G37*
G36*
G01X1491287D02*
X1491472Y1076383D01*
X1492502D01*
X1492687Y1075783D01*
Y1075609D01*
X1491287D01*
Y1075783D01*
G37*
G36*
G01X1487587D02*
X1487772Y1076383D01*
X1488802D01*
X1488987Y1075783D01*
Y1075609D01*
X1487587D01*
Y1075783D01*
G37*
G36*
G01X1492687Y1070981D02*
X1492502Y1070381D01*
X1491472D01*
X1491287Y1070981D01*
Y1071156D01*
X1492687D01*
Y1070981D01*
G37*
G36*
G01X1488953Y1070985D02*
X1488768Y1070385D01*
X1487738D01*
X1487553Y1070985D01*
Y1071160D01*
X1488953D01*
Y1070985D01*
G37*
G36*
G01X1492687Y1070981D02*
X1492502Y1070381D01*
X1491472D01*
X1491287Y1070981D01*
Y1071156D01*
X1492687D01*
Y1070981D01*
G37*
G36*
G01X1488953Y1070985D02*
X1488768Y1070385D01*
X1487738D01*
X1487553Y1070985D01*
Y1071160D01*
X1488953D01*
Y1070985D01*
G37*
G36*
G01X1487070Y1080595D02*
X1486885Y1079995D01*
X1485855D01*
X1485670Y1080595D01*
Y1080769D01*
X1487070D01*
Y1080595D01*
G37*
G36*
G01X1490770D02*
X1490585Y1079995D01*
X1489555D01*
X1489370Y1080595D01*
Y1080769D01*
X1490770D01*
Y1080595D01*
G37*
G36*
G01X1487070D02*
X1486885Y1079995D01*
X1485855D01*
X1485670Y1080595D01*
Y1080769D01*
X1487070D01*
Y1080595D01*
G37*
G36*
G01X1490770D02*
X1490585Y1079995D01*
X1489555D01*
X1489370Y1080595D01*
Y1080769D01*
X1490770D01*
Y1080595D01*
G37*
G36*
G01X1483370D02*
X1483185Y1079995D01*
X1482155D01*
X1481970Y1080595D01*
Y1080769D01*
X1483370D01*
Y1080595D01*
G37*
G36*
G01D02*
X1483185Y1079995D01*
X1482155D01*
X1481970Y1080595D01*
Y1080769D01*
X1483370D01*
Y1080595D01*
G37*
G36*
G01X1483887Y1082191D02*
X1484072Y1082791D01*
X1485102D01*
X1485287Y1082191D01*
Y1082017D01*
X1483887D01*
Y1082191D01*
G37*
G36*
G01X1487587D02*
X1487772Y1082791D01*
X1488802D01*
X1488987Y1082191D01*
Y1082017D01*
X1487587D01*
Y1082191D01*
G37*
G36*
G01X1491287D02*
X1491472Y1082791D01*
X1492502D01*
X1492687Y1082191D01*
Y1082017D01*
X1491287D01*
Y1082191D01*
G37*
G36*
G01X1483887D02*
X1484072Y1082791D01*
X1485102D01*
X1485287Y1082191D01*
Y1082017D01*
X1483887D01*
Y1082191D01*
G37*
G36*
G01X1487587D02*
X1487772Y1082791D01*
X1488802D01*
X1488987Y1082191D01*
Y1082017D01*
X1487587D01*
Y1082191D01*
G37*
G36*
G01X1491287D02*
X1491472Y1082791D01*
X1492502D01*
X1492687Y1082191D01*
Y1082017D01*
X1491287D01*
Y1082191D01*
G37*
G36*
G01X1480187D02*
X1480372Y1082791D01*
X1481402D01*
X1481587Y1082191D01*
Y1082017D01*
X1480187D01*
Y1082191D01*
G37*
G36*
G01D02*
X1480372Y1082791D01*
X1481402D01*
X1481587Y1082191D01*
Y1082017D01*
X1480187D01*
Y1082191D01*
G37*
G36*
G01X1487587Y1088600D02*
X1487772Y1089200D01*
X1488802D01*
X1488987Y1088600D01*
Y1088426D01*
X1487587D01*
Y1088600D01*
G37*
G36*
G01X1491287D02*
X1491472Y1089200D01*
X1492502D01*
X1492687Y1088600D01*
Y1088426D01*
X1491287D01*
Y1088600D01*
G37*
G36*
G01X1487587D02*
X1487772Y1089200D01*
X1488802D01*
X1488987Y1088600D01*
Y1088426D01*
X1487587D01*
Y1088600D01*
G37*
G36*
G01X1491287D02*
X1491472Y1089200D01*
X1492502D01*
X1492687Y1088600D01*
Y1088426D01*
X1491287D01*
Y1088600D01*
G37*
G36*
G01X1485680Y1085396D02*
X1485865Y1085996D01*
X1486895D01*
X1487080Y1085396D01*
Y1085221D01*
X1485680D01*
Y1085396D01*
G37*
G36*
G01X1489370D02*
X1489555Y1085996D01*
X1490585D01*
X1490770Y1085396D01*
Y1085222D01*
X1489370D01*
Y1085396D01*
G37*
G36*
G01X1485680D02*
X1485865Y1085996D01*
X1486895D01*
X1487080Y1085396D01*
Y1085221D01*
X1485680D01*
Y1085396D01*
G37*
G36*
G01X1489370D02*
X1489555Y1085996D01*
X1490585D01*
X1490770Y1085396D01*
Y1085222D01*
X1489370D01*
Y1085396D01*
G37*
G36*
G01X1487080Y1087005D02*
X1486895Y1086405D01*
X1485865D01*
X1485680Y1087005D01*
Y1087179D01*
X1487080D01*
Y1087005D01*
G37*
G36*
G01X1490770Y1087003D02*
X1490585Y1086403D01*
X1489555D01*
X1489370Y1087003D01*
Y1087178D01*
X1490770D01*
Y1087003D01*
G37*
G36*
G01X1487080Y1087005D02*
X1486895Y1086405D01*
X1485865D01*
X1485680Y1087005D01*
Y1087179D01*
X1487080D01*
Y1087005D01*
G37*
G36*
G01X1490770Y1087003D02*
X1490585Y1086403D01*
X1489555D01*
X1489370Y1087003D01*
Y1087178D01*
X1490770D01*
Y1087003D01*
G37*
G36*
G01X1485254Y1083799D02*
X1485069Y1083199D01*
X1484039D01*
X1483854Y1083799D01*
Y1083974D01*
X1485254D01*
Y1083799D01*
G37*
G36*
G01X1488987D02*
X1488802Y1083199D01*
X1487772D01*
X1487587Y1083799D01*
Y1083973D01*
X1488987D01*
Y1083799D01*
G37*
G36*
G01X1492687D02*
X1492502Y1083199D01*
X1491472D01*
X1491287Y1083799D01*
Y1083973D01*
X1492687D01*
Y1083799D01*
G37*
G36*
G01X1485254D02*
X1485069Y1083199D01*
X1484039D01*
X1483854Y1083799D01*
Y1083974D01*
X1485254D01*
Y1083799D01*
G37*
G36*
G01X1488987D02*
X1488802Y1083199D01*
X1487772D01*
X1487587Y1083799D01*
Y1083973D01*
X1488987D01*
Y1083799D01*
G37*
G36*
G01X1492687D02*
X1492502Y1083199D01*
X1491472D01*
X1491287Y1083799D01*
Y1083973D01*
X1492687D01*
Y1083799D01*
G37*
G36*
G01X1490837Y1093411D02*
X1490652Y1092811D01*
X1489622D01*
X1489437Y1093411D01*
Y1093586D01*
X1490837D01*
Y1093411D01*
G37*
G36*
G01X1487080D02*
X1486895Y1092811D01*
X1485865D01*
X1485680Y1093411D01*
Y1093586D01*
X1487080D01*
Y1093411D01*
G37*
G36*
G01X1490837D02*
X1490652Y1092811D01*
X1489622D01*
X1489437Y1093411D01*
Y1093586D01*
X1490837D01*
Y1093411D01*
G37*
G36*
G01X1487080D02*
X1486895Y1092811D01*
X1485865D01*
X1485680Y1093411D01*
Y1093586D01*
X1487080D01*
Y1093411D01*
G37*
G36*
G01X1489405Y1091804D02*
X1489590Y1092404D01*
X1490620D01*
X1490805Y1091804D01*
Y1091630D01*
X1489405D01*
Y1091804D01*
G37*
G36*
G01D02*
X1489590Y1092404D01*
X1490620D01*
X1490805Y1091804D01*
Y1091630D01*
X1489405D01*
Y1091804D01*
G37*
G36*
G01X1491230Y1095009D02*
X1491415Y1095609D01*
X1492445D01*
X1492630Y1095009D01*
Y1094835D01*
X1491230D01*
Y1095009D01*
G37*
G36*
G01D02*
X1491415Y1095609D01*
X1492445D01*
X1492630Y1095009D01*
Y1094835D01*
X1491230D01*
Y1095009D01*
G37*
G36*
G01X1492654Y1090209D02*
X1492469Y1089609D01*
X1491439D01*
X1491254Y1090209D01*
Y1090383D01*
X1492654D01*
Y1090209D01*
G37*
G36*
G01D02*
X1492469Y1089609D01*
X1491439D01*
X1491254Y1090209D01*
Y1090383D01*
X1492654D01*
Y1090209D01*
G37*
G36*
G01X1492677Y1096617D02*
X1492492Y1096017D01*
X1491462D01*
X1491277Y1096617D01*
Y1096791D01*
X1492677D01*
Y1096617D01*
G37*
G36*
G01D02*
X1492492Y1096017D01*
X1491462D01*
X1491277Y1096617D01*
Y1096791D01*
X1492677D01*
Y1096617D01*
G37*
G36*
G01X1500071Y898641D02*
X1500256Y899241D01*
X1501286D01*
X1501471Y898641D01*
Y898466D01*
X1500071D01*
Y898641D01*
G37*
G36*
G01X1496347D02*
X1496532Y899241D01*
X1497562D01*
X1497747Y898641D01*
Y898467D01*
X1496347D01*
Y898641D01*
G37*
G36*
G01X1507447D02*
X1507632Y899241D01*
X1508662D01*
X1508847Y898641D01*
Y898467D01*
X1507447D01*
Y898641D01*
G37*
G36*
G01X1503747D02*
X1503932Y899241D01*
X1504962D01*
X1505147Y898641D01*
Y898466D01*
X1503747D01*
Y898641D01*
G37*
G36*
G01X1500071D02*
X1500256Y899241D01*
X1501286D01*
X1501471Y898641D01*
Y898466D01*
X1500071D01*
Y898641D01*
G37*
G36*
G01X1496347D02*
X1496532Y899241D01*
X1497562D01*
X1497747Y898641D01*
Y898467D01*
X1496347D01*
Y898641D01*
G37*
G36*
G01X1507447D02*
X1507632Y899241D01*
X1508662D01*
X1508847Y898641D01*
Y898467D01*
X1507447D01*
Y898641D01*
G37*
G36*
G01X1503747D02*
X1503932Y899241D01*
X1504962D01*
X1505147Y898641D01*
Y898466D01*
X1503747D01*
Y898641D01*
G37*
G36*
G01X1498254Y895437D02*
X1498439Y896037D01*
X1499469D01*
X1499654Y895437D01*
Y895262D01*
X1498254D01*
Y895437D01*
G37*
G36*
G01X1494554D02*
X1494739Y896037D01*
X1495769D01*
X1495954Y895437D01*
Y895262D01*
X1494554D01*
Y895437D01*
G37*
G36*
G01X1501921Y895435D02*
X1502106Y896035D01*
X1503136D01*
X1503321Y895435D01*
Y895261D01*
X1501921D01*
Y895435D01*
G37*
G36*
G01X1505654Y895437D02*
X1505839Y896037D01*
X1506869D01*
X1507054Y895437D01*
Y895262D01*
X1505654D01*
Y895437D01*
G37*
G36*
G01X1498254D02*
X1498439Y896037D01*
X1499469D01*
X1499654Y895437D01*
Y895262D01*
X1498254D01*
Y895437D01*
G37*
G36*
G01X1494554D02*
X1494739Y896037D01*
X1495769D01*
X1495954Y895437D01*
Y895262D01*
X1494554D01*
Y895437D01*
G37*
G36*
G01X1501921Y895435D02*
X1502106Y896035D01*
X1503136D01*
X1503321Y895435D01*
Y895261D01*
X1501921D01*
Y895435D01*
G37*
G36*
G01X1505654Y895437D02*
X1505839Y896037D01*
X1506869D01*
X1507054Y895437D01*
Y895262D01*
X1505654D01*
Y895437D01*
G37*
G36*
G01X1499621Y897045D02*
X1499436Y896445D01*
X1498406D01*
X1498221Y897045D01*
Y897219D01*
X1499621D01*
Y897045D01*
G37*
G36*
G01X1495954Y897043D02*
X1495769Y896443D01*
X1494739D01*
X1494554Y897043D01*
Y897218D01*
X1495954D01*
Y897043D01*
G37*
G36*
G01X1507054D02*
X1506869Y896443D01*
X1505839D01*
X1505654Y897043D01*
Y897218D01*
X1507054D01*
Y897043D01*
G37*
G36*
G01X1503321Y897045D02*
X1503136Y896445D01*
X1502106D01*
X1501921Y897045D01*
Y897219D01*
X1503321D01*
Y897045D01*
G37*
G36*
G01X1499621D02*
X1499436Y896445D01*
X1498406D01*
X1498221Y897045D01*
Y897219D01*
X1499621D01*
Y897045D01*
G37*
G36*
G01X1495954Y897043D02*
X1495769Y896443D01*
X1494739D01*
X1494554Y897043D01*
Y897218D01*
X1495954D01*
Y897043D01*
G37*
G36*
G01X1507054D02*
X1506869Y896443D01*
X1505839D01*
X1505654Y897043D01*
Y897218D01*
X1507054D01*
Y897043D01*
G37*
G36*
G01X1503321Y897045D02*
X1503136Y896445D01*
X1502106D01*
X1501921Y897045D01*
Y897219D01*
X1503321D01*
Y897045D01*
G37*
G36*
G01X1497737Y893839D02*
X1497552Y893239D01*
X1496522D01*
X1496337Y893839D01*
Y894014D01*
X1497737D01*
Y893839D01*
G37*
G36*
G01X1501447D02*
X1501262Y893239D01*
X1500232D01*
X1500047Y893839D01*
Y894014D01*
X1501447D01*
Y893839D01*
G37*
G36*
G01X1505147Y893841D02*
X1504962Y893241D01*
X1503932D01*
X1503747Y893841D01*
Y894015D01*
X1505147D01*
Y893841D01*
G37*
G36*
G01X1508847Y893839D02*
X1508662Y893239D01*
X1507632D01*
X1507447Y893839D01*
Y894014D01*
X1508847D01*
Y893839D01*
G37*
G36*
G01X1497737D02*
X1497552Y893239D01*
X1496522D01*
X1496337Y893839D01*
Y894014D01*
X1497737D01*
Y893839D01*
G37*
G36*
G01X1501447D02*
X1501262Y893239D01*
X1500232D01*
X1500047Y893839D01*
Y894014D01*
X1501447D01*
Y893839D01*
G37*
G36*
G01X1505147Y893841D02*
X1504962Y893241D01*
X1503932D01*
X1503747Y893841D01*
Y894015D01*
X1505147D01*
Y893841D01*
G37*
G36*
G01X1508847Y893839D02*
X1508662Y893239D01*
X1507632D01*
X1507447Y893839D01*
Y894014D01*
X1508847D01*
Y893839D01*
G37*
G36*
G01X1501471Y900249D02*
X1501286Y899649D01*
X1500256D01*
X1500071Y900249D01*
Y900424D01*
X1501471D01*
Y900249D01*
G37*
G36*
G01X1497747D02*
X1497562Y899649D01*
X1496532D01*
X1496347Y900249D01*
Y900423D01*
X1497747D01*
Y900249D01*
G37*
G36*
G01X1505147D02*
X1504962Y899649D01*
X1503932D01*
X1503747Y900249D01*
Y900424D01*
X1505147D01*
Y900249D01*
G37*
G36*
G01X1508847D02*
X1508662Y899649D01*
X1507632D01*
X1507447Y900249D01*
Y900423D01*
X1508847D01*
Y900249D01*
G37*
G36*
G01X1501471D02*
X1501286Y899649D01*
X1500256D01*
X1500071Y900249D01*
Y900424D01*
X1501471D01*
Y900249D01*
G37*
G36*
G01X1497747D02*
X1497562Y899649D01*
X1496532D01*
X1496347Y900249D01*
Y900423D01*
X1497747D01*
Y900249D01*
G37*
G36*
G01X1505147D02*
X1504962Y899649D01*
X1503932D01*
X1503747Y900249D01*
Y900424D01*
X1505147D01*
Y900249D01*
G37*
G36*
G01X1508847D02*
X1508662Y899649D01*
X1507632D01*
X1507447Y900249D01*
Y900423D01*
X1508847D01*
Y900249D01*
G37*
G36*
G01X1495954Y916269D02*
X1495769Y915669D01*
X1494739D01*
X1494554Y916269D01*
Y916444D01*
X1495954D01*
Y916269D01*
G37*
G36*
G01X1499597Y916271D02*
X1499412Y915671D01*
X1498382D01*
X1498197Y916271D01*
Y916445D01*
X1499597D01*
Y916271D01*
G37*
G36*
G01X1503297Y916269D02*
X1503112Y915669D01*
X1502082D01*
X1501897Y916269D01*
Y916444D01*
X1503297D01*
Y916269D01*
G37*
G36*
G01X1507021Y916271D02*
X1506836Y915671D01*
X1505806D01*
X1505621Y916271D01*
Y916445D01*
X1507021D01*
Y916271D01*
G37*
G36*
G01X1495954Y916269D02*
X1495769Y915669D01*
X1494739D01*
X1494554Y916269D01*
Y916444D01*
X1495954D01*
Y916269D01*
G37*
G36*
G01X1499597Y916271D02*
X1499412Y915671D01*
X1498382D01*
X1498197Y916271D01*
Y916445D01*
X1499597D01*
Y916271D01*
G37*
G36*
G01X1503297Y916269D02*
X1503112Y915669D01*
X1502082D01*
X1501897Y916269D01*
Y916444D01*
X1503297D01*
Y916269D01*
G37*
G36*
G01X1507021Y916271D02*
X1506836Y915671D01*
X1505806D01*
X1505621Y916271D01*
Y916445D01*
X1507021D01*
Y916271D01*
G37*
G36*
G01X1496370Y911457D02*
X1496555Y912057D01*
X1497585D01*
X1497770Y911457D01*
Y911283D01*
X1496370D01*
Y911457D01*
G37*
G36*
G01X1500047Y911459D02*
X1500232Y912059D01*
X1501262D01*
X1501447Y911459D01*
Y911284D01*
X1500047D01*
Y911459D01*
G37*
G36*
G01X1493234Y914094D02*
X1493846Y914234D01*
X1494361Y913342D01*
X1493934Y912882D01*
X1493783Y912795D01*
X1493083Y914007D01*
X1493234Y914094D01*
G37*
G36*
G01X1503771Y911457D02*
X1503956Y912057D01*
X1504986D01*
X1505171Y911457D01*
Y911283D01*
X1503771D01*
Y911457D01*
G37*
G36*
G01X1507471D02*
X1507656Y912057D01*
X1508686D01*
X1508871Y911457D01*
Y911283D01*
X1507471D01*
Y911457D01*
G37*
G36*
G01X1496370D02*
X1496555Y912057D01*
X1497585D01*
X1497770Y911457D01*
Y911283D01*
X1496370D01*
Y911457D01*
G37*
G36*
G01X1500047Y911459D02*
X1500232Y912059D01*
X1501262D01*
X1501447Y911459D01*
Y911284D01*
X1500047D01*
Y911459D01*
G37*
G36*
G01X1493234Y914094D02*
X1493846Y914234D01*
X1494361Y913342D01*
X1493934Y912882D01*
X1493783Y912795D01*
X1493083Y914007D01*
X1493234Y914094D01*
G37*
G36*
G01X1503771Y911457D02*
X1503956Y912057D01*
X1504986D01*
X1505171Y911457D01*
Y911283D01*
X1503771D01*
Y911457D01*
G37*
G36*
G01X1507471D02*
X1507656Y912057D01*
X1508686D01*
X1508871Y911457D01*
Y911283D01*
X1507471D01*
Y911457D01*
G37*
G36*
G01X1494497Y908253D02*
X1494682Y908853D01*
X1495712D01*
X1495897Y908253D01*
Y908078D01*
X1494497D01*
Y908253D01*
G37*
G36*
G01X1498244D02*
X1498429Y908853D01*
X1499459D01*
X1499644Y908253D01*
Y908079D01*
X1498244D01*
Y908253D01*
G37*
G36*
G01X1501921D02*
X1502106Y908853D01*
X1503136D01*
X1503321Y908253D01*
Y908078D01*
X1501921D01*
Y908253D01*
G37*
G36*
G01X1505621D02*
X1505806Y908853D01*
X1506836D01*
X1507021Y908253D01*
Y908078D01*
X1505621D01*
Y908253D01*
G37*
G36*
G01X1494497D02*
X1494682Y908853D01*
X1495712D01*
X1495897Y908253D01*
Y908078D01*
X1494497D01*
Y908253D01*
G37*
G36*
G01X1498244D02*
X1498429Y908853D01*
X1499459D01*
X1499644Y908253D01*
Y908079D01*
X1498244D01*
Y908253D01*
G37*
G36*
G01X1501921D02*
X1502106Y908853D01*
X1503136D01*
X1503321Y908253D01*
Y908078D01*
X1501921D01*
Y908253D01*
G37*
G36*
G01X1505621D02*
X1505806Y908853D01*
X1506836D01*
X1507021Y908253D01*
Y908078D01*
X1505621D01*
Y908253D01*
G37*
G36*
G01X1499644Y909861D02*
X1499459Y909261D01*
X1498429D01*
X1498244Y909861D01*
Y910035D01*
X1499644D01*
Y909861D01*
G37*
G36*
G01X1495944D02*
X1495759Y909261D01*
X1494729D01*
X1494544Y909861D01*
Y910036D01*
X1495944D01*
Y909861D01*
G37*
G36*
G01X1503321D02*
X1503136Y909261D01*
X1502106D01*
X1501921Y909861D01*
Y910036D01*
X1503321D01*
Y909861D01*
G37*
G36*
G01X1507021D02*
X1506836Y909261D01*
X1505806D01*
X1505621Y909861D01*
Y910036D01*
X1507021D01*
Y909861D01*
G37*
G36*
G01X1499644D02*
X1499459Y909261D01*
X1498429D01*
X1498244Y909861D01*
Y910035D01*
X1499644D01*
Y909861D01*
G37*
G36*
G01X1495944D02*
X1495759Y909261D01*
X1494729D01*
X1494544Y909861D01*
Y910036D01*
X1495944D01*
Y909861D01*
G37*
G36*
G01X1503321D02*
X1503136Y909261D01*
X1502106D01*
X1501921Y909861D01*
Y910036D01*
X1503321D01*
Y909861D01*
G37*
G36*
G01X1507021D02*
X1506836Y909261D01*
X1505806D01*
X1505621Y909861D01*
Y910036D01*
X1507021D01*
Y909861D01*
G37*
G36*
G01X1501447Y906657D02*
X1501262Y906057D01*
X1500232D01*
X1500047Y906657D01*
Y906831D01*
X1501447D01*
Y906657D01*
G37*
G36*
G01X1497794D02*
X1497609Y906057D01*
X1496579D01*
X1496394Y906657D01*
Y906832D01*
X1497794D01*
Y906657D01*
G37*
G36*
G01X1508871D02*
X1508686Y906057D01*
X1507656D01*
X1507471Y906657D01*
Y906832D01*
X1508871D01*
Y906657D01*
G37*
G36*
G01X1505171D02*
X1504986Y906057D01*
X1503956D01*
X1503771Y906657D01*
Y906832D01*
X1505171D01*
Y906657D01*
G37*
G36*
G01X1501447D02*
X1501262Y906057D01*
X1500232D01*
X1500047Y906657D01*
Y906831D01*
X1501447D01*
Y906657D01*
G37*
G36*
G01X1497794D02*
X1497609Y906057D01*
X1496579D01*
X1496394Y906657D01*
Y906832D01*
X1497794D01*
Y906657D01*
G37*
G36*
G01X1508871D02*
X1508686Y906057D01*
X1507656D01*
X1507471Y906657D01*
Y906832D01*
X1508871D01*
Y906657D01*
G37*
G36*
G01X1505171D02*
X1504986Y906057D01*
X1503956D01*
X1503771Y906657D01*
Y906832D01*
X1505171D01*
Y906657D01*
G37*
G36*
G01X1499654Y903453D02*
X1499469Y902853D01*
X1498439D01*
X1498254Y903453D01*
Y903627D01*
X1499654D01*
Y903453D01*
G37*
G36*
G01X1495921D02*
X1495736Y902853D01*
X1494706D01*
X1494521Y903453D01*
Y903628D01*
X1495921D01*
Y903453D01*
G37*
G36*
G01X1507021D02*
X1506836Y902853D01*
X1505806D01*
X1505621Y903453D01*
Y903628D01*
X1507021D01*
Y903453D01*
G37*
G36*
G01X1503321D02*
X1503136Y902853D01*
X1502106D01*
X1501921Y903453D01*
Y903628D01*
X1503321D01*
Y903453D01*
G37*
G36*
G01X1499654D02*
X1499469Y902853D01*
X1498439D01*
X1498254Y903453D01*
Y903627D01*
X1499654D01*
Y903453D01*
G37*
G36*
G01X1495921D02*
X1495736Y902853D01*
X1494706D01*
X1494521Y903453D01*
Y903628D01*
X1495921D01*
Y903453D01*
G37*
G36*
G01X1507021D02*
X1506836Y902853D01*
X1505806D01*
X1505621Y903453D01*
Y903628D01*
X1507021D01*
Y903453D01*
G37*
G36*
G01X1503321D02*
X1503136Y902853D01*
X1502106D01*
X1501921Y903453D01*
Y903628D01*
X1503321D01*
Y903453D01*
G37*
G36*
G01X1498221Y901845D02*
X1498406Y902445D01*
X1499436D01*
X1499621Y901845D01*
Y901670D01*
X1498221D01*
Y901845D01*
G37*
G36*
G01X1494554D02*
X1494739Y902445D01*
X1495769D01*
X1495954Y901845D01*
Y901671D01*
X1494554D01*
Y901845D01*
G37*
G36*
G01X1505654D02*
X1505839Y902445D01*
X1506869D01*
X1507054Y901845D01*
Y901671D01*
X1505654D01*
Y901845D01*
G37*
G36*
G01X1501921D02*
X1502106Y902445D01*
X1503136D01*
X1503321Y901845D01*
Y901670D01*
X1501921D01*
Y901845D01*
G37*
G36*
G01X1498221D02*
X1498406Y902445D01*
X1499436D01*
X1499621Y901845D01*
Y901670D01*
X1498221D01*
Y901845D01*
G37*
G36*
G01X1494554D02*
X1494739Y902445D01*
X1495769D01*
X1495954Y901845D01*
Y901671D01*
X1494554D01*
Y901845D01*
G37*
G36*
G01X1505654D02*
X1505839Y902445D01*
X1506869D01*
X1507054Y901845D01*
Y901671D01*
X1505654D01*
Y901845D01*
G37*
G36*
G01X1501921D02*
X1502106Y902445D01*
X1503136D01*
X1503321Y901845D01*
Y901670D01*
X1501921D01*
Y901845D01*
G37*
G36*
G01X1500047Y905049D02*
X1500232Y905649D01*
X1501262D01*
X1501447Y905049D01*
Y904875D01*
X1500047D01*
Y905049D01*
G37*
G36*
G01X1496347D02*
X1496532Y905649D01*
X1497562D01*
X1497747Y905049D01*
Y904874D01*
X1496347D01*
Y905049D01*
G37*
G36*
G01X1507471D02*
X1507656Y905649D01*
X1508686D01*
X1508871Y905049D01*
Y904874D01*
X1507471D01*
Y905049D01*
G37*
G36*
G01X1503771D02*
X1503956Y905649D01*
X1504986D01*
X1505171Y905049D01*
Y904874D01*
X1503771D01*
Y905049D01*
G37*
G36*
G01X1500047D02*
X1500232Y905649D01*
X1501262D01*
X1501447Y905049D01*
Y904875D01*
X1500047D01*
Y905049D01*
G37*
G36*
G01X1496347D02*
X1496532Y905649D01*
X1497562D01*
X1497747Y905049D01*
Y904874D01*
X1496347D01*
Y905049D01*
G37*
G36*
G01X1507471D02*
X1507656Y905649D01*
X1508686D01*
X1508871Y905049D01*
Y904874D01*
X1507471D01*
Y905049D01*
G37*
G36*
G01X1503771D02*
X1503956Y905649D01*
X1504986D01*
X1505171Y905049D01*
Y904874D01*
X1503771D01*
Y905049D01*
G37*
G36*
G01X1497737Y932291D02*
X1497552Y931691D01*
X1496522D01*
X1496337Y932291D01*
Y932465D01*
X1497737D01*
Y932291D01*
G37*
G36*
G01X1501494D02*
X1501309Y931691D01*
X1500279D01*
X1500094Y932291D01*
Y932465D01*
X1501494D01*
Y932291D01*
G37*
G36*
G01X1508847D02*
X1508662Y931691D01*
X1507632D01*
X1507447Y932291D01*
Y932466D01*
X1508847D01*
Y932291D01*
G37*
G36*
G01X1505171D02*
X1504986Y931691D01*
X1503956D01*
X1503771Y932291D01*
Y932466D01*
X1505171D01*
Y932291D01*
G37*
G36*
G01X1497737D02*
X1497552Y931691D01*
X1496522D01*
X1496337Y932291D01*
Y932465D01*
X1497737D01*
Y932291D01*
G37*
G36*
G01X1501494D02*
X1501309Y931691D01*
X1500279D01*
X1500094Y932291D01*
Y932465D01*
X1501494D01*
Y932291D01*
G37*
G36*
G01X1508847D02*
X1508662Y931691D01*
X1507632D01*
X1507447Y932291D01*
Y932466D01*
X1508847D01*
Y932291D01*
G37*
G36*
G01X1505171D02*
X1504986Y931691D01*
X1503956D01*
X1503771Y932291D01*
Y932466D01*
X1505171D01*
Y932291D01*
G37*
G36*
G01X1500047Y930685D02*
X1500232Y931285D01*
X1501262D01*
X1501447Y930685D01*
Y930510D01*
X1500047D01*
Y930685D01*
G37*
G36*
G01X1496370Y930683D02*
X1496555Y931283D01*
X1497585D01*
X1497770Y930683D01*
Y930509D01*
X1496370D01*
Y930683D01*
G37*
G36*
G01X1507447D02*
X1507632Y931283D01*
X1508662D01*
X1508847Y930683D01*
Y930509D01*
X1507447D01*
Y930683D01*
G37*
G36*
G01X1503771D02*
X1503956Y931283D01*
X1504986D01*
X1505171Y930683D01*
Y930509D01*
X1503771D01*
Y930683D01*
G37*
G36*
G01X1500047Y930685D02*
X1500232Y931285D01*
X1501262D01*
X1501447Y930685D01*
Y930510D01*
X1500047D01*
Y930685D01*
G37*
G36*
G01X1496370Y930683D02*
X1496555Y931283D01*
X1497585D01*
X1497770Y930683D01*
Y930509D01*
X1496370D01*
Y930683D01*
G37*
G36*
G01X1507447D02*
X1507632Y931283D01*
X1508662D01*
X1508847Y930683D01*
Y930509D01*
X1507447D01*
Y930683D01*
G37*
G36*
G01X1503771D02*
X1503956Y931283D01*
X1504986D01*
X1505171Y930683D01*
Y930509D01*
X1503771D01*
Y930683D01*
G37*
G36*
G01X1501471Y919475D02*
X1501286Y918875D01*
X1500256D01*
X1500071Y919475D01*
Y919649D01*
X1501471D01*
Y919475D01*
G37*
G36*
G01X1497747Y919473D02*
X1497562Y918873D01*
X1496532D01*
X1496347Y919473D01*
Y919648D01*
X1497747D01*
Y919473D01*
G37*
G36*
G01X1508871Y919475D02*
X1508686Y918875D01*
X1507656D01*
X1507471Y919475D01*
Y919649D01*
X1508871D01*
Y919475D01*
G37*
G36*
G01X1505171D02*
X1504986Y918875D01*
X1503956D01*
X1503771Y919475D01*
Y919649D01*
X1505171D01*
Y919475D01*
G37*
G36*
G01X1501471D02*
X1501286Y918875D01*
X1500256D01*
X1500071Y919475D01*
Y919649D01*
X1501471D01*
Y919475D01*
G37*
G36*
G01X1497747Y919473D02*
X1497562Y918873D01*
X1496532D01*
X1496347Y919473D01*
Y919648D01*
X1497747D01*
Y919473D01*
G37*
G36*
G01X1508871Y919475D02*
X1508686Y918875D01*
X1507656D01*
X1507471Y919475D01*
Y919649D01*
X1508871D01*
Y919475D01*
G37*
G36*
G01X1505171D02*
X1504986Y918875D01*
X1503956D01*
X1503771Y919475D01*
Y919649D01*
X1505171D01*
Y919475D01*
G37*
G36*
G01X1494504Y921069D02*
X1494689Y921669D01*
X1495719D01*
X1495904Y921069D01*
Y920895D01*
X1494504D01*
Y921069D01*
G37*
G36*
G01X1498221Y921071D02*
X1498406Y921671D01*
X1499436D01*
X1499621Y921071D01*
Y920896D01*
X1498221D01*
Y921071D01*
G37*
G36*
G01X1505621D02*
X1505806Y921671D01*
X1506836D01*
X1507021Y921071D01*
Y920896D01*
X1505621D01*
Y921071D01*
G37*
G36*
G01X1501921D02*
X1502106Y921671D01*
X1503136D01*
X1503321Y921071D01*
Y920896D01*
X1501921D01*
Y921071D01*
G37*
G36*
G01X1494504Y921069D02*
X1494689Y921669D01*
X1495719D01*
X1495904Y921069D01*
Y920895D01*
X1494504D01*
Y921069D01*
G37*
G36*
G01X1498221Y921071D02*
X1498406Y921671D01*
X1499436D01*
X1499621Y921071D01*
Y920896D01*
X1498221D01*
Y921071D01*
G37*
G36*
G01X1505621D02*
X1505806Y921671D01*
X1506836D01*
X1507021Y921071D01*
Y920896D01*
X1505621D01*
Y921071D01*
G37*
G36*
G01X1501921D02*
X1502106Y921671D01*
X1503136D01*
X1503321Y921071D01*
Y920896D01*
X1501921D01*
Y921071D01*
G37*
G36*
G01X1500104Y917867D02*
X1500289Y918467D01*
X1501319D01*
X1501504Y917867D01*
Y917692D01*
X1500104D01*
Y917867D01*
G37*
G36*
G01X1496347D02*
X1496532Y918467D01*
X1497562D01*
X1497747Y917867D01*
Y917692D01*
X1496347D01*
Y917867D01*
G37*
G36*
G01X1507471Y917865D02*
X1507656Y918465D01*
X1508686D01*
X1508871Y917865D01*
Y917691D01*
X1507471D01*
Y917865D01*
G37*
G36*
G01X1503771D02*
X1503956Y918465D01*
X1504986D01*
X1505171Y917865D01*
Y917691D01*
X1503771D01*
Y917865D01*
G37*
G36*
G01X1500104Y917867D02*
X1500289Y918467D01*
X1501319D01*
X1501504Y917867D01*
Y917692D01*
X1500104D01*
Y917867D01*
G37*
G36*
G01X1496347D02*
X1496532Y918467D01*
X1497562D01*
X1497747Y917867D01*
Y917692D01*
X1496347D01*
Y917867D01*
G37*
G36*
G01X1507471Y917865D02*
X1507656Y918465D01*
X1508686D01*
X1508871Y917865D01*
Y917691D01*
X1507471D01*
Y917865D01*
G37*
G36*
G01X1503771D02*
X1503956Y918465D01*
X1504986D01*
X1505171Y917865D01*
Y917691D01*
X1503771D01*
Y917865D01*
G37*
G36*
G01X1499644Y929087D02*
X1499459Y928487D01*
X1498429D01*
X1498244Y929087D01*
Y929261D01*
X1499644D01*
Y929087D01*
G37*
G36*
G01X1495944D02*
X1495759Y928487D01*
X1494729D01*
X1494544Y929087D01*
Y929262D01*
X1495944D01*
Y929087D01*
G37*
G36*
G01X1507021D02*
X1506836Y928487D01*
X1505806D01*
X1505621Y929087D01*
Y929262D01*
X1507021D01*
Y929087D01*
G37*
G36*
G01X1503321D02*
X1503136Y928487D01*
X1502106D01*
X1501921Y929087D01*
Y929262D01*
X1503321D01*
Y929087D01*
G37*
G36*
G01X1499644D02*
X1499459Y928487D01*
X1498429D01*
X1498244Y929087D01*
Y929261D01*
X1499644D01*
Y929087D01*
G37*
G36*
G01X1495944D02*
X1495759Y928487D01*
X1494729D01*
X1494544Y929087D01*
Y929262D01*
X1495944D01*
Y929087D01*
G37*
G36*
G01X1507021D02*
X1506836Y928487D01*
X1505806D01*
X1505621Y929087D01*
Y929262D01*
X1507021D01*
Y929087D01*
G37*
G36*
G01X1503321D02*
X1503136Y928487D01*
X1502106D01*
X1501921Y929087D01*
Y929262D01*
X1503321D01*
Y929087D01*
G37*
G36*
G01X1499654Y922679D02*
X1499469Y922079D01*
X1498439D01*
X1498254Y922679D01*
Y922853D01*
X1499654D01*
Y922679D01*
G37*
G36*
G01X1495921D02*
X1495736Y922079D01*
X1494706D01*
X1494521Y922679D01*
Y922854D01*
X1495921D01*
Y922679D01*
G37*
G36*
G01X1507021D02*
X1506836Y922079D01*
X1505806D01*
X1505621Y922679D01*
Y922854D01*
X1507021D01*
Y922679D01*
G37*
G36*
G01X1503321D02*
X1503136Y922079D01*
X1502106D01*
X1501921Y922679D01*
Y922854D01*
X1503321D01*
Y922679D01*
G37*
G36*
G01X1499654D02*
X1499469Y922079D01*
X1498439D01*
X1498254Y922679D01*
Y922853D01*
X1499654D01*
Y922679D01*
G37*
G36*
G01X1495921D02*
X1495736Y922079D01*
X1494706D01*
X1494521Y922679D01*
Y922854D01*
X1495921D01*
Y922679D01*
G37*
G36*
G01X1507021D02*
X1506836Y922079D01*
X1505806D01*
X1505621Y922679D01*
Y922854D01*
X1507021D01*
Y922679D01*
G37*
G36*
G01X1503321D02*
X1503136Y922079D01*
X1502106D01*
X1501921Y922679D01*
Y922854D01*
X1503321D01*
Y922679D01*
G37*
G36*
G01X1498244Y927479D02*
X1498429Y928079D01*
X1499459D01*
X1499644Y927479D01*
Y927305D01*
X1498244D01*
Y927479D01*
G37*
G36*
G01X1494507D02*
X1494692Y928079D01*
X1495722D01*
X1495907Y927479D01*
Y927304D01*
X1494507D01*
Y927479D01*
G37*
G36*
G01X1505621D02*
X1505806Y928079D01*
X1506836D01*
X1507021Y927479D01*
Y927304D01*
X1505621D01*
Y927479D01*
G37*
G36*
G01X1501921D02*
X1502106Y928079D01*
X1503136D01*
X1503321Y927479D01*
Y927304D01*
X1501921D01*
Y927479D01*
G37*
G36*
G01X1498244D02*
X1498429Y928079D01*
X1499459D01*
X1499644Y927479D01*
Y927305D01*
X1498244D01*
Y927479D01*
G37*
G36*
G01X1494507D02*
X1494692Y928079D01*
X1495722D01*
X1495907Y927479D01*
Y927304D01*
X1494507D01*
Y927479D01*
G37*
G36*
G01X1505621D02*
X1505806Y928079D01*
X1506836D01*
X1507021Y927479D01*
Y927304D01*
X1505621D01*
Y927479D01*
G37*
G36*
G01X1501921D02*
X1502106Y928079D01*
X1503136D01*
X1503321Y927479D01*
Y927304D01*
X1501921D01*
Y927479D01*
G37*
G36*
G01X1500047Y924275D02*
X1500232Y924875D01*
X1501262D01*
X1501447Y924275D01*
Y924101D01*
X1500047D01*
Y924275D01*
G37*
G36*
G01X1496347D02*
X1496532Y924875D01*
X1497562D01*
X1497747Y924275D01*
Y924100D01*
X1496347D01*
Y924275D01*
G37*
G36*
G01X1507471D02*
X1507656Y924875D01*
X1508686D01*
X1508871Y924275D01*
Y924100D01*
X1507471D01*
Y924275D01*
G37*
G36*
G01X1503771D02*
X1503956Y924875D01*
X1504986D01*
X1505171Y924275D01*
Y924100D01*
X1503771D01*
Y924275D01*
G37*
G36*
G01X1500047D02*
X1500232Y924875D01*
X1501262D01*
X1501447Y924275D01*
Y924101D01*
X1500047D01*
Y924275D01*
G37*
G36*
G01X1496347D02*
X1496532Y924875D01*
X1497562D01*
X1497747Y924275D01*
Y924100D01*
X1496347D01*
Y924275D01*
G37*
G36*
G01X1507471D02*
X1507656Y924875D01*
X1508686D01*
X1508871Y924275D01*
Y924100D01*
X1507471D01*
Y924275D01*
G37*
G36*
G01X1503771D02*
X1503956Y924875D01*
X1504986D01*
X1505171Y924275D01*
Y924100D01*
X1503771D01*
Y924275D01*
G37*
G36*
G01X1501447Y925883D02*
X1501262Y925283D01*
X1500232D01*
X1500047Y925883D01*
Y926057D01*
X1501447D01*
Y925883D01*
G37*
G36*
G01X1497784D02*
X1497599Y925283D01*
X1496569D01*
X1496384Y925883D01*
Y926058D01*
X1497784D01*
Y925883D01*
G37*
G36*
G01X1508871D02*
X1508686Y925283D01*
X1507656D01*
X1507471Y925883D01*
Y926058D01*
X1508871D01*
Y925883D01*
G37*
G36*
G01X1505171D02*
X1504986Y925283D01*
X1503956D01*
X1503771Y925883D01*
Y926058D01*
X1505171D01*
Y925883D01*
G37*
G36*
G01X1501447D02*
X1501262Y925283D01*
X1500232D01*
X1500047Y925883D01*
Y926057D01*
X1501447D01*
Y925883D01*
G37*
G36*
G01X1497784D02*
X1497599Y925283D01*
X1496569D01*
X1496384Y925883D01*
Y926058D01*
X1497784D01*
Y925883D01*
G37*
G36*
G01X1508871D02*
X1508686Y925283D01*
X1507656D01*
X1507471Y925883D01*
Y926058D01*
X1508871D01*
Y925883D01*
G37*
G36*
G01X1505171D02*
X1504986Y925283D01*
X1503956D01*
X1503771Y925883D01*
Y926058D01*
X1505171D01*
Y925883D01*
G37*
G36*
G01X1495944Y948313D02*
X1495759Y947713D01*
X1494729D01*
X1494544Y948313D01*
Y948488D01*
X1495944D01*
Y948313D01*
G37*
G36*
G01X1499644D02*
X1499459Y947713D01*
X1498429D01*
X1498244Y948313D01*
Y948487D01*
X1499644D01*
Y948313D01*
G37*
G36*
G01X1503321D02*
X1503136Y947713D01*
X1502106D01*
X1501921Y948313D01*
Y948488D01*
X1503321D01*
Y948313D01*
G37*
G36*
G01X1507054D02*
X1506869Y947713D01*
X1505839D01*
X1505654Y948313D01*
Y948487D01*
X1507054D01*
Y948313D01*
G37*
G36*
G01X1495944D02*
X1495759Y947713D01*
X1494729D01*
X1494544Y948313D01*
Y948488D01*
X1495944D01*
Y948313D01*
G37*
G36*
G01X1499644D02*
X1499459Y947713D01*
X1498429D01*
X1498244Y948313D01*
Y948487D01*
X1499644D01*
Y948313D01*
G37*
G36*
G01X1503321D02*
X1503136Y947713D01*
X1502106D01*
X1501921Y948313D01*
Y948488D01*
X1503321D01*
Y948313D01*
G37*
G36*
G01X1507054D02*
X1506869Y947713D01*
X1505839D01*
X1505654Y948313D01*
Y948487D01*
X1507054D01*
Y948313D01*
G37*
G36*
G01X1494504Y940295D02*
X1494689Y940895D01*
X1495719D01*
X1495904Y940295D01*
Y940121D01*
X1494504D01*
Y940295D01*
G37*
G36*
G01X1498204D02*
X1498389Y940895D01*
X1499419D01*
X1499604Y940295D01*
Y940121D01*
X1498204D01*
Y940295D01*
G37*
G36*
G01X1501908D02*
X1502093Y940895D01*
X1503123D01*
X1503308Y940295D01*
Y940121D01*
X1501908D01*
Y940295D01*
G37*
G36*
G01X1505621D02*
X1505806Y940895D01*
X1506836D01*
X1507021Y940295D01*
Y940121D01*
X1505621D01*
Y940295D01*
G37*
G36*
G01X1494504D02*
X1494689Y940895D01*
X1495719D01*
X1495904Y940295D01*
Y940121D01*
X1494504D01*
Y940295D01*
G37*
G36*
G01X1498204D02*
X1498389Y940895D01*
X1499419D01*
X1499604Y940295D01*
Y940121D01*
X1498204D01*
Y940295D01*
G37*
G36*
G01X1501908D02*
X1502093Y940895D01*
X1503123D01*
X1503308Y940295D01*
Y940121D01*
X1501908D01*
Y940295D01*
G37*
G36*
G01X1505621D02*
X1505806Y940895D01*
X1506836D01*
X1507021Y940295D01*
Y940121D01*
X1505621D01*
Y940295D01*
G37*
G36*
G01X1496384Y937091D02*
X1496569Y937691D01*
X1497599D01*
X1497784Y937091D01*
Y936916D01*
X1496384D01*
Y937091D01*
G37*
G36*
G01X1500084D02*
X1500269Y937691D01*
X1501299D01*
X1501484Y937091D01*
Y936916D01*
X1500084D01*
Y937091D01*
G37*
G36*
G01X1507471D02*
X1507656Y937691D01*
X1508686D01*
X1508871Y937091D01*
Y936917D01*
X1507471D01*
Y937091D01*
G37*
G36*
G01X1503770D02*
X1503955Y937691D01*
X1504985D01*
X1505170Y937091D01*
Y936916D01*
X1503770D01*
Y937091D01*
G37*
G36*
G01X1496384D02*
X1496569Y937691D01*
X1497599D01*
X1497784Y937091D01*
Y936916D01*
X1496384D01*
Y937091D01*
G37*
G36*
G01X1500084D02*
X1500269Y937691D01*
X1501299D01*
X1501484Y937091D01*
Y936916D01*
X1500084D01*
Y937091D01*
G37*
G36*
G01X1507471D02*
X1507656Y937691D01*
X1508686D01*
X1508871Y937091D01*
Y936917D01*
X1507471D01*
Y937091D01*
G37*
G36*
G01X1503770D02*
X1503955Y937691D01*
X1504985D01*
X1505170Y937091D01*
Y936916D01*
X1503770D01*
Y937091D01*
G37*
G36*
G01X1497787Y938701D02*
X1497602Y938101D01*
X1496572D01*
X1496387Y938701D01*
Y938875D01*
X1497787D01*
Y938701D01*
G37*
G36*
G01X1501487D02*
X1501302Y938101D01*
X1500272D01*
X1500087Y938701D01*
Y938875D01*
X1501487D01*
Y938701D01*
G37*
G36*
G01X1505170D02*
X1504985Y938101D01*
X1503955D01*
X1503770Y938701D01*
Y938875D01*
X1505170D01*
Y938701D01*
G37*
G36*
G01X1508871D02*
X1508686Y938101D01*
X1507656D01*
X1507471Y938701D01*
Y938875D01*
X1508871D01*
Y938701D01*
G37*
G36*
G01X1497787D02*
X1497602Y938101D01*
X1496572D01*
X1496387Y938701D01*
Y938875D01*
X1497787D01*
Y938701D01*
G37*
G36*
G01X1501487D02*
X1501302Y938101D01*
X1500272D01*
X1500087Y938701D01*
Y938875D01*
X1501487D01*
Y938701D01*
G37*
G36*
G01X1505170D02*
X1504985Y938101D01*
X1503955D01*
X1503770Y938701D01*
Y938875D01*
X1505170D01*
Y938701D01*
G37*
G36*
G01X1508871D02*
X1508686Y938101D01*
X1507656D01*
X1507471Y938701D01*
Y938875D01*
X1508871D01*
Y938701D01*
G37*
G36*
G01X1495907Y935497D02*
X1495722Y934897D01*
X1494692D01*
X1494507Y935497D01*
Y935671D01*
X1495907D01*
Y935497D01*
G37*
G36*
G01X1499607D02*
X1499422Y934897D01*
X1498392D01*
X1498207Y935497D01*
Y935671D01*
X1499607D01*
Y935497D01*
G37*
G36*
G01X1507021Y935495D02*
X1506836Y934895D01*
X1505806D01*
X1505621Y935495D01*
Y935670D01*
X1507021D01*
Y935495D01*
G37*
G36*
G01X1503312D02*
X1503127Y934895D01*
X1502097D01*
X1501912Y935495D01*
Y935670D01*
X1503312D01*
Y935495D01*
G37*
G36*
G01X1495907Y935497D02*
X1495722Y934897D01*
X1494692D01*
X1494507Y935497D01*
Y935671D01*
X1495907D01*
Y935497D01*
G37*
G36*
G01X1499607D02*
X1499422Y934897D01*
X1498392D01*
X1498207Y935497D01*
Y935671D01*
X1499607D01*
Y935497D01*
G37*
G36*
G01X1507021Y935495D02*
X1506836Y934895D01*
X1505806D01*
X1505621Y935495D01*
Y935670D01*
X1507021D01*
Y935495D01*
G37*
G36*
G01X1503312D02*
X1503127Y934895D01*
X1502097D01*
X1501912Y935495D01*
Y935670D01*
X1503312D01*
Y935495D01*
G37*
G36*
G01X1494554Y933889D02*
X1494739Y934489D01*
X1495769D01*
X1495954Y933889D01*
Y933714D01*
X1494554D01*
Y933889D01*
G37*
G36*
G01X1498244Y933887D02*
X1498429Y934487D01*
X1499459D01*
X1499644Y933887D01*
Y933713D01*
X1498244D01*
Y933887D01*
G37*
G36*
G01X1501897Y933889D02*
X1502082Y934489D01*
X1503112D01*
X1503297Y933889D01*
Y933714D01*
X1501897D01*
Y933889D01*
G37*
G36*
G01X1505621Y933887D02*
X1505806Y934487D01*
X1506836D01*
X1507021Y933887D01*
Y933713D01*
X1505621D01*
Y933887D01*
G37*
G36*
G01X1494554Y933889D02*
X1494739Y934489D01*
X1495769D01*
X1495954Y933889D01*
Y933714D01*
X1494554D01*
Y933889D01*
G37*
G36*
G01X1498244Y933887D02*
X1498429Y934487D01*
X1499459D01*
X1499644Y933887D01*
Y933713D01*
X1498244D01*
Y933887D01*
G37*
G36*
G01X1501897Y933889D02*
X1502082Y934489D01*
X1503112D01*
X1503297Y933889D01*
Y933714D01*
X1501897D01*
Y933889D01*
G37*
G36*
G01X1505621Y933887D02*
X1505806Y934487D01*
X1506836D01*
X1507021Y933887D01*
Y933713D01*
X1505621D01*
Y933887D01*
G37*
G36*
G01X1497794Y945109D02*
X1497609Y944509D01*
X1496579D01*
X1496394Y945109D01*
Y945283D01*
X1497794D01*
Y945109D01*
G37*
G36*
G01X1501447Y945107D02*
X1501262Y944507D01*
X1500232D01*
X1500047Y945107D01*
Y945282D01*
X1501447D01*
Y945107D01*
G37*
G36*
G01X1505147Y945109D02*
X1504962Y944509D01*
X1503932D01*
X1503747Y945109D01*
Y945283D01*
X1505147D01*
Y945109D01*
G37*
G36*
G01X1508871D02*
X1508686Y944509D01*
X1507656D01*
X1507471Y945109D01*
Y945284D01*
X1508871D01*
Y945109D01*
G37*
G36*
G01X1497794D02*
X1497609Y944509D01*
X1496579D01*
X1496394Y945109D01*
Y945283D01*
X1497794D01*
Y945109D01*
G37*
G36*
G01X1501447Y945107D02*
X1501262Y944507D01*
X1500232D01*
X1500047Y945107D01*
Y945282D01*
X1501447D01*
Y945107D01*
G37*
G36*
G01X1505147Y945109D02*
X1504962Y944509D01*
X1503932D01*
X1503747Y945109D01*
Y945283D01*
X1505147D01*
Y945109D01*
G37*
G36*
G01X1508871D02*
X1508686Y944509D01*
X1507656D01*
X1507471Y945109D01*
Y945284D01*
X1508871D01*
Y945109D01*
G37*
G36*
G01X1496347Y943499D02*
X1496532Y944099D01*
X1497562D01*
X1497747Y943499D01*
Y943325D01*
X1496347D01*
Y943499D01*
G37*
G36*
G01X1500047Y943501D02*
X1500232Y944101D01*
X1501262D01*
X1501447Y943501D01*
Y943326D01*
X1500047D01*
Y943501D01*
G37*
G36*
G01X1507447D02*
X1507632Y944101D01*
X1508662D01*
X1508847Y943501D01*
Y943326D01*
X1507447D01*
Y943501D01*
G37*
G36*
G01X1503747Y943499D02*
X1503932Y944099D01*
X1504962D01*
X1505147Y943499D01*
Y943325D01*
X1503747D01*
Y943499D01*
G37*
G36*
G01X1496347D02*
X1496532Y944099D01*
X1497562D01*
X1497747Y943499D01*
Y943325D01*
X1496347D01*
Y943499D01*
G37*
G36*
G01X1500047Y943501D02*
X1500232Y944101D01*
X1501262D01*
X1501447Y943501D01*
Y943326D01*
X1500047D01*
Y943501D01*
G37*
G36*
G01X1507447D02*
X1507632Y944101D01*
X1508662D01*
X1508847Y943501D01*
Y943326D01*
X1507447D01*
Y943501D01*
G37*
G36*
G01X1503747Y943499D02*
X1503932Y944099D01*
X1504962D01*
X1505147Y943499D01*
Y943325D01*
X1503747D01*
Y943499D01*
G37*
G36*
G01X1498244Y946705D02*
X1498429Y947305D01*
X1499459D01*
X1499644Y946705D01*
Y946531D01*
X1498244D01*
Y946705D01*
G37*
G36*
G01X1494497D02*
X1494682Y947305D01*
X1495712D01*
X1495897Y946705D01*
Y946530D01*
X1494497D01*
Y946705D01*
G37*
G36*
G01X1505654D02*
X1505839Y947305D01*
X1506869D01*
X1507054Y946705D01*
Y946531D01*
X1505654D01*
Y946705D01*
G37*
G36*
G01X1501921D02*
X1502106Y947305D01*
X1503136D01*
X1503321Y946705D01*
Y946530D01*
X1501921D01*
Y946705D01*
G37*
G36*
G01X1498244D02*
X1498429Y947305D01*
X1499459D01*
X1499644Y946705D01*
Y946531D01*
X1498244D01*
Y946705D01*
G37*
G36*
G01X1494497D02*
X1494682Y947305D01*
X1495712D01*
X1495897Y946705D01*
Y946530D01*
X1494497D01*
Y946705D01*
G37*
G36*
G01X1505654D02*
X1505839Y947305D01*
X1506869D01*
X1507054Y946705D01*
Y946531D01*
X1505654D01*
Y946705D01*
G37*
G36*
G01X1501921D02*
X1502106Y947305D01*
X1503136D01*
X1503321Y946705D01*
Y946530D01*
X1501921D01*
Y946705D01*
G37*
G36*
G01X1495921Y941905D02*
X1495736Y941305D01*
X1494706D01*
X1494521Y941905D01*
Y942079D01*
X1495921D01*
Y941905D01*
G37*
G36*
G01X1499654Y941903D02*
X1499469Y941303D01*
X1498439D01*
X1498254Y941903D01*
Y942078D01*
X1499654D01*
Y941903D01*
G37*
G36*
G01X1507054D02*
X1506869Y941303D01*
X1505839D01*
X1505654Y941903D01*
Y942078D01*
X1507054D01*
Y941903D01*
G37*
G36*
G01X1503321Y941905D02*
X1503136Y941305D01*
X1502106D01*
X1501921Y941905D01*
Y942079D01*
X1503321D01*
Y941905D01*
G37*
G36*
G01X1495921D02*
X1495736Y941305D01*
X1494706D01*
X1494521Y941905D01*
Y942079D01*
X1495921D01*
Y941905D01*
G37*
G36*
G01X1499654Y941903D02*
X1499469Y941303D01*
X1498439D01*
X1498254Y941903D01*
Y942078D01*
X1499654D01*
Y941903D01*
G37*
G36*
G01X1507054D02*
X1506869Y941303D01*
X1505839D01*
X1505654Y941903D01*
Y942078D01*
X1507054D01*
Y941903D01*
G37*
G36*
G01X1503321Y941905D02*
X1503136Y941305D01*
X1502106D01*
X1501921Y941905D01*
Y942079D01*
X1503321D01*
Y941905D01*
G37*
G36*
G01X1498254Y953113D02*
X1498439Y953713D01*
X1499469D01*
X1499654Y953113D01*
Y952939D01*
X1498254D01*
Y953113D01*
G37*
G36*
G01X1494554D02*
X1494739Y953713D01*
X1495769D01*
X1495954Y953113D01*
Y952939D01*
X1494554D01*
Y953113D01*
G37*
G36*
G01X1505654D02*
X1505839Y953713D01*
X1506869D01*
X1507054Y953113D01*
Y952939D01*
X1505654D01*
Y953113D01*
G37*
G36*
G01X1501921D02*
X1502106Y953713D01*
X1503136D01*
X1503321Y953113D01*
Y952938D01*
X1501921D01*
Y953113D01*
G37*
G36*
G01X1498254D02*
X1498439Y953713D01*
X1499469D01*
X1499654Y953113D01*
Y952939D01*
X1498254D01*
Y953113D01*
G37*
G36*
G01X1494554D02*
X1494739Y953713D01*
X1495769D01*
X1495954Y953113D01*
Y952939D01*
X1494554D01*
Y953113D01*
G37*
G36*
G01X1505654D02*
X1505839Y953713D01*
X1506869D01*
X1507054Y953113D01*
Y952939D01*
X1505654D01*
Y953113D01*
G37*
G36*
G01X1501921D02*
X1502106Y953713D01*
X1503136D01*
X1503321Y953113D01*
Y952938D01*
X1501921D01*
Y953113D01*
G37*
G36*
G01X1496370Y949909D02*
X1496555Y950509D01*
X1497585D01*
X1497770Y949909D01*
Y949734D01*
X1496370D01*
Y949909D01*
G37*
G36*
G01X1500047D02*
X1500232Y950509D01*
X1501262D01*
X1501447Y949909D01*
Y949735D01*
X1500047D01*
Y949909D01*
G37*
G36*
G01X1503747D02*
X1503932Y950509D01*
X1504962D01*
X1505147Y949909D01*
Y949734D01*
X1503747D01*
Y949909D01*
G37*
G36*
G01X1507447D02*
X1507632Y950509D01*
X1508662D01*
X1508847Y949909D01*
Y949735D01*
X1507447D01*
Y949909D01*
G37*
G36*
G01X1496370D02*
X1496555Y950509D01*
X1497585D01*
X1497770Y949909D01*
Y949734D01*
X1496370D01*
Y949909D01*
G37*
G36*
G01X1500047D02*
X1500232Y950509D01*
X1501262D01*
X1501447Y949909D01*
Y949735D01*
X1500047D01*
Y949909D01*
G37*
G36*
G01X1503747D02*
X1503932Y950509D01*
X1504962D01*
X1505147Y949909D01*
Y949734D01*
X1503747D01*
Y949909D01*
G37*
G36*
G01X1507447D02*
X1507632Y950509D01*
X1508662D01*
X1508847Y949909D01*
Y949735D01*
X1507447D01*
Y949909D01*
G37*
G36*
G01X1497737Y951517D02*
X1497552Y950917D01*
X1496522D01*
X1496337Y951517D01*
Y951691D01*
X1497737D01*
Y951517D01*
G37*
G36*
G01X1501447D02*
X1501262Y950917D01*
X1500232D01*
X1500047Y951517D01*
Y951691D01*
X1501447D01*
Y951517D01*
G37*
G36*
G01X1505147D02*
X1504962Y950917D01*
X1503932D01*
X1503747Y951517D01*
Y951692D01*
X1505147D01*
Y951517D01*
G37*
G36*
G01X1508847D02*
X1508662Y950917D01*
X1507632D01*
X1507447Y951517D01*
Y951691D01*
X1508847D01*
Y951517D01*
G37*
G36*
G01X1497737D02*
X1497552Y950917D01*
X1496522D01*
X1496337Y951517D01*
Y951691D01*
X1497737D01*
Y951517D01*
G37*
G36*
G01X1501447D02*
X1501262Y950917D01*
X1500232D01*
X1500047Y951517D01*
Y951691D01*
X1501447D01*
Y951517D01*
G37*
G36*
G01X1505147D02*
X1504962Y950917D01*
X1503932D01*
X1503747Y951517D01*
Y951692D01*
X1505147D01*
Y951517D01*
G37*
G36*
G01X1508847D02*
X1508662Y950917D01*
X1507632D01*
X1507447Y951517D01*
Y951691D01*
X1508847D01*
Y951517D01*
G37*
G36*
G01X1494554Y959523D02*
X1494739Y960123D01*
X1495769D01*
X1495954Y959523D01*
Y959348D01*
X1494554D01*
Y959523D01*
G37*
G36*
G01X1498221Y959521D02*
X1498406Y960121D01*
X1499436D01*
X1499621Y959521D01*
Y959347D01*
X1498221D01*
Y959521D01*
G37*
G36*
G01X1501921D02*
X1502106Y960121D01*
X1503136D01*
X1503321Y959521D01*
Y959347D01*
X1501921D01*
Y959521D01*
G37*
G36*
G01X1505654Y959523D02*
X1505839Y960123D01*
X1506869D01*
X1507054Y959523D01*
Y959348D01*
X1505654D01*
Y959523D01*
G37*
G36*
G01X1494554D02*
X1494739Y960123D01*
X1495769D01*
X1495954Y959523D01*
Y959348D01*
X1494554D01*
Y959523D01*
G37*
G36*
G01X1498221Y959521D02*
X1498406Y960121D01*
X1499436D01*
X1499621Y959521D01*
Y959347D01*
X1498221D01*
Y959521D01*
G37*
G36*
G01X1501921D02*
X1502106Y960121D01*
X1503136D01*
X1503321Y959521D01*
Y959347D01*
X1501921D01*
Y959521D01*
G37*
G36*
G01X1505654Y959523D02*
X1505839Y960123D01*
X1506869D01*
X1507054Y959523D01*
Y959348D01*
X1505654D01*
Y959523D01*
G37*
G36*
G01X1497747Y957925D02*
X1497562Y957325D01*
X1496532D01*
X1496347Y957925D01*
Y958100D01*
X1497747D01*
Y957925D01*
G37*
G36*
G01X1501471Y957927D02*
X1501286Y957327D01*
X1500256D01*
X1500071Y957927D01*
Y958101D01*
X1501471D01*
Y957927D01*
G37*
G36*
G01X1505147D02*
X1504962Y957327D01*
X1503932D01*
X1503747Y957927D01*
Y958101D01*
X1505147D01*
Y957927D01*
G37*
G36*
G01X1508847Y957925D02*
X1508662Y957325D01*
X1507632D01*
X1507447Y957925D01*
Y958100D01*
X1508847D01*
Y957925D01*
G37*
G36*
G01X1497747D02*
X1497562Y957325D01*
X1496532D01*
X1496347Y957925D01*
Y958100D01*
X1497747D01*
Y957925D01*
G37*
G36*
G01X1501471Y957927D02*
X1501286Y957327D01*
X1500256D01*
X1500071Y957927D01*
Y958101D01*
X1501471D01*
Y957927D01*
G37*
G36*
G01X1505147D02*
X1504962Y957327D01*
X1503932D01*
X1503747Y957927D01*
Y958101D01*
X1505147D01*
Y957927D01*
G37*
G36*
G01X1508847Y957925D02*
X1508662Y957325D01*
X1507632D01*
X1507447Y957925D01*
Y958100D01*
X1508847D01*
Y957925D01*
G37*
G36*
G01X1500047Y962727D02*
X1500232Y963327D01*
X1501262D01*
X1501447Y962727D01*
Y962552D01*
X1500047D01*
Y962727D01*
G37*
G36*
G01X1496347Y962725D02*
X1496532Y963325D01*
X1497562D01*
X1497747Y962725D01*
Y962551D01*
X1496347D01*
Y962725D01*
G37*
G36*
G01X1507447Y962727D02*
X1507632Y963327D01*
X1508662D01*
X1508847Y962727D01*
Y962552D01*
X1507447D01*
Y962727D01*
G37*
G36*
G01X1503747Y962725D02*
X1503932Y963325D01*
X1504962D01*
X1505147Y962725D01*
Y962551D01*
X1503747D01*
Y962725D01*
G37*
G36*
G01X1500047Y962727D02*
X1500232Y963327D01*
X1501262D01*
X1501447Y962727D01*
Y962552D01*
X1500047D01*
Y962727D01*
G37*
G36*
G01X1496347Y962725D02*
X1496532Y963325D01*
X1497562D01*
X1497747Y962725D01*
Y962551D01*
X1496347D01*
Y962725D01*
G37*
G36*
G01X1507447Y962727D02*
X1507632Y963327D01*
X1508662D01*
X1508847Y962727D01*
Y962552D01*
X1507447D01*
Y962727D01*
G37*
G36*
G01X1503747Y962725D02*
X1503932Y963325D01*
X1504962D01*
X1505147Y962725D01*
Y962551D01*
X1503747D01*
Y962725D01*
G37*
G36*
G01X1495921Y961131D02*
X1495736Y960531D01*
X1494706D01*
X1494521Y961131D01*
Y961305D01*
X1495921D01*
Y961131D01*
G37*
G36*
G01X1499654Y961129D02*
X1499469Y960529D01*
X1498439D01*
X1498254Y961129D01*
Y961304D01*
X1499654D01*
Y961129D01*
G37*
G36*
G01X1507054D02*
X1506869Y960529D01*
X1505839D01*
X1505654Y961129D01*
Y961304D01*
X1507054D01*
Y961129D01*
G37*
G36*
G01X1503321Y961131D02*
X1503136Y960531D01*
X1502106D01*
X1501921Y961131D01*
Y961305D01*
X1503321D01*
Y961131D01*
G37*
G36*
G01X1495921D02*
X1495736Y960531D01*
X1494706D01*
X1494521Y961131D01*
Y961305D01*
X1495921D01*
Y961131D01*
G37*
G36*
G01X1499654Y961129D02*
X1499469Y960529D01*
X1498439D01*
X1498254Y961129D01*
Y961304D01*
X1499654D01*
Y961129D01*
G37*
G36*
G01X1507054D02*
X1506869Y960529D01*
X1505839D01*
X1505654Y961129D01*
Y961304D01*
X1507054D01*
Y961129D01*
G37*
G36*
G01X1503321Y961131D02*
X1503136Y960531D01*
X1502106D01*
X1501921Y961131D01*
Y961305D01*
X1503321D01*
Y961131D01*
G37*
G36*
G01X1496371Y981951D02*
X1496556Y982551D01*
X1497586D01*
X1497771Y981951D01*
Y981777D01*
X1496371D01*
Y981951D01*
G37*
G36*
G01X1500071D02*
X1500256Y982551D01*
X1501286D01*
X1501471Y981951D01*
Y981777D01*
X1500071D01*
Y981951D01*
G37*
G36*
G01X1503771D02*
X1503956Y982551D01*
X1504986D01*
X1505171Y981951D01*
Y981777D01*
X1503771D01*
Y981951D01*
G37*
G36*
G01X1496371D02*
X1496556Y982551D01*
X1497586D01*
X1497771Y981951D01*
Y981777D01*
X1496371D01*
Y981951D01*
G37*
G36*
G01X1500071D02*
X1500256Y982551D01*
X1501286D01*
X1501471Y981951D01*
Y981777D01*
X1500071D01*
Y981951D01*
G37*
G36*
G01X1503771D02*
X1503956Y982551D01*
X1504986D01*
X1505171Y981951D01*
Y981777D01*
X1503771D01*
Y981951D01*
G37*
G36*
G01X1494554Y978749D02*
X1494739Y979349D01*
X1495769D01*
X1495954Y978749D01*
Y978574D01*
X1494554D01*
Y978749D01*
G37*
G36*
G01X1498221Y978747D02*
X1498406Y979347D01*
X1499436D01*
X1499621Y978747D01*
Y978573D01*
X1498221D01*
Y978747D01*
G37*
G36*
G01X1501921D02*
X1502106Y979347D01*
X1503136D01*
X1503321Y978747D01*
Y978573D01*
X1501921D01*
Y978747D01*
G37*
G36*
G01X1505621D02*
X1505806Y979347D01*
X1506836D01*
X1507021Y978747D01*
Y978573D01*
X1505621D01*
Y978747D01*
G37*
G36*
G01X1494554Y978749D02*
X1494739Y979349D01*
X1495769D01*
X1495954Y978749D01*
Y978574D01*
X1494554D01*
Y978749D01*
G37*
G36*
G01X1498221Y978747D02*
X1498406Y979347D01*
X1499436D01*
X1499621Y978747D01*
Y978573D01*
X1498221D01*
Y978747D01*
G37*
G36*
G01X1501921D02*
X1502106Y979347D01*
X1503136D01*
X1503321Y978747D01*
Y978573D01*
X1501921D01*
Y978747D01*
G37*
G36*
G01X1505621D02*
X1505806Y979347D01*
X1506836D01*
X1507021Y978747D01*
Y978573D01*
X1505621D01*
Y978747D01*
G37*
G36*
G01X1499621Y980357D02*
X1499436Y979757D01*
X1498406D01*
X1498221Y980357D01*
Y980531D01*
X1499621D01*
Y980357D01*
G37*
G36*
G01X1495921D02*
X1495736Y979757D01*
X1494706D01*
X1494521Y980357D01*
Y980531D01*
X1495921D01*
Y980357D01*
G37*
G36*
G01X1507021D02*
X1506836Y979757D01*
X1505806D01*
X1505621Y980357D01*
Y980531D01*
X1507021D01*
Y980357D01*
G37*
G36*
G01X1503321D02*
X1503136Y979757D01*
X1502106D01*
X1501921Y980357D01*
Y980531D01*
X1503321D01*
Y980357D01*
G37*
G36*
G01X1499621D02*
X1499436Y979757D01*
X1498406D01*
X1498221Y980357D01*
Y980531D01*
X1499621D01*
Y980357D01*
G37*
G36*
G01X1495921D02*
X1495736Y979757D01*
X1494706D01*
X1494521Y980357D01*
Y980531D01*
X1495921D01*
Y980357D01*
G37*
G36*
G01X1507021D02*
X1506836Y979757D01*
X1505806D01*
X1505621Y980357D01*
Y980531D01*
X1507021D01*
Y980357D01*
G37*
G36*
G01X1503321D02*
X1503136Y979757D01*
X1502106D01*
X1501921Y980357D01*
Y980531D01*
X1503321D01*
Y980357D01*
G37*
G36*
G01X1497747Y977151D02*
X1497562Y976551D01*
X1496532D01*
X1496347Y977151D01*
Y977325D01*
X1497747D01*
Y977151D01*
G37*
G36*
G01X1501471D02*
X1501286Y976551D01*
X1500256D01*
X1500071Y977151D01*
Y977326D01*
X1501471D01*
Y977151D01*
G37*
G36*
G01X1505171D02*
X1504986Y976551D01*
X1503956D01*
X1503771Y977151D01*
Y977326D01*
X1505171D01*
Y977151D01*
G37*
G36*
G01X1508871D02*
X1508686Y976551D01*
X1507656D01*
X1507471Y977151D01*
Y977326D01*
X1508871D01*
Y977151D01*
G37*
G36*
G01X1497747D02*
X1497562Y976551D01*
X1496532D01*
X1496347Y977151D01*
Y977325D01*
X1497747D01*
Y977151D01*
G37*
G36*
G01X1501471D02*
X1501286Y976551D01*
X1500256D01*
X1500071Y977151D01*
Y977326D01*
X1501471D01*
Y977151D01*
G37*
G36*
G01X1505171D02*
X1504986Y976551D01*
X1503956D01*
X1503771Y977151D01*
Y977326D01*
X1505171D01*
Y977151D01*
G37*
G36*
G01X1508871D02*
X1508686Y976551D01*
X1507656D01*
X1507471Y977151D01*
Y977326D01*
X1508871D01*
Y977151D01*
G37*
G36*
G01X1507318Y1005475D02*
X1507745Y1005015D01*
X1507230Y1004123D01*
X1506618Y1004263D01*
X1506467Y1004350D01*
X1507167Y1005562D01*
X1507318Y1005475D01*
G37*
G36*
G01D02*
X1507745Y1005015D01*
X1507230Y1004123D01*
X1506618Y1004263D01*
X1506467Y1004350D01*
X1507167Y1005562D01*
X1507318Y1005475D01*
G37*
G36*
G01X1506185Y1006703D02*
X1505758Y1007163D01*
X1506273Y1008055D01*
X1506885Y1007915D01*
X1507036Y1007828D01*
X1506336Y1006616D01*
X1506185Y1006703D01*
G37*
G36*
G01X1507903Y1008493D02*
X1508088Y1009093D01*
X1509118D01*
X1509303Y1008493D01*
Y1008318D01*
X1507903D01*
Y1008493D01*
G37*
G36*
G01X1506185Y1006703D02*
X1505758Y1007163D01*
X1506273Y1008055D01*
X1506885Y1007915D01*
X1507036Y1007828D01*
X1506336Y1006616D01*
X1506185Y1006703D01*
G37*
G36*
G01X1507903Y1008493D02*
X1508088Y1009093D01*
X1509118D01*
X1509303Y1008493D01*
Y1008318D01*
X1507903D01*
Y1008493D01*
G37*
G36*
G01X1508043Y1003514D02*
X1507616Y1003974D01*
X1508131Y1004866D01*
X1508743Y1004726D01*
X1508894Y1004639D01*
X1508194Y1003427D01*
X1508043Y1003514D01*
G37*
G36*
G01D02*
X1507616Y1003974D01*
X1508131Y1004866D01*
X1508743Y1004726D01*
X1508894Y1004639D01*
X1508194Y1003427D01*
X1508043Y1003514D01*
G37*
G36*
G01X1500503Y1027719D02*
X1500688Y1028319D01*
X1501718D01*
X1501903Y1027719D01*
Y1027544D01*
X1500503D01*
Y1027719D01*
G37*
G36*
G01X1496770D02*
X1496955Y1028319D01*
X1497985D01*
X1498170Y1027719D01*
Y1027545D01*
X1496770D01*
Y1027719D01*
G37*
G36*
G01X1493070D02*
X1493255Y1028319D01*
X1494285D01*
X1494470Y1027719D01*
Y1027545D01*
X1493070D01*
Y1027719D01*
G37*
G36*
G01X1507903D02*
X1508088Y1028319D01*
X1509118D01*
X1509303Y1027719D01*
Y1027544D01*
X1507903D01*
Y1027719D01*
G37*
G36*
G01X1504170D02*
X1504355Y1028319D01*
X1505385D01*
X1505570Y1027719D01*
Y1027545D01*
X1504170D01*
Y1027719D01*
G37*
G36*
G01X1500503D02*
X1500688Y1028319D01*
X1501718D01*
X1501903Y1027719D01*
Y1027544D01*
X1500503D01*
Y1027719D01*
G37*
G36*
G01X1496770D02*
X1496955Y1028319D01*
X1497985D01*
X1498170Y1027719D01*
Y1027545D01*
X1496770D01*
Y1027719D01*
G37*
G36*
G01X1493070D02*
X1493255Y1028319D01*
X1494285D01*
X1494470Y1027719D01*
Y1027545D01*
X1493070D01*
Y1027719D01*
G37*
G36*
G01X1507903D02*
X1508088Y1028319D01*
X1509118D01*
X1509303Y1027719D01*
Y1027544D01*
X1507903D01*
Y1027719D01*
G37*
G36*
G01X1504170D02*
X1504355Y1028319D01*
X1505385D01*
X1505570Y1027719D01*
Y1027545D01*
X1504170D01*
Y1027719D01*
G37*
G36*
G01X1501870Y1029327D02*
X1501685Y1028727D01*
X1500655D01*
X1500470Y1029327D01*
Y1029501D01*
X1501870D01*
Y1029327D01*
G37*
G36*
G01X1498203D02*
X1498018Y1028727D01*
X1496988D01*
X1496803Y1029327D01*
Y1029502D01*
X1498203D01*
Y1029327D01*
G37*
G36*
G01X1494470D02*
X1494285Y1028727D01*
X1493255D01*
X1493070Y1029327D01*
Y1029501D01*
X1494470D01*
Y1029327D01*
G37*
G36*
G01X1509303D02*
X1509118Y1028727D01*
X1508088D01*
X1507903Y1029327D01*
Y1029502D01*
X1509303D01*
Y1029327D01*
G37*
G36*
G01X1505570D02*
X1505385Y1028727D01*
X1504355D01*
X1504170Y1029327D01*
Y1029501D01*
X1505570D01*
Y1029327D01*
G37*
G36*
G01X1501870D02*
X1501685Y1028727D01*
X1500655D01*
X1500470Y1029327D01*
Y1029501D01*
X1501870D01*
Y1029327D01*
G37*
G36*
G01X1498203D02*
X1498018Y1028727D01*
X1496988D01*
X1496803Y1029327D01*
Y1029502D01*
X1498203D01*
Y1029327D01*
G37*
G36*
G01X1494470D02*
X1494285Y1028727D01*
X1493255D01*
X1493070Y1029327D01*
Y1029501D01*
X1494470D01*
Y1029327D01*
G37*
G36*
G01X1509303D02*
X1509118Y1028727D01*
X1508088D01*
X1507903Y1029327D01*
Y1029502D01*
X1509303D01*
Y1029327D01*
G37*
G36*
G01X1505570D02*
X1505385Y1028727D01*
X1504355D01*
X1504170Y1029327D01*
Y1029501D01*
X1505570D01*
Y1029327D01*
G37*
G36*
G01X1500077Y1026123D02*
X1499892Y1025523D01*
X1498862D01*
X1498677Y1026123D01*
Y1026297D01*
X1500077D01*
Y1026123D01*
G37*
G36*
G01X1496387Y1026121D02*
X1496202Y1025521D01*
X1495172D01*
X1494987Y1026121D01*
Y1026296D01*
X1496387D01*
Y1026121D01*
G37*
G36*
G01X1507477Y1026123D02*
X1507292Y1025523D01*
X1506262D01*
X1506077Y1026123D01*
Y1026297D01*
X1507477D01*
Y1026123D01*
G37*
G36*
G01X1503777Y1026121D02*
X1503592Y1025521D01*
X1502562D01*
X1502377Y1026121D01*
Y1026296D01*
X1503777D01*
Y1026121D01*
G37*
G36*
G01X1500077Y1026123D02*
X1499892Y1025523D01*
X1498862D01*
X1498677Y1026123D01*
Y1026297D01*
X1500077D01*
Y1026123D01*
G37*
G36*
G01X1496387Y1026121D02*
X1496202Y1025521D01*
X1495172D01*
X1494987Y1026121D01*
Y1026296D01*
X1496387D01*
Y1026121D01*
G37*
G36*
G01X1507477Y1026123D02*
X1507292Y1025523D01*
X1506262D01*
X1506077Y1026123D01*
Y1026297D01*
X1507477D01*
Y1026123D01*
G37*
G36*
G01X1503777Y1026121D02*
X1503592Y1025521D01*
X1502562D01*
X1502377Y1026121D01*
Y1026296D01*
X1503777D01*
Y1026121D01*
G37*
G36*
G01X1494937Y1043739D02*
X1495122Y1044339D01*
X1496152D01*
X1496337Y1043739D01*
Y1043565D01*
X1494937D01*
Y1043739D01*
G37*
G36*
G01X1498637D02*
X1498822Y1044339D01*
X1499852D01*
X1500037Y1043739D01*
Y1043565D01*
X1498637D01*
Y1043739D01*
G37*
G36*
G01X1506087Y1043741D02*
X1506272Y1044341D01*
X1507302D01*
X1507487Y1043741D01*
Y1043566D01*
X1506087D01*
Y1043741D01*
G37*
G36*
G01X1502337Y1043739D02*
X1502522Y1044339D01*
X1503552D01*
X1503737Y1043739D01*
Y1043565D01*
X1502337D01*
Y1043739D01*
G37*
G36*
G01X1494937D02*
X1495122Y1044339D01*
X1496152D01*
X1496337Y1043739D01*
Y1043565D01*
X1494937D01*
Y1043739D01*
G37*
G36*
G01X1498637D02*
X1498822Y1044339D01*
X1499852D01*
X1500037Y1043739D01*
Y1043565D01*
X1498637D01*
Y1043739D01*
G37*
G36*
G01X1506087Y1043741D02*
X1506272Y1044341D01*
X1507302D01*
X1507487Y1043741D01*
Y1043566D01*
X1506087D01*
Y1043741D01*
G37*
G36*
G01X1502337Y1043739D02*
X1502522Y1044339D01*
X1503552D01*
X1503737Y1043739D01*
Y1043565D01*
X1502337D01*
Y1043739D01*
G37*
G36*
G01X1496817Y1040535D02*
X1497002Y1041135D01*
X1498032D01*
X1498217Y1040535D01*
Y1040360D01*
X1496817D01*
Y1040535D01*
G37*
G36*
G01X1493117D02*
X1493302Y1041135D01*
X1494332D01*
X1494517Y1040535D01*
Y1040360D01*
X1493117D01*
Y1040535D01*
G37*
G36*
G01X1500517D02*
X1500702Y1041135D01*
X1501732D01*
X1501917Y1040535D01*
Y1040360D01*
X1500517D01*
Y1040535D01*
G37*
G36*
G01X1507903D02*
X1508088Y1041135D01*
X1509118D01*
X1509303Y1040535D01*
Y1040361D01*
X1507903D01*
Y1040535D01*
G37*
G36*
G01X1504170Y1040537D02*
X1504355Y1041137D01*
X1505385D01*
X1505570Y1040537D01*
Y1040362D01*
X1504170D01*
Y1040537D01*
G37*
G36*
G01X1496817Y1040535D02*
X1497002Y1041135D01*
X1498032D01*
X1498217Y1040535D01*
Y1040360D01*
X1496817D01*
Y1040535D01*
G37*
G36*
G01X1493117D02*
X1493302Y1041135D01*
X1494332D01*
X1494517Y1040535D01*
Y1040360D01*
X1493117D01*
Y1040535D01*
G37*
G36*
G01X1500517D02*
X1500702Y1041135D01*
X1501732D01*
X1501917Y1040535D01*
Y1040360D01*
X1500517D01*
Y1040535D01*
G37*
G36*
G01X1507903D02*
X1508088Y1041135D01*
X1509118D01*
X1509303Y1040535D01*
Y1040361D01*
X1507903D01*
Y1040535D01*
G37*
G36*
G01X1504170Y1040537D02*
X1504355Y1041137D01*
X1505385D01*
X1505570Y1040537D01*
Y1040362D01*
X1504170D01*
Y1040537D01*
G37*
G36*
G01X1494520Y1042145D02*
X1494335Y1041545D01*
X1493305D01*
X1493120Y1042145D01*
Y1042319D01*
X1494520D01*
Y1042145D01*
G37*
G36*
G01X1498220D02*
X1498035Y1041545D01*
X1497005D01*
X1496820Y1042145D01*
Y1042319D01*
X1498220D01*
Y1042145D01*
G37*
G36*
G01X1501920D02*
X1501735Y1041545D01*
X1500705D01*
X1500520Y1042145D01*
Y1042319D01*
X1501920D01*
Y1042145D01*
G37*
G36*
G01X1505620D02*
X1505435Y1041545D01*
X1504405D01*
X1504220Y1042145D01*
Y1042319D01*
X1505620D01*
Y1042145D01*
G37*
G36*
G01X1509270Y1042143D02*
X1509085Y1041543D01*
X1508055D01*
X1507870Y1042143D01*
Y1042318D01*
X1509270D01*
Y1042143D01*
G37*
G36*
G01X1494520Y1042145D02*
X1494335Y1041545D01*
X1493305D01*
X1493120Y1042145D01*
Y1042319D01*
X1494520D01*
Y1042145D01*
G37*
G36*
G01X1498220D02*
X1498035Y1041545D01*
X1497005D01*
X1496820Y1042145D01*
Y1042319D01*
X1498220D01*
Y1042145D01*
G37*
G36*
G01X1501920D02*
X1501735Y1041545D01*
X1500705D01*
X1500520Y1042145D01*
Y1042319D01*
X1501920D01*
Y1042145D01*
G37*
G36*
G01X1505620D02*
X1505435Y1041545D01*
X1504405D01*
X1504220Y1042145D01*
Y1042319D01*
X1505620D01*
Y1042145D01*
G37*
G36*
G01X1509270Y1042143D02*
X1509085Y1041543D01*
X1508055D01*
X1507870Y1042143D01*
Y1042318D01*
X1509270D01*
Y1042143D01*
G37*
G36*
G01X1496340Y1038941D02*
X1496155Y1038341D01*
X1495125D01*
X1494940Y1038941D01*
Y1039115D01*
X1496340D01*
Y1038941D01*
G37*
G36*
G01X1500040D02*
X1499855Y1038341D01*
X1498825D01*
X1498640Y1038941D01*
Y1039115D01*
X1500040D01*
Y1038941D01*
G37*
G36*
G01X1507477D02*
X1507292Y1038341D01*
X1506262D01*
X1506077Y1038941D01*
Y1039115D01*
X1507477D01*
Y1038941D01*
G37*
G36*
G01X1503787Y1038939D02*
X1503602Y1038339D01*
X1502572D01*
X1502387Y1038939D01*
Y1039114D01*
X1503787D01*
Y1038939D01*
G37*
G36*
G01X1496340Y1038941D02*
X1496155Y1038341D01*
X1495125D01*
X1494940Y1038941D01*
Y1039115D01*
X1496340D01*
Y1038941D01*
G37*
G36*
G01X1500040D02*
X1499855Y1038341D01*
X1498825D01*
X1498640Y1038941D01*
Y1039115D01*
X1500040D01*
Y1038941D01*
G37*
G36*
G01X1507477D02*
X1507292Y1038341D01*
X1506262D01*
X1506077Y1038941D01*
Y1039115D01*
X1507477D01*
Y1038941D01*
G37*
G36*
G01X1503787Y1038939D02*
X1503602Y1038339D01*
X1502572D01*
X1502387Y1038939D01*
Y1039114D01*
X1503787D01*
Y1038939D01*
G37*
G36*
G01X1498677Y1030923D02*
X1498862Y1031523D01*
X1499892D01*
X1500077Y1030923D01*
Y1030749D01*
X1498677D01*
Y1030923D01*
G37*
G36*
G01X1494977D02*
X1495162Y1031523D01*
X1496192D01*
X1496377Y1030923D01*
Y1030748D01*
X1494977D01*
Y1030923D01*
G37*
G36*
G01X1506077D02*
X1506262Y1031523D01*
X1507292D01*
X1507477Y1030923D01*
Y1030748D01*
X1506077D01*
Y1030923D01*
G37*
G36*
G01X1502387D02*
X1502572Y1031523D01*
X1503602D01*
X1503787Y1030923D01*
Y1030749D01*
X1502387D01*
Y1030923D01*
G37*
G36*
G01X1498677D02*
X1498862Y1031523D01*
X1499892D01*
X1500077Y1030923D01*
Y1030749D01*
X1498677D01*
Y1030923D01*
G37*
G36*
G01X1494977D02*
X1495162Y1031523D01*
X1496192D01*
X1496377Y1030923D01*
Y1030748D01*
X1494977D01*
Y1030923D01*
G37*
G36*
G01X1506077D02*
X1506262Y1031523D01*
X1507292D01*
X1507477Y1030923D01*
Y1030748D01*
X1506077D01*
Y1030923D01*
G37*
G36*
G01X1502387D02*
X1502572Y1031523D01*
X1503602D01*
X1503787Y1030923D01*
Y1030749D01*
X1502387D01*
Y1030923D01*
G37*
G36*
G01X1496817Y1046943D02*
X1497002Y1047543D01*
X1498032D01*
X1498217Y1046943D01*
Y1046769D01*
X1496817D01*
Y1046943D01*
G37*
G36*
G01X1493117D02*
X1493302Y1047543D01*
X1494332D01*
X1494517Y1046943D01*
Y1046769D01*
X1493117D01*
Y1046943D01*
G37*
G36*
G01X1500517D02*
X1500702Y1047543D01*
X1501732D01*
X1501917Y1046943D01*
Y1046769D01*
X1500517D01*
Y1046943D01*
G37*
G36*
G01X1507870Y1046945D02*
X1508055Y1047545D01*
X1509085D01*
X1509270Y1046945D01*
Y1046771D01*
X1507870D01*
Y1046945D01*
G37*
G36*
G01X1504217Y1046943D02*
X1504402Y1047543D01*
X1505432D01*
X1505617Y1046943D01*
Y1046769D01*
X1504217D01*
Y1046943D01*
G37*
G36*
G01X1496817D02*
X1497002Y1047543D01*
X1498032D01*
X1498217Y1046943D01*
Y1046769D01*
X1496817D01*
Y1046943D01*
G37*
G36*
G01X1493117D02*
X1493302Y1047543D01*
X1494332D01*
X1494517Y1046943D01*
Y1046769D01*
X1493117D01*
Y1046943D01*
G37*
G36*
G01X1500517D02*
X1500702Y1047543D01*
X1501732D01*
X1501917Y1046943D01*
Y1046769D01*
X1500517D01*
Y1046943D01*
G37*
G36*
G01X1507870Y1046945D02*
X1508055Y1047545D01*
X1509085D01*
X1509270Y1046945D01*
Y1046771D01*
X1507870D01*
Y1046945D01*
G37*
G36*
G01X1504217Y1046943D02*
X1504402Y1047543D01*
X1505432D01*
X1505617Y1046943D01*
Y1046769D01*
X1504217D01*
Y1046943D01*
G37*
G36*
G01X1500040Y1045349D02*
X1499855Y1044749D01*
X1498825D01*
X1498640Y1045349D01*
Y1045524D01*
X1500040D01*
Y1045349D01*
G37*
G36*
G01X1496340D02*
X1496155Y1044749D01*
X1495125D01*
X1494940Y1045349D01*
Y1045524D01*
X1496340D01*
Y1045349D01*
G37*
G36*
G01X1507440D02*
X1507255Y1044749D01*
X1506225D01*
X1506040Y1045349D01*
Y1045524D01*
X1507440D01*
Y1045349D01*
G37*
G36*
G01X1503740D02*
X1503555Y1044749D01*
X1502525D01*
X1502340Y1045349D01*
Y1045524D01*
X1503740D01*
Y1045349D01*
G37*
G36*
G01X1500040D02*
X1499855Y1044749D01*
X1498825D01*
X1498640Y1045349D01*
Y1045524D01*
X1500040D01*
Y1045349D01*
G37*
G36*
G01X1496340D02*
X1496155Y1044749D01*
X1495125D01*
X1494940Y1045349D01*
Y1045524D01*
X1496340D01*
Y1045349D01*
G37*
G36*
G01X1507440D02*
X1507255Y1044749D01*
X1506225D01*
X1506040Y1045349D01*
Y1045524D01*
X1507440D01*
Y1045349D01*
G37*
G36*
G01X1503740D02*
X1503555Y1044749D01*
X1502525D01*
X1502340Y1045349D01*
Y1045524D01*
X1503740D01*
Y1045349D01*
G37*
G36*
G01X1501870Y1035735D02*
X1501685Y1035135D01*
X1500655D01*
X1500470Y1035735D01*
Y1035909D01*
X1501870D01*
Y1035735D01*
G37*
G36*
G01X1498180D02*
X1497995Y1035135D01*
X1496965D01*
X1496780Y1035735D01*
Y1035910D01*
X1498180D01*
Y1035735D01*
G37*
G36*
G01X1494480D02*
X1494295Y1035135D01*
X1493265D01*
X1493080Y1035735D01*
Y1035909D01*
X1494480D01*
Y1035735D01*
G37*
G36*
G01X1509303D02*
X1509118Y1035135D01*
X1508088D01*
X1507903Y1035735D01*
Y1035910D01*
X1509303D01*
Y1035735D01*
G37*
G36*
G01X1505570D02*
X1505385Y1035135D01*
X1504355D01*
X1504170Y1035735D01*
Y1035909D01*
X1505570D01*
Y1035735D01*
G37*
G36*
G01X1501870D02*
X1501685Y1035135D01*
X1500655D01*
X1500470Y1035735D01*
Y1035909D01*
X1501870D01*
Y1035735D01*
G37*
G36*
G01X1498180D02*
X1497995Y1035135D01*
X1496965D01*
X1496780Y1035735D01*
Y1035910D01*
X1498180D01*
Y1035735D01*
G37*
G36*
G01X1494480D02*
X1494295Y1035135D01*
X1493265D01*
X1493080Y1035735D01*
Y1035909D01*
X1494480D01*
Y1035735D01*
G37*
G36*
G01X1509303D02*
X1509118Y1035135D01*
X1508088D01*
X1507903Y1035735D01*
Y1035910D01*
X1509303D01*
Y1035735D01*
G37*
G36*
G01X1505570D02*
X1505385Y1035135D01*
X1504355D01*
X1504170Y1035735D01*
Y1035909D01*
X1505570D01*
Y1035735D01*
G37*
G36*
G01X1500470Y1034127D02*
X1500655Y1034727D01*
X1501685D01*
X1501870Y1034127D01*
Y1033953D01*
X1500470D01*
Y1034127D01*
G37*
G36*
G01X1496827D02*
X1497012Y1034727D01*
X1498042D01*
X1498227Y1034127D01*
Y1033952D01*
X1496827D01*
Y1034127D01*
G37*
G36*
G01X1493080D02*
X1493265Y1034727D01*
X1494295D01*
X1494480Y1034127D01*
Y1033953D01*
X1493080D01*
Y1034127D01*
G37*
G36*
G01X1507903D02*
X1508088Y1034727D01*
X1509118D01*
X1509303Y1034127D01*
Y1033952D01*
X1507903D01*
Y1034127D01*
G37*
G36*
G01X1504170D02*
X1504355Y1034727D01*
X1505385D01*
X1505570Y1034127D01*
Y1033953D01*
X1504170D01*
Y1034127D01*
G37*
G36*
G01X1500470D02*
X1500655Y1034727D01*
X1501685D01*
X1501870Y1034127D01*
Y1033953D01*
X1500470D01*
Y1034127D01*
G37*
G36*
G01X1496827D02*
X1497012Y1034727D01*
X1498042D01*
X1498227Y1034127D01*
Y1033952D01*
X1496827D01*
Y1034127D01*
G37*
G36*
G01X1493080D02*
X1493265Y1034727D01*
X1494295D01*
X1494480Y1034127D01*
Y1033953D01*
X1493080D01*
Y1034127D01*
G37*
G36*
G01X1507903D02*
X1508088Y1034727D01*
X1509118D01*
X1509303Y1034127D01*
Y1033952D01*
X1507903D01*
Y1034127D01*
G37*
G36*
G01X1504170D02*
X1504355Y1034727D01*
X1505385D01*
X1505570Y1034127D01*
Y1033953D01*
X1504170D01*
Y1034127D01*
G37*
G36*
G01X1498687Y1037333D02*
X1498872Y1037933D01*
X1499902D01*
X1500087Y1037333D01*
Y1037158D01*
X1498687D01*
Y1037333D01*
G37*
G36*
G01X1494954Y1037331D02*
X1495139Y1037931D01*
X1496169D01*
X1496354Y1037331D01*
Y1037157D01*
X1494954D01*
Y1037331D01*
G37*
G36*
G01X1506077D02*
X1506262Y1037931D01*
X1507292D01*
X1507477Y1037331D01*
Y1037157D01*
X1506077D01*
Y1037331D01*
G37*
G36*
G01X1502387Y1037333D02*
X1502572Y1037933D01*
X1503602D01*
X1503787Y1037333D01*
Y1037158D01*
X1502387D01*
Y1037333D01*
G37*
G36*
G01X1498687D02*
X1498872Y1037933D01*
X1499902D01*
X1500087Y1037333D01*
Y1037158D01*
X1498687D01*
Y1037333D01*
G37*
G36*
G01X1494954Y1037331D02*
X1495139Y1037931D01*
X1496169D01*
X1496354Y1037331D01*
Y1037157D01*
X1494954D01*
Y1037331D01*
G37*
G36*
G01X1506077D02*
X1506262Y1037931D01*
X1507292D01*
X1507477Y1037331D01*
Y1037157D01*
X1506077D01*
Y1037331D01*
G37*
G36*
G01X1502387Y1037333D02*
X1502572Y1037933D01*
X1503602D01*
X1503787Y1037333D01*
Y1037158D01*
X1502387D01*
Y1037333D01*
G37*
G36*
G01X1500077Y1032531D02*
X1499892Y1031931D01*
X1498862D01*
X1498677Y1032531D01*
Y1032705D01*
X1500077D01*
Y1032531D01*
G37*
G36*
G01X1496330D02*
X1496145Y1031931D01*
X1495115D01*
X1494930Y1032531D01*
Y1032706D01*
X1496330D01*
Y1032531D01*
G37*
G36*
G01X1507477D02*
X1507292Y1031931D01*
X1506262D01*
X1506077Y1032531D01*
Y1032706D01*
X1507477D01*
Y1032531D01*
G37*
G36*
G01X1503787D02*
X1503602Y1031931D01*
X1502572D01*
X1502387Y1032531D01*
Y1032705D01*
X1503787D01*
Y1032531D01*
G37*
G36*
G01X1500077D02*
X1499892Y1031931D01*
X1498862D01*
X1498677Y1032531D01*
Y1032705D01*
X1500077D01*
Y1032531D01*
G37*
G36*
G01X1496330D02*
X1496145Y1031931D01*
X1495115D01*
X1494930Y1032531D01*
Y1032706D01*
X1496330D01*
Y1032531D01*
G37*
G36*
G01X1507477D02*
X1507292Y1031931D01*
X1506262D01*
X1506077Y1032531D01*
Y1032706D01*
X1507477D01*
Y1032531D01*
G37*
G36*
G01X1503787D02*
X1503602Y1031931D01*
X1502572D01*
X1502387Y1032531D01*
Y1032705D01*
X1503787D01*
Y1032531D01*
G37*
G36*
G01X1498630Y1062965D02*
X1498815Y1063565D01*
X1499845D01*
X1500030Y1062965D01*
Y1062791D01*
X1498630D01*
Y1062965D01*
G37*
G36*
G01X1494987Y1062967D02*
X1495172Y1063567D01*
X1496202D01*
X1496387Y1062967D01*
Y1062792D01*
X1494987D01*
Y1062967D01*
G37*
G36*
G01X1506087D02*
X1506272Y1063567D01*
X1507302D01*
X1507487Y1062967D01*
Y1062792D01*
X1506087D01*
Y1062967D01*
G37*
G36*
G01X1502377D02*
X1502562Y1063567D01*
X1503592D01*
X1503777Y1062967D01*
Y1062792D01*
X1502377D01*
Y1062967D01*
G37*
G36*
G01X1498630Y1062965D02*
X1498815Y1063565D01*
X1499845D01*
X1500030Y1062965D01*
Y1062791D01*
X1498630D01*
Y1062965D01*
G37*
G36*
G01X1494987Y1062967D02*
X1495172Y1063567D01*
X1496202D01*
X1496387Y1062967D01*
Y1062792D01*
X1494987D01*
Y1062967D01*
G37*
G36*
G01X1506087D02*
X1506272Y1063567D01*
X1507302D01*
X1507487Y1062967D01*
Y1062792D01*
X1506087D01*
Y1062967D01*
G37*
G36*
G01X1502377D02*
X1502562Y1063567D01*
X1503592D01*
X1503777Y1062967D01*
Y1062792D01*
X1502377D01*
Y1062967D01*
G37*
G36*
G01X1493117Y1059761D02*
X1493302Y1060361D01*
X1494332D01*
X1494517Y1059761D01*
Y1059586D01*
X1493117D01*
Y1059761D01*
G37*
G36*
G01X1496817D02*
X1497002Y1060361D01*
X1498032D01*
X1498217Y1059761D01*
Y1059586D01*
X1496817D01*
Y1059761D01*
G37*
G36*
G01X1500480D02*
X1500665Y1060361D01*
X1501695D01*
X1501880Y1059761D01*
Y1059586D01*
X1500480D01*
Y1059761D01*
G37*
G36*
G01X1504170D02*
X1504355Y1060361D01*
X1505385D01*
X1505570Y1059761D01*
Y1059587D01*
X1504170D01*
Y1059761D01*
G37*
G36*
G01X1507870D02*
X1508055Y1060361D01*
X1509085D01*
X1509270Y1059761D01*
Y1059587D01*
X1507870D01*
Y1059761D01*
G37*
G36*
G01X1493117D02*
X1493302Y1060361D01*
X1494332D01*
X1494517Y1059761D01*
Y1059586D01*
X1493117D01*
Y1059761D01*
G37*
G36*
G01X1496817D02*
X1497002Y1060361D01*
X1498032D01*
X1498217Y1059761D01*
Y1059586D01*
X1496817D01*
Y1059761D01*
G37*
G36*
G01X1500480D02*
X1500665Y1060361D01*
X1501695D01*
X1501880Y1059761D01*
Y1059586D01*
X1500480D01*
Y1059761D01*
G37*
G36*
G01X1504170D02*
X1504355Y1060361D01*
X1505385D01*
X1505570Y1059761D01*
Y1059587D01*
X1504170D01*
Y1059761D01*
G37*
G36*
G01X1507870D02*
X1508055Y1060361D01*
X1509085D01*
X1509270Y1059761D01*
Y1059587D01*
X1507870D01*
Y1059761D01*
G37*
G36*
G01X1501927Y1061369D02*
X1501742Y1060769D01*
X1500712D01*
X1500527Y1061369D01*
Y1061544D01*
X1501927D01*
Y1061369D01*
G37*
G36*
G01X1498180D02*
X1497995Y1060769D01*
X1496965D01*
X1496780Y1061369D01*
Y1061543D01*
X1498180D01*
Y1061369D01*
G37*
G36*
G01X1494470D02*
X1494285Y1060769D01*
X1493255D01*
X1493070Y1061369D01*
Y1061543D01*
X1494470D01*
Y1061369D01*
G37*
G36*
G01X1509270D02*
X1509085Y1060769D01*
X1508055D01*
X1507870Y1061369D01*
Y1061543D01*
X1509270D01*
Y1061369D01*
G37*
G36*
G01X1505570D02*
X1505385Y1060769D01*
X1504355D01*
X1504170Y1061369D01*
Y1061543D01*
X1505570D01*
Y1061369D01*
G37*
G36*
G01X1501927D02*
X1501742Y1060769D01*
X1500712D01*
X1500527Y1061369D01*
Y1061544D01*
X1501927D01*
Y1061369D01*
G37*
G36*
G01X1498180D02*
X1497995Y1060769D01*
X1496965D01*
X1496780Y1061369D01*
Y1061543D01*
X1498180D01*
Y1061369D01*
G37*
G36*
G01X1494470D02*
X1494285Y1060769D01*
X1493255D01*
X1493070Y1061369D01*
Y1061543D01*
X1494470D01*
Y1061369D01*
G37*
G36*
G01X1509270D02*
X1509085Y1060769D01*
X1508055D01*
X1507870Y1061369D01*
Y1061543D01*
X1509270D01*
Y1061369D01*
G37*
G36*
G01X1505570D02*
X1505385Y1060769D01*
X1504355D01*
X1504170Y1061369D01*
Y1061543D01*
X1505570D01*
Y1061369D01*
G37*
G36*
G01X1500054Y1058165D02*
X1499869Y1057565D01*
X1498839D01*
X1498654Y1058165D01*
Y1058340D01*
X1500054D01*
Y1058165D01*
G37*
G36*
G01X1496387D02*
X1496202Y1057565D01*
X1495172D01*
X1494987Y1058165D01*
Y1058339D01*
X1496387D01*
Y1058165D01*
G37*
G36*
G01X1503787D02*
X1503602Y1057565D01*
X1502572D01*
X1502387Y1058165D01*
Y1058339D01*
X1503787D01*
Y1058165D01*
G37*
G36*
G01X1507487D02*
X1507302Y1057565D01*
X1506272D01*
X1506087Y1058165D01*
Y1058339D01*
X1507487D01*
Y1058165D01*
G37*
G36*
G01X1500054D02*
X1499869Y1057565D01*
X1498839D01*
X1498654Y1058165D01*
Y1058340D01*
X1500054D01*
Y1058165D01*
G37*
G36*
G01X1496387D02*
X1496202Y1057565D01*
X1495172D01*
X1494987Y1058165D01*
Y1058339D01*
X1496387D01*
Y1058165D01*
G37*
G36*
G01X1503787D02*
X1503602Y1057565D01*
X1502572D01*
X1502387Y1058165D01*
Y1058339D01*
X1503787D01*
Y1058165D01*
G37*
G36*
G01X1507487D02*
X1507302Y1057565D01*
X1506272D01*
X1506087Y1058165D01*
Y1058339D01*
X1507487D01*
Y1058165D01*
G37*
G36*
G01X1494940Y1050149D02*
X1495125Y1050749D01*
X1496155D01*
X1496340Y1050149D01*
Y1049974D01*
X1494940D01*
Y1050149D01*
G37*
G36*
G01X1498640D02*
X1498825Y1050749D01*
X1499855D01*
X1500040Y1050149D01*
Y1049974D01*
X1498640D01*
Y1050149D01*
G37*
G36*
G01X1506040D02*
X1506225Y1050749D01*
X1507255D01*
X1507440Y1050149D01*
Y1049974D01*
X1506040D01*
Y1050149D01*
G37*
G36*
G01X1502340D02*
X1502525Y1050749D01*
X1503555D01*
X1503740Y1050149D01*
Y1049974D01*
X1502340D01*
Y1050149D01*
G37*
G36*
G01X1494940D02*
X1495125Y1050749D01*
X1496155D01*
X1496340Y1050149D01*
Y1049974D01*
X1494940D01*
Y1050149D01*
G37*
G36*
G01X1498640D02*
X1498825Y1050749D01*
X1499855D01*
X1500040Y1050149D01*
Y1049974D01*
X1498640D01*
Y1050149D01*
G37*
G36*
G01X1506040D02*
X1506225Y1050749D01*
X1507255D01*
X1507440Y1050149D01*
Y1049974D01*
X1506040D01*
Y1050149D01*
G37*
G36*
G01X1502340D02*
X1502525Y1050749D01*
X1503555D01*
X1503740Y1050149D01*
Y1049974D01*
X1502340D01*
Y1050149D01*
G37*
G36*
G01X1501917Y1048553D02*
X1501732Y1047953D01*
X1500702D01*
X1500517Y1048553D01*
Y1048727D01*
X1501917D01*
Y1048553D01*
G37*
G36*
G01X1498217D02*
X1498032Y1047953D01*
X1497002D01*
X1496817Y1048553D01*
Y1048727D01*
X1498217D01*
Y1048553D01*
G37*
G36*
G01X1494517D02*
X1494332Y1047953D01*
X1493302D01*
X1493117Y1048553D01*
Y1048727D01*
X1494517D01*
Y1048553D01*
G37*
G36*
G01X1509270Y1048551D02*
X1509085Y1047951D01*
X1508055D01*
X1507870Y1048551D01*
Y1048726D01*
X1509270D01*
Y1048551D01*
G37*
G36*
G01X1505617Y1048553D02*
X1505432Y1047953D01*
X1504402D01*
X1504217Y1048553D01*
Y1048727D01*
X1505617D01*
Y1048553D01*
G37*
G36*
G01X1501917D02*
X1501732Y1047953D01*
X1500702D01*
X1500517Y1048553D01*
Y1048727D01*
X1501917D01*
Y1048553D01*
G37*
G36*
G01X1498217D02*
X1498032Y1047953D01*
X1497002D01*
X1496817Y1048553D01*
Y1048727D01*
X1498217D01*
Y1048553D01*
G37*
G36*
G01X1494517D02*
X1494332Y1047953D01*
X1493302D01*
X1493117Y1048553D01*
Y1048727D01*
X1494517D01*
Y1048553D01*
G37*
G36*
G01X1509270Y1048551D02*
X1509085Y1047951D01*
X1508055D01*
X1507870Y1048551D01*
Y1048726D01*
X1509270D01*
Y1048551D01*
G37*
G36*
G01X1505617Y1048553D02*
X1505432Y1047953D01*
X1504402D01*
X1504217Y1048553D01*
Y1048727D01*
X1505617D01*
Y1048553D01*
G37*
G36*
G01X1501870Y1054961D02*
X1501685Y1054361D01*
X1500655D01*
X1500470Y1054961D01*
Y1055135D01*
X1501870D01*
Y1054961D01*
G37*
G36*
G01X1498180D02*
X1497995Y1054361D01*
X1496965D01*
X1496780Y1054961D01*
Y1055136D01*
X1498180D01*
Y1054961D01*
G37*
G36*
G01X1494480D02*
X1494295Y1054361D01*
X1493265D01*
X1493080Y1054961D01*
Y1055135D01*
X1494480D01*
Y1054961D01*
G37*
G36*
G01X1509270D02*
X1509085Y1054361D01*
X1508055D01*
X1507870Y1054961D01*
Y1055135D01*
X1509270D01*
Y1054961D01*
G37*
G36*
G01X1505570D02*
X1505385Y1054361D01*
X1504355D01*
X1504170Y1054961D01*
Y1055135D01*
X1505570D01*
Y1054961D01*
G37*
G36*
G01X1501870D02*
X1501685Y1054361D01*
X1500655D01*
X1500470Y1054961D01*
Y1055135D01*
X1501870D01*
Y1054961D01*
G37*
G36*
G01X1498180D02*
X1497995Y1054361D01*
X1496965D01*
X1496780Y1054961D01*
Y1055136D01*
X1498180D01*
Y1054961D01*
G37*
G36*
G01X1494480D02*
X1494295Y1054361D01*
X1493265D01*
X1493080Y1054961D01*
Y1055135D01*
X1494480D01*
Y1054961D01*
G37*
G36*
G01X1509270D02*
X1509085Y1054361D01*
X1508055D01*
X1507870Y1054961D01*
Y1055135D01*
X1509270D01*
Y1054961D01*
G37*
G36*
G01X1505570D02*
X1505385Y1054361D01*
X1504355D01*
X1504170Y1054961D01*
Y1055135D01*
X1505570D01*
Y1054961D01*
G37*
G36*
G01X1500470Y1053353D02*
X1500655Y1053953D01*
X1501685D01*
X1501870Y1053353D01*
Y1053179D01*
X1500470D01*
Y1053353D01*
G37*
G36*
G01X1496827D02*
X1497012Y1053953D01*
X1498042D01*
X1498227Y1053353D01*
Y1053178D01*
X1496827D01*
Y1053353D01*
G37*
G36*
G01X1493080D02*
X1493265Y1053953D01*
X1494295D01*
X1494480Y1053353D01*
Y1053179D01*
X1493080D01*
Y1053353D01*
G37*
G36*
G01X1504170D02*
X1504355Y1053953D01*
X1505385D01*
X1505570Y1053353D01*
Y1053179D01*
X1504170D01*
Y1053353D01*
G37*
G36*
G01X1507870D02*
X1508055Y1053953D01*
X1509085D01*
X1509270Y1053353D01*
Y1053179D01*
X1507870D01*
Y1053353D01*
G37*
G36*
G01X1500470D02*
X1500655Y1053953D01*
X1501685D01*
X1501870Y1053353D01*
Y1053179D01*
X1500470D01*
Y1053353D01*
G37*
G36*
G01X1496827D02*
X1497012Y1053953D01*
X1498042D01*
X1498227Y1053353D01*
Y1053178D01*
X1496827D01*
Y1053353D01*
G37*
G36*
G01X1493080D02*
X1493265Y1053953D01*
X1494295D01*
X1494480Y1053353D01*
Y1053179D01*
X1493080D01*
Y1053353D01*
G37*
G36*
G01X1504170D02*
X1504355Y1053953D01*
X1505385D01*
X1505570Y1053353D01*
Y1053179D01*
X1504170D01*
Y1053353D01*
G37*
G36*
G01X1507870D02*
X1508055Y1053953D01*
X1509085D01*
X1509270Y1053353D01*
Y1053179D01*
X1507870D01*
Y1053353D01*
G37*
G36*
G01X1498687Y1056557D02*
X1498872Y1057157D01*
X1499902D01*
X1500087Y1056557D01*
Y1056383D01*
X1498687D01*
Y1056557D01*
G37*
G36*
G01X1494954D02*
X1495139Y1057157D01*
X1496169D01*
X1496354Y1056557D01*
Y1056382D01*
X1494954D01*
Y1056557D01*
G37*
G36*
G01X1506087D02*
X1506272Y1057157D01*
X1507302D01*
X1507487Y1056557D01*
Y1056383D01*
X1506087D01*
Y1056557D01*
G37*
G36*
G01X1502387D02*
X1502572Y1057157D01*
X1503602D01*
X1503787Y1056557D01*
Y1056383D01*
X1502387D01*
Y1056557D01*
G37*
G36*
G01X1498687D02*
X1498872Y1057157D01*
X1499902D01*
X1500087Y1056557D01*
Y1056383D01*
X1498687D01*
Y1056557D01*
G37*
G36*
G01X1494954D02*
X1495139Y1057157D01*
X1496169D01*
X1496354Y1056557D01*
Y1056382D01*
X1494954D01*
Y1056557D01*
G37*
G36*
G01X1506087D02*
X1506272Y1057157D01*
X1507302D01*
X1507487Y1056557D01*
Y1056383D01*
X1506087D01*
Y1056557D01*
G37*
G36*
G01X1502387D02*
X1502572Y1057157D01*
X1503602D01*
X1503787Y1056557D01*
Y1056383D01*
X1502387D01*
Y1056557D01*
G37*
G36*
G01X1496330Y1051757D02*
X1496145Y1051157D01*
X1495115D01*
X1494930Y1051757D01*
Y1051932D01*
X1496330D01*
Y1051757D01*
G37*
G36*
G01X1500077D02*
X1499892Y1051157D01*
X1498862D01*
X1498677Y1051757D01*
Y1051931D01*
X1500077D01*
Y1051757D01*
G37*
G36*
G01X1507487Y1051755D02*
X1507302Y1051155D01*
X1506272D01*
X1506087Y1051755D01*
Y1051930D01*
X1507487D01*
Y1051755D01*
G37*
G36*
G01X1503787Y1051757D02*
X1503602Y1051157D01*
X1502572D01*
X1502387Y1051757D01*
Y1051931D01*
X1503787D01*
Y1051757D01*
G37*
G36*
G01X1496330D02*
X1496145Y1051157D01*
X1495115D01*
X1494930Y1051757D01*
Y1051932D01*
X1496330D01*
Y1051757D01*
G37*
G36*
G01X1500077D02*
X1499892Y1051157D01*
X1498862D01*
X1498677Y1051757D01*
Y1051931D01*
X1500077D01*
Y1051757D01*
G37*
G36*
G01X1507487Y1051755D02*
X1507302Y1051155D01*
X1506272D01*
X1506087Y1051755D01*
Y1051930D01*
X1507487D01*
Y1051755D01*
G37*
G36*
G01X1503787Y1051757D02*
X1503602Y1051157D01*
X1502572D01*
X1502387Y1051757D01*
Y1051931D01*
X1503787D01*
Y1051757D01*
G37*
G36*
G01X1500054Y1077391D02*
X1499869Y1076791D01*
X1498839D01*
X1498654Y1077391D01*
Y1077566D01*
X1500054D01*
Y1077391D01*
G37*
G36*
G01X1496387D02*
X1496202Y1076791D01*
X1495172D01*
X1494987Y1077391D01*
Y1077565D01*
X1496387D01*
Y1077391D01*
G37*
G36*
G01X1507487D02*
X1507302Y1076791D01*
X1506272D01*
X1506087Y1077391D01*
Y1077565D01*
X1507487D01*
Y1077391D01*
G37*
G36*
G01X1503787D02*
X1503602Y1076791D01*
X1502572D01*
X1502387Y1077391D01*
Y1077565D01*
X1503787D01*
Y1077391D01*
G37*
G36*
G01X1500054D02*
X1499869Y1076791D01*
X1498839D01*
X1498654Y1077391D01*
Y1077566D01*
X1500054D01*
Y1077391D01*
G37*
G36*
G01X1496387D02*
X1496202Y1076791D01*
X1495172D01*
X1494987Y1077391D01*
Y1077565D01*
X1496387D01*
Y1077391D01*
G37*
G36*
G01X1507487D02*
X1507302Y1076791D01*
X1506272D01*
X1506087Y1077391D01*
Y1077565D01*
X1507487D01*
Y1077391D01*
G37*
G36*
G01X1503787D02*
X1503602Y1076791D01*
X1502572D01*
X1502387Y1077391D01*
Y1077565D01*
X1503787D01*
Y1077391D01*
G37*
G36*
G01X1498640Y1069375D02*
X1498825Y1069975D01*
X1499855D01*
X1500040Y1069375D01*
Y1069200D01*
X1498640D01*
Y1069375D01*
G37*
G36*
G01X1494940D02*
X1495125Y1069975D01*
X1496155D01*
X1496340Y1069375D01*
Y1069200D01*
X1494940D01*
Y1069375D01*
G37*
G36*
G01X1502340D02*
X1502525Y1069975D01*
X1503555D01*
X1503740Y1069375D01*
Y1069200D01*
X1502340D01*
Y1069375D01*
G37*
G36*
G01X1506040D02*
X1506225Y1069975D01*
X1507255D01*
X1507440Y1069375D01*
Y1069200D01*
X1506040D01*
Y1069375D01*
G37*
G36*
G01X1498640D02*
X1498825Y1069975D01*
X1499855D01*
X1500040Y1069375D01*
Y1069200D01*
X1498640D01*
Y1069375D01*
G37*
G36*
G01X1494940D02*
X1495125Y1069975D01*
X1496155D01*
X1496340Y1069375D01*
Y1069200D01*
X1494940D01*
Y1069375D01*
G37*
G36*
G01X1502340D02*
X1502525Y1069975D01*
X1503555D01*
X1503740Y1069375D01*
Y1069200D01*
X1502340D01*
Y1069375D01*
G37*
G36*
G01X1506040D02*
X1506225Y1069975D01*
X1507255D01*
X1507440Y1069375D01*
Y1069200D01*
X1506040D01*
Y1069375D01*
G37*
G36*
G01X1500503Y1066169D02*
X1500688Y1066769D01*
X1501718D01*
X1501903Y1066169D01*
Y1065995D01*
X1500503D01*
Y1066169D01*
G37*
G36*
G01X1496770Y1066171D02*
X1496955Y1066771D01*
X1497985D01*
X1498170Y1066171D01*
Y1065996D01*
X1496770D01*
Y1066171D01*
G37*
G36*
G01X1493070D02*
X1493255Y1066771D01*
X1494285D01*
X1494470Y1066171D01*
Y1065996D01*
X1493070D01*
Y1066171D01*
G37*
G36*
G01X1504170D02*
X1504355Y1066771D01*
X1505385D01*
X1505570Y1066171D01*
Y1065996D01*
X1504170D01*
Y1066171D01*
G37*
G36*
G01X1507870D02*
X1508055Y1066771D01*
X1509085D01*
X1509270Y1066171D01*
Y1065996D01*
X1507870D01*
Y1066171D01*
G37*
G36*
G01X1500503Y1066169D02*
X1500688Y1066769D01*
X1501718D01*
X1501903Y1066169D01*
Y1065995D01*
X1500503D01*
Y1066169D01*
G37*
G36*
G01X1496770Y1066171D02*
X1496955Y1066771D01*
X1497985D01*
X1498170Y1066171D01*
Y1065996D01*
X1496770D01*
Y1066171D01*
G37*
G36*
G01X1493070D02*
X1493255Y1066771D01*
X1494285D01*
X1494470Y1066171D01*
Y1065996D01*
X1493070D01*
Y1066171D01*
G37*
G36*
G01X1504170D02*
X1504355Y1066771D01*
X1505385D01*
X1505570Y1066171D01*
Y1065996D01*
X1504170D01*
Y1066171D01*
G37*
G36*
G01X1507870D02*
X1508055Y1066771D01*
X1509085D01*
X1509270Y1066171D01*
Y1065996D01*
X1507870D01*
Y1066171D01*
G37*
G36*
G01X1501917Y1067779D02*
X1501732Y1067179D01*
X1500702D01*
X1500517Y1067779D01*
Y1067953D01*
X1501917D01*
Y1067779D01*
G37*
G36*
G01X1498217D02*
X1498032Y1067179D01*
X1497002D01*
X1496817Y1067779D01*
Y1067953D01*
X1498217D01*
Y1067779D01*
G37*
G36*
G01X1494517D02*
X1494332Y1067179D01*
X1493302D01*
X1493117Y1067779D01*
Y1067953D01*
X1494517D01*
Y1067779D01*
G37*
G36*
G01X1509312D02*
X1509127Y1067179D01*
X1508097D01*
X1507912Y1067779D01*
Y1067954D01*
X1509312D01*
Y1067779D01*
G37*
G36*
G01X1505617D02*
X1505432Y1067179D01*
X1504402D01*
X1504217Y1067779D01*
Y1067953D01*
X1505617D01*
Y1067779D01*
G37*
G36*
G01X1501917D02*
X1501732Y1067179D01*
X1500702D01*
X1500517Y1067779D01*
Y1067953D01*
X1501917D01*
Y1067779D01*
G37*
G36*
G01X1498217D02*
X1498032Y1067179D01*
X1497002D01*
X1496817Y1067779D01*
Y1067953D01*
X1498217D01*
Y1067779D01*
G37*
G36*
G01X1494517D02*
X1494332Y1067179D01*
X1493302D01*
X1493117Y1067779D01*
Y1067953D01*
X1494517D01*
Y1067779D01*
G37*
G36*
G01X1509312D02*
X1509127Y1067179D01*
X1508097D01*
X1507912Y1067779D01*
Y1067954D01*
X1509312D01*
Y1067779D01*
G37*
G36*
G01X1505617D02*
X1505432Y1067179D01*
X1504402D01*
X1504217Y1067779D01*
Y1067953D01*
X1505617D01*
Y1067779D01*
G37*
G36*
G01X1500077Y1064575D02*
X1499892Y1063975D01*
X1498862D01*
X1498677Y1064575D01*
Y1064749D01*
X1500077D01*
Y1064575D01*
G37*
G36*
G01X1496387Y1064573D02*
X1496202Y1063973D01*
X1495172D01*
X1494987Y1064573D01*
Y1064748D01*
X1496387D01*
Y1064573D01*
G37*
G36*
G01X1507487D02*
X1507302Y1063973D01*
X1506272D01*
X1506087Y1064573D01*
Y1064748D01*
X1507487D01*
Y1064573D01*
G37*
G36*
G01X1503777D02*
X1503592Y1063973D01*
X1502562D01*
X1502377Y1064573D01*
Y1064748D01*
X1503777D01*
Y1064573D01*
G37*
G36*
G01X1500077Y1064575D02*
X1499892Y1063975D01*
X1498862D01*
X1498677Y1064575D01*
Y1064749D01*
X1500077D01*
Y1064575D01*
G37*
G36*
G01X1496387Y1064573D02*
X1496202Y1063973D01*
X1495172D01*
X1494987Y1064573D01*
Y1064748D01*
X1496387D01*
Y1064573D01*
G37*
G36*
G01X1507487D02*
X1507302Y1063973D01*
X1506272D01*
X1506087Y1064573D01*
Y1064748D01*
X1507487D01*
Y1064573D01*
G37*
G36*
G01X1503777D02*
X1503592Y1063973D01*
X1502562D01*
X1502377Y1064573D01*
Y1064748D01*
X1503777D01*
Y1064573D01*
G37*
G36*
G01X1500480Y1078987D02*
X1500665Y1079587D01*
X1501695D01*
X1501880Y1078987D01*
Y1078812D01*
X1500480D01*
Y1078987D01*
G37*
G36*
G01X1496780D02*
X1496965Y1079587D01*
X1497995D01*
X1498180Y1078987D01*
Y1078813D01*
X1496780D01*
Y1078987D01*
G37*
G36*
G01X1493070D02*
X1493255Y1079587D01*
X1494285D01*
X1494470Y1078987D01*
Y1078813D01*
X1493070D01*
Y1078987D01*
G37*
G36*
G01X1507870D02*
X1508055Y1079587D01*
X1509085D01*
X1509270Y1078987D01*
Y1078813D01*
X1507870D01*
Y1078987D01*
G37*
G36*
G01X1504170D02*
X1504355Y1079587D01*
X1505385D01*
X1505570Y1078987D01*
Y1078813D01*
X1504170D01*
Y1078987D01*
G37*
G36*
G01X1500480D02*
X1500665Y1079587D01*
X1501695D01*
X1501880Y1078987D01*
Y1078812D01*
X1500480D01*
Y1078987D01*
G37*
G36*
G01X1496780D02*
X1496965Y1079587D01*
X1497995D01*
X1498180Y1078987D01*
Y1078813D01*
X1496780D01*
Y1078987D01*
G37*
G36*
G01X1493070D02*
X1493255Y1079587D01*
X1494285D01*
X1494470Y1078987D01*
Y1078813D01*
X1493070D01*
Y1078987D01*
G37*
G36*
G01X1507870D02*
X1508055Y1079587D01*
X1509085D01*
X1509270Y1078987D01*
Y1078813D01*
X1507870D01*
Y1078987D01*
G37*
G36*
G01X1504170D02*
X1504355Y1079587D01*
X1505385D01*
X1505570Y1078987D01*
Y1078813D01*
X1504170D01*
Y1078987D01*
G37*
G36*
G01X1498180Y1074187D02*
X1497995Y1073587D01*
X1496965D01*
X1496780Y1074187D01*
Y1074362D01*
X1498180D01*
Y1074187D01*
G37*
G36*
G01X1501870D02*
X1501685Y1073587D01*
X1500655D01*
X1500470Y1074187D01*
Y1074361D01*
X1501870D01*
Y1074187D01*
G37*
G36*
G01X1494480D02*
X1494295Y1073587D01*
X1493265D01*
X1493080Y1074187D01*
Y1074361D01*
X1494480D01*
Y1074187D01*
G37*
G36*
G01X1509270D02*
X1509085Y1073587D01*
X1508055D01*
X1507870Y1074187D01*
Y1074361D01*
X1509270D01*
Y1074187D01*
G37*
G36*
G01X1505570D02*
X1505385Y1073587D01*
X1504355D01*
X1504170Y1074187D01*
Y1074361D01*
X1505570D01*
Y1074187D01*
G37*
G36*
G01X1498180D02*
X1497995Y1073587D01*
X1496965D01*
X1496780Y1074187D01*
Y1074362D01*
X1498180D01*
Y1074187D01*
G37*
G36*
G01X1501870D02*
X1501685Y1073587D01*
X1500655D01*
X1500470Y1074187D01*
Y1074361D01*
X1501870D01*
Y1074187D01*
G37*
G36*
G01X1494480D02*
X1494295Y1073587D01*
X1493265D01*
X1493080Y1074187D01*
Y1074361D01*
X1494480D01*
Y1074187D01*
G37*
G36*
G01X1509270D02*
X1509085Y1073587D01*
X1508055D01*
X1507870Y1074187D01*
Y1074361D01*
X1509270D01*
Y1074187D01*
G37*
G36*
G01X1505570D02*
X1505385Y1073587D01*
X1504355D01*
X1504170Y1074187D01*
Y1074361D01*
X1505570D01*
Y1074187D01*
G37*
G36*
G01X1496827Y1072579D02*
X1497012Y1073179D01*
X1498042D01*
X1498227Y1072579D01*
Y1072404D01*
X1496827D01*
Y1072579D01*
G37*
G36*
G01X1493080D02*
X1493265Y1073179D01*
X1494295D01*
X1494480Y1072579D01*
Y1072405D01*
X1493080D01*
Y1072579D01*
G37*
G36*
G01X1500470D02*
X1500655Y1073179D01*
X1501685D01*
X1501870Y1072579D01*
Y1072405D01*
X1500470D01*
Y1072579D01*
G37*
G36*
G01X1507870D02*
X1508055Y1073179D01*
X1509085D01*
X1509270Y1072579D01*
Y1072405D01*
X1507870D01*
Y1072579D01*
G37*
G36*
G01X1504170D02*
X1504355Y1073179D01*
X1505385D01*
X1505570Y1072579D01*
Y1072405D01*
X1504170D01*
Y1072579D01*
G37*
G36*
G01X1496827D02*
X1497012Y1073179D01*
X1498042D01*
X1498227Y1072579D01*
Y1072404D01*
X1496827D01*
Y1072579D01*
G37*
G36*
G01X1493080D02*
X1493265Y1073179D01*
X1494295D01*
X1494480Y1072579D01*
Y1072405D01*
X1493080D01*
Y1072579D01*
G37*
G36*
G01X1500470D02*
X1500655Y1073179D01*
X1501685D01*
X1501870Y1072579D01*
Y1072405D01*
X1500470D01*
Y1072579D01*
G37*
G36*
G01X1507870D02*
X1508055Y1073179D01*
X1509085D01*
X1509270Y1072579D01*
Y1072405D01*
X1507870D01*
Y1072579D01*
G37*
G36*
G01X1504170D02*
X1504355Y1073179D01*
X1505385D01*
X1505570Y1072579D01*
Y1072405D01*
X1504170D01*
Y1072579D01*
G37*
G36*
G01X1494954Y1075783D02*
X1495139Y1076383D01*
X1496169D01*
X1496354Y1075783D01*
Y1075608D01*
X1494954D01*
Y1075783D01*
G37*
G36*
G01X1498687D02*
X1498872Y1076383D01*
X1499902D01*
X1500087Y1075783D01*
Y1075609D01*
X1498687D01*
Y1075783D01*
G37*
G36*
G01X1506087D02*
X1506272Y1076383D01*
X1507302D01*
X1507487Y1075783D01*
Y1075609D01*
X1506087D01*
Y1075783D01*
G37*
G36*
G01X1502387D02*
X1502572Y1076383D01*
X1503602D01*
X1503787Y1075783D01*
Y1075609D01*
X1502387D01*
Y1075783D01*
G37*
G36*
G01X1494954D02*
X1495139Y1076383D01*
X1496169D01*
X1496354Y1075783D01*
Y1075608D01*
X1494954D01*
Y1075783D01*
G37*
G36*
G01X1498687D02*
X1498872Y1076383D01*
X1499902D01*
X1500087Y1075783D01*
Y1075609D01*
X1498687D01*
Y1075783D01*
G37*
G36*
G01X1506087D02*
X1506272Y1076383D01*
X1507302D01*
X1507487Y1075783D01*
Y1075609D01*
X1506087D01*
Y1075783D01*
G37*
G36*
G01X1502387D02*
X1502572Y1076383D01*
X1503602D01*
X1503787Y1075783D01*
Y1075609D01*
X1502387D01*
Y1075783D01*
G37*
G36*
G01X1500077Y1070981D02*
X1499892Y1070381D01*
X1498862D01*
X1498677Y1070981D01*
Y1071156D01*
X1500077D01*
Y1070981D01*
G37*
G36*
G01X1496330Y1070983D02*
X1496145Y1070383D01*
X1495115D01*
X1494930Y1070983D01*
Y1071157D01*
X1496330D01*
Y1070983D01*
G37*
G36*
G01X1507487Y1070981D02*
X1507302Y1070381D01*
X1506272D01*
X1506087Y1070981D01*
Y1071156D01*
X1507487D01*
Y1070981D01*
G37*
G36*
G01X1503787D02*
X1503602Y1070381D01*
X1502572D01*
X1502387Y1070981D01*
Y1071156D01*
X1503787D01*
Y1070981D01*
G37*
G36*
G01X1500077D02*
X1499892Y1070381D01*
X1498862D01*
X1498677Y1070981D01*
Y1071156D01*
X1500077D01*
Y1070981D01*
G37*
G36*
G01X1496330Y1070983D02*
X1496145Y1070383D01*
X1495115D01*
X1494930Y1070983D01*
Y1071157D01*
X1496330D01*
Y1070983D01*
G37*
G36*
G01X1507487Y1070981D02*
X1507302Y1070381D01*
X1506272D01*
X1506087Y1070981D01*
Y1071156D01*
X1507487D01*
Y1070981D01*
G37*
G36*
G01X1503787D02*
X1503602Y1070381D01*
X1502572D01*
X1502387Y1070981D01*
Y1071156D01*
X1503787D01*
Y1070981D01*
G37*
G36*
G01X1494470Y1080595D02*
X1494285Y1079995D01*
X1493255D01*
X1493070Y1080595D01*
Y1080769D01*
X1494470D01*
Y1080595D01*
G37*
G36*
G01X1498180D02*
X1497995Y1079995D01*
X1496965D01*
X1496780Y1080595D01*
Y1080769D01*
X1498180D01*
Y1080595D01*
G37*
G36*
G01X1501927D02*
X1501742Y1079995D01*
X1500712D01*
X1500527Y1080595D01*
Y1080770D01*
X1501927D01*
Y1080595D01*
G37*
G36*
G01X1509270D02*
X1509085Y1079995D01*
X1508055D01*
X1507870Y1080595D01*
Y1080769D01*
X1509270D01*
Y1080595D01*
G37*
G36*
G01X1505570D02*
X1505385Y1079995D01*
X1504355D01*
X1504170Y1080595D01*
Y1080769D01*
X1505570D01*
Y1080595D01*
G37*
G36*
G01X1494470D02*
X1494285Y1079995D01*
X1493255D01*
X1493070Y1080595D01*
Y1080769D01*
X1494470D01*
Y1080595D01*
G37*
G36*
G01X1498180D02*
X1497995Y1079995D01*
X1496965D01*
X1496780Y1080595D01*
Y1080769D01*
X1498180D01*
Y1080595D01*
G37*
G36*
G01X1501927D02*
X1501742Y1079995D01*
X1500712D01*
X1500527Y1080595D01*
Y1080770D01*
X1501927D01*
Y1080595D01*
G37*
G36*
G01X1509270D02*
X1509085Y1079995D01*
X1508055D01*
X1507870Y1080595D01*
Y1080769D01*
X1509270D01*
Y1080595D01*
G37*
G36*
G01X1505570D02*
X1505385Y1079995D01*
X1504355D01*
X1504170Y1080595D01*
Y1080769D01*
X1505570D01*
Y1080595D01*
G37*
G36*
G01X1498630Y1082191D02*
X1498815Y1082791D01*
X1499845D01*
X1500030Y1082191D01*
Y1082016D01*
X1498630D01*
Y1082191D01*
G37*
G36*
G01X1494987D02*
X1495172Y1082791D01*
X1496202D01*
X1496387Y1082191D01*
Y1082017D01*
X1494987D01*
Y1082191D01*
G37*
G36*
G01X1502377D02*
X1502562Y1082791D01*
X1503592D01*
X1503777Y1082191D01*
Y1082017D01*
X1502377D01*
Y1082191D01*
G37*
G36*
G01X1506091D02*
X1506276Y1082791D01*
X1507306D01*
X1507491Y1082191D01*
Y1082017D01*
X1506091D01*
Y1082191D01*
G37*
G36*
G01X1498630D02*
X1498815Y1082791D01*
X1499845D01*
X1500030Y1082191D01*
Y1082016D01*
X1498630D01*
Y1082191D01*
G37*
G36*
G01X1494987D02*
X1495172Y1082791D01*
X1496202D01*
X1496387Y1082191D01*
Y1082017D01*
X1494987D01*
Y1082191D01*
G37*
G36*
G01X1502377D02*
X1502562Y1082791D01*
X1503592D01*
X1503777Y1082191D01*
Y1082017D01*
X1502377D01*
Y1082191D01*
G37*
G36*
G01X1506091D02*
X1506276Y1082791D01*
X1507306D01*
X1507491Y1082191D01*
Y1082017D01*
X1506091D01*
Y1082191D01*
G37*
G36*
G01X1494977Y1088599D02*
X1495162Y1089199D01*
X1496192D01*
X1496377Y1088599D01*
Y1088425D01*
X1494977D01*
Y1088599D01*
G37*
G36*
G01X1498677Y1088600D02*
X1498862Y1089200D01*
X1499892D01*
X1500077Y1088600D01*
Y1088426D01*
X1498677D01*
Y1088600D01*
G37*
G36*
G01X1502387D02*
X1502572Y1089200D01*
X1503602D01*
X1503787Y1088600D01*
Y1088426D01*
X1502387D01*
Y1088600D01*
G37*
G36*
G01X1506087D02*
X1506272Y1089200D01*
X1507302D01*
X1507487Y1088600D01*
Y1088426D01*
X1506087D01*
Y1088600D01*
G37*
G36*
G01X1494977Y1088599D02*
X1495162Y1089199D01*
X1496192D01*
X1496377Y1088599D01*
Y1088425D01*
X1494977D01*
Y1088599D01*
G37*
G36*
G01X1498677Y1088600D02*
X1498862Y1089200D01*
X1499892D01*
X1500077Y1088600D01*
Y1088426D01*
X1498677D01*
Y1088600D01*
G37*
G36*
G01X1502387D02*
X1502572Y1089200D01*
X1503602D01*
X1503787Y1088600D01*
Y1088426D01*
X1502387D01*
Y1088600D01*
G37*
G36*
G01X1506087D02*
X1506272Y1089200D01*
X1507302D01*
X1507487Y1088600D01*
Y1088426D01*
X1506087D01*
Y1088600D01*
G37*
G36*
G01X1493070Y1085396D02*
X1493255Y1085996D01*
X1494285D01*
X1494470Y1085396D01*
Y1085222D01*
X1493070D01*
Y1085396D01*
G37*
G36*
G01X1500503D02*
X1500688Y1085996D01*
X1501718D01*
X1501903Y1085396D01*
Y1085221D01*
X1500503D01*
Y1085396D01*
G37*
G36*
G01X1496770D02*
X1496955Y1085996D01*
X1497985D01*
X1498170Y1085396D01*
Y1085222D01*
X1496770D01*
Y1085396D01*
G37*
G36*
G01X1507870D02*
X1508055Y1085996D01*
X1509085D01*
X1509270Y1085396D01*
Y1085222D01*
X1507870D01*
Y1085396D01*
G37*
G36*
G01X1504170D02*
X1504355Y1085996D01*
X1505385D01*
X1505570Y1085396D01*
Y1085222D01*
X1504170D01*
Y1085396D01*
G37*
G36*
G01X1493070D02*
X1493255Y1085996D01*
X1494285D01*
X1494470Y1085396D01*
Y1085222D01*
X1493070D01*
Y1085396D01*
G37*
G36*
G01X1500503D02*
X1500688Y1085996D01*
X1501718D01*
X1501903Y1085396D01*
Y1085221D01*
X1500503D01*
Y1085396D01*
G37*
G36*
G01X1496770D02*
X1496955Y1085996D01*
X1497985D01*
X1498170Y1085396D01*
Y1085222D01*
X1496770D01*
Y1085396D01*
G37*
G36*
G01X1507870D02*
X1508055Y1085996D01*
X1509085D01*
X1509270Y1085396D01*
Y1085222D01*
X1507870D01*
Y1085396D01*
G37*
G36*
G01X1504170D02*
X1504355Y1085996D01*
X1505385D01*
X1505570Y1085396D01*
Y1085222D01*
X1504170D01*
Y1085396D01*
G37*
G36*
G01X1494470Y1087003D02*
X1494285Y1086403D01*
X1493255D01*
X1493070Y1087003D01*
Y1087178D01*
X1494470D01*
Y1087003D01*
G37*
G36*
G01X1498203Y1087005D02*
X1498018Y1086405D01*
X1496988D01*
X1496803Y1087005D01*
Y1087179D01*
X1498203D01*
Y1087005D01*
G37*
G36*
G01X1501870Y1087003D02*
X1501685Y1086403D01*
X1500655D01*
X1500470Y1087003D01*
Y1087178D01*
X1501870D01*
Y1087003D01*
G37*
G36*
G01X1505570D02*
X1505385Y1086403D01*
X1504355D01*
X1504170Y1087003D01*
Y1087178D01*
X1505570D01*
Y1087003D01*
G37*
G36*
G01X1509270D02*
X1509085Y1086403D01*
X1508055D01*
X1507870Y1087003D01*
Y1087178D01*
X1509270D01*
Y1087003D01*
G37*
G36*
G01X1494470D02*
X1494285Y1086403D01*
X1493255D01*
X1493070Y1087003D01*
Y1087178D01*
X1494470D01*
Y1087003D01*
G37*
G36*
G01X1498203Y1087005D02*
X1498018Y1086405D01*
X1496988D01*
X1496803Y1087005D01*
Y1087179D01*
X1498203D01*
Y1087005D01*
G37*
G36*
G01X1501870Y1087003D02*
X1501685Y1086403D01*
X1500655D01*
X1500470Y1087003D01*
Y1087178D01*
X1501870D01*
Y1087003D01*
G37*
G36*
G01X1505570D02*
X1505385Y1086403D01*
X1504355D01*
X1504170Y1087003D01*
Y1087178D01*
X1505570D01*
Y1087003D01*
G37*
G36*
G01X1509270D02*
X1509085Y1086403D01*
X1508055D01*
X1507870Y1087003D01*
Y1087178D01*
X1509270D01*
Y1087003D01*
G37*
G36*
G01X1496387Y1083799D02*
X1496202Y1083199D01*
X1495172D01*
X1494987Y1083799D01*
Y1083973D01*
X1496387D01*
Y1083799D01*
G37*
G36*
G01X1500077D02*
X1499892Y1083199D01*
X1498862D01*
X1498677Y1083799D01*
Y1083974D01*
X1500077D01*
Y1083799D01*
G37*
G36*
G01X1507467D02*
X1507282Y1083199D01*
X1506252D01*
X1506067Y1083799D01*
Y1083974D01*
X1507467D01*
Y1083799D01*
G37*
G36*
G01X1503777D02*
X1503592Y1083199D01*
X1502562D01*
X1502377Y1083799D01*
Y1083973D01*
X1503777D01*
Y1083799D01*
G37*
G36*
G01X1496387D02*
X1496202Y1083199D01*
X1495172D01*
X1494987Y1083799D01*
Y1083973D01*
X1496387D01*
Y1083799D01*
G37*
G36*
G01X1500077D02*
X1499892Y1083199D01*
X1498862D01*
X1498677Y1083799D01*
Y1083974D01*
X1500077D01*
Y1083799D01*
G37*
G36*
G01X1507467D02*
X1507282Y1083199D01*
X1506252D01*
X1506067Y1083799D01*
Y1083974D01*
X1507467D01*
Y1083799D01*
G37*
G36*
G01X1503777D02*
X1503592Y1083199D01*
X1502562D01*
X1502377Y1083799D01*
Y1083973D01*
X1503777D01*
Y1083799D01*
G37*
G36*
G01X1501870Y1093411D02*
X1501685Y1092811D01*
X1500655D01*
X1500470Y1093411D01*
Y1093586D01*
X1501870D01*
Y1093411D01*
G37*
G36*
G01X1498170D02*
X1497985Y1092811D01*
X1496955D01*
X1496770Y1093411D01*
Y1093586D01*
X1498170D01*
Y1093411D01*
G37*
G36*
G01X1494480Y1093413D02*
X1494295Y1092813D01*
X1493265D01*
X1493080Y1093413D01*
Y1093587D01*
X1494480D01*
Y1093413D01*
G37*
G36*
G01X1509279D02*
X1509094Y1092813D01*
X1508064D01*
X1507879Y1093413D01*
Y1093587D01*
X1509279D01*
Y1093413D01*
G37*
G36*
G01X1505603D02*
X1505418Y1092813D01*
X1504388D01*
X1504203Y1093413D01*
Y1093587D01*
X1505603D01*
Y1093413D01*
G37*
G36*
G01X1501870Y1093411D02*
X1501685Y1092811D01*
X1500655D01*
X1500470Y1093411D01*
Y1093586D01*
X1501870D01*
Y1093411D01*
G37*
G36*
G01X1498170D02*
X1497985Y1092811D01*
X1496955D01*
X1496770Y1093411D01*
Y1093586D01*
X1498170D01*
Y1093411D01*
G37*
G36*
G01X1494480Y1093413D02*
X1494295Y1092813D01*
X1493265D01*
X1493080Y1093413D01*
Y1093587D01*
X1494480D01*
Y1093413D01*
G37*
G36*
G01X1509279D02*
X1509094Y1092813D01*
X1508064D01*
X1507879Y1093413D01*
Y1093587D01*
X1509279D01*
Y1093413D01*
G37*
G36*
G01X1505603D02*
X1505418Y1092813D01*
X1504388D01*
X1504203Y1093413D01*
Y1093587D01*
X1505603D01*
Y1093413D01*
G37*
G36*
G01X1493080Y1091803D02*
X1493265Y1092403D01*
X1494295D01*
X1494480Y1091803D01*
Y1091629D01*
X1493080D01*
Y1091803D01*
G37*
G36*
G01X1500470Y1091804D02*
X1500655Y1092404D01*
X1501685D01*
X1501870Y1091804D01*
Y1091630D01*
X1500470D01*
Y1091804D01*
G37*
G36*
G01X1496803Y1091803D02*
X1496988Y1092403D01*
X1498018D01*
X1498203Y1091803D01*
Y1091629D01*
X1496803D01*
Y1091803D01*
G37*
G36*
G01X1507870Y1091804D02*
X1508055Y1092404D01*
X1509085D01*
X1509270Y1091804D01*
Y1091630D01*
X1507870D01*
Y1091804D01*
G37*
G36*
G01X1504170D02*
X1504355Y1092404D01*
X1505385D01*
X1505570Y1091804D01*
Y1091630D01*
X1504170D01*
Y1091804D01*
G37*
G36*
G01X1493080Y1091803D02*
X1493265Y1092403D01*
X1494295D01*
X1494480Y1091803D01*
Y1091629D01*
X1493080D01*
Y1091803D01*
G37*
G36*
G01X1500470Y1091804D02*
X1500655Y1092404D01*
X1501685D01*
X1501870Y1091804D01*
Y1091630D01*
X1500470D01*
Y1091804D01*
G37*
G36*
G01X1496803Y1091803D02*
X1496988Y1092403D01*
X1498018D01*
X1498203Y1091803D01*
Y1091629D01*
X1496803D01*
Y1091803D01*
G37*
G36*
G01X1507870Y1091804D02*
X1508055Y1092404D01*
X1509085D01*
X1509270Y1091804D01*
Y1091630D01*
X1507870D01*
Y1091804D01*
G37*
G36*
G01X1504170D02*
X1504355Y1092404D01*
X1505385D01*
X1505570Y1091804D01*
Y1091630D01*
X1504170D01*
Y1091804D01*
G37*
G36*
G01X1498687Y1095009D02*
X1498872Y1095609D01*
X1499902D01*
X1500087Y1095009D01*
Y1094835D01*
X1498687D01*
Y1095009D01*
G37*
G36*
G01X1494987D02*
X1495172Y1095609D01*
X1496202D01*
X1496387Y1095009D01*
Y1094835D01*
X1494987D01*
Y1095009D01*
G37*
G36*
G01X1506053Y1095008D02*
X1506238Y1095608D01*
X1507268D01*
X1507453Y1095008D01*
Y1094834D01*
X1506053D01*
Y1095008D01*
G37*
G36*
G01X1502377D02*
X1502562Y1095608D01*
X1503592D01*
X1503777Y1095008D01*
Y1094834D01*
X1502377D01*
Y1095008D01*
G37*
G36*
G01X1498687Y1095009D02*
X1498872Y1095609D01*
X1499902D01*
X1500087Y1095009D01*
Y1094835D01*
X1498687D01*
Y1095009D01*
G37*
G36*
G01X1494987D02*
X1495172Y1095609D01*
X1496202D01*
X1496387Y1095009D01*
Y1094835D01*
X1494987D01*
Y1095009D01*
G37*
G36*
G01X1506053Y1095008D02*
X1506238Y1095608D01*
X1507268D01*
X1507453Y1095008D01*
Y1094834D01*
X1506053D01*
Y1095008D01*
G37*
G36*
G01X1502377D02*
X1502562Y1095608D01*
X1503592D01*
X1503777Y1095008D01*
Y1094834D01*
X1502377D01*
Y1095008D01*
G37*
G36*
G01X1500077Y1090207D02*
X1499892Y1089607D01*
X1498862D01*
X1498677Y1090207D01*
Y1090382D01*
X1500077D01*
Y1090207D01*
G37*
G36*
G01X1496377Y1090209D02*
X1496192Y1089609D01*
X1495162D01*
X1494977Y1090209D01*
Y1090383D01*
X1496377D01*
Y1090209D01*
G37*
G36*
G01X1507487Y1090207D02*
X1507302Y1089607D01*
X1506272D01*
X1506087Y1090207D01*
Y1090382D01*
X1507487D01*
Y1090207D01*
G37*
G36*
G01X1503787D02*
X1503602Y1089607D01*
X1502572D01*
X1502387Y1090207D01*
Y1090382D01*
X1503787D01*
Y1090207D01*
G37*
G36*
G01X1500077D02*
X1499892Y1089607D01*
X1498862D01*
X1498677Y1090207D01*
Y1090382D01*
X1500077D01*
Y1090207D01*
G37*
G36*
G01X1496377Y1090209D02*
X1496192Y1089609D01*
X1495162D01*
X1494977Y1090209D01*
Y1090383D01*
X1496377D01*
Y1090209D01*
G37*
G36*
G01X1507487Y1090207D02*
X1507302Y1089607D01*
X1506272D01*
X1506087Y1090207D01*
Y1090382D01*
X1507487D01*
Y1090207D01*
G37*
G36*
G01X1503787D02*
X1503602Y1089607D01*
X1502572D01*
X1502387Y1090207D01*
Y1090382D01*
X1503787D01*
Y1090207D01*
G37*
G36*
G01X1498630Y1101417D02*
X1498815Y1102017D01*
X1499845D01*
X1500030Y1101417D01*
Y1101243D01*
X1498630D01*
Y1101417D01*
G37*
G36*
G01X1494930Y1101416D02*
X1495115Y1102016D01*
X1496145D01*
X1496330Y1101416D01*
Y1101242D01*
X1494930D01*
Y1101416D01*
G37*
G36*
G01X1506053D02*
X1506238Y1102016D01*
X1507268D01*
X1507453Y1101416D01*
Y1101242D01*
X1506053D01*
Y1101416D01*
G37*
G36*
G01X1502387Y1101417D02*
X1502572Y1102017D01*
X1503602D01*
X1503787Y1101417D01*
Y1101243D01*
X1502387D01*
Y1101417D01*
G37*
G36*
G01X1498630D02*
X1498815Y1102017D01*
X1499845D01*
X1500030Y1101417D01*
Y1101243D01*
X1498630D01*
Y1101417D01*
G37*
G36*
G01X1494930Y1101416D02*
X1495115Y1102016D01*
X1496145D01*
X1496330Y1101416D01*
Y1101242D01*
X1494930D01*
Y1101416D01*
G37*
G36*
G01X1506053D02*
X1506238Y1102016D01*
X1507268D01*
X1507453Y1101416D01*
Y1101242D01*
X1506053D01*
Y1101416D01*
G37*
G36*
G01X1502387Y1101417D02*
X1502572Y1102017D01*
X1503602D01*
X1503787Y1101417D01*
Y1101243D01*
X1502387D01*
Y1101417D01*
G37*
G36*
G01X1500054Y1096617D02*
X1499869Y1096017D01*
X1498839D01*
X1498654Y1096617D01*
Y1096792D01*
X1500054D01*
Y1096617D01*
G37*
G36*
G01X1496354D02*
X1496169Y1096017D01*
X1495139D01*
X1494954Y1096617D01*
Y1096792D01*
X1496354D01*
Y1096617D01*
G37*
G36*
G01X1507453D02*
X1507268Y1096017D01*
X1506238D01*
X1506053Y1096617D01*
Y1096792D01*
X1507453D01*
Y1096617D01*
G37*
G36*
G01X1503777D02*
X1503592Y1096017D01*
X1502562D01*
X1502377Y1096617D01*
Y1096792D01*
X1503777D01*
Y1096617D01*
G37*
G36*
G01X1500054D02*
X1499869Y1096017D01*
X1498839D01*
X1498654Y1096617D01*
Y1096792D01*
X1500054D01*
Y1096617D01*
G37*
G36*
G01X1496354D02*
X1496169Y1096017D01*
X1495139D01*
X1494954Y1096617D01*
Y1096792D01*
X1496354D01*
Y1096617D01*
G37*
G36*
G01X1507453D02*
X1507268Y1096017D01*
X1506238D01*
X1506053Y1096617D01*
Y1096792D01*
X1507453D01*
Y1096617D01*
G37*
G36*
G01X1503777D02*
X1503592Y1096017D01*
X1502562D01*
X1502377Y1096617D01*
Y1096792D01*
X1503777D01*
Y1096617D01*
G37*
G36*
G01X1501880Y1099822D02*
X1501695Y1099222D01*
X1500665D01*
X1500480Y1099822D01*
Y1099996D01*
X1501880D01*
Y1099822D01*
G37*
G36*
G01X1498237Y1099821D02*
X1498052Y1099221D01*
X1497022D01*
X1496837Y1099821D01*
Y1099995D01*
X1498237D01*
Y1099821D01*
G37*
G36*
G01X1509336D02*
X1509151Y1099221D01*
X1508121D01*
X1507936Y1099821D01*
Y1099995D01*
X1509336D01*
Y1099821D01*
G37*
G36*
G01X1505570D02*
X1505385Y1099221D01*
X1504355D01*
X1504170Y1099821D01*
Y1099995D01*
X1505570D01*
Y1099821D01*
G37*
G36*
G01X1501880Y1099822D02*
X1501695Y1099222D01*
X1500665D01*
X1500480Y1099822D01*
Y1099996D01*
X1501880D01*
Y1099822D01*
G37*
G36*
G01X1498237Y1099821D02*
X1498052Y1099221D01*
X1497022D01*
X1496837Y1099821D01*
Y1099995D01*
X1498237D01*
Y1099821D01*
G37*
G36*
G01X1509336D02*
X1509151Y1099221D01*
X1508121D01*
X1507936Y1099821D01*
Y1099995D01*
X1509336D01*
Y1099821D01*
G37*
G36*
G01X1505570D02*
X1505385Y1099221D01*
X1504355D01*
X1504170Y1099821D01*
Y1099995D01*
X1505570D01*
Y1099821D01*
G37*
G36*
G01X1496804Y1098212D02*
X1496989Y1098812D01*
X1498019D01*
X1498204Y1098212D01*
Y1098038D01*
X1496804D01*
Y1098212D01*
G37*
G36*
G01X1493080Y1098213D02*
X1493265Y1098813D01*
X1494295D01*
X1494480Y1098213D01*
Y1098039D01*
X1493080D01*
Y1098213D01*
G37*
G36*
G01X1500480Y1098212D02*
X1500665Y1098812D01*
X1501695D01*
X1501880Y1098212D01*
Y1098038D01*
X1500480D01*
Y1098212D01*
G37*
G36*
G01X1507903D02*
X1508088Y1098812D01*
X1509118D01*
X1509303Y1098212D01*
Y1098038D01*
X1507903D01*
Y1098212D01*
G37*
G36*
G01X1504203D02*
X1504388Y1098812D01*
X1505418D01*
X1505603Y1098212D01*
Y1098038D01*
X1504203D01*
Y1098212D01*
G37*
G36*
G01X1496804D02*
X1496989Y1098812D01*
X1498019D01*
X1498204Y1098212D01*
Y1098038D01*
X1496804D01*
Y1098212D01*
G37*
G36*
G01X1493080Y1098213D02*
X1493265Y1098813D01*
X1494295D01*
X1494480Y1098213D01*
Y1098039D01*
X1493080D01*
Y1098213D01*
G37*
G36*
G01X1500480Y1098212D02*
X1500665Y1098812D01*
X1501695D01*
X1501880Y1098212D01*
Y1098038D01*
X1500480D01*
Y1098212D01*
G37*
G36*
G01X1507903D02*
X1508088Y1098812D01*
X1509118D01*
X1509303Y1098212D01*
Y1098038D01*
X1507903D01*
Y1098212D01*
G37*
G36*
G01X1504203D02*
X1504388Y1098812D01*
X1505418D01*
X1505603Y1098212D01*
Y1098038D01*
X1504203D01*
Y1098212D01*
G37*
G36*
G01X1527200Y164452D02*
X1610680D01*
X1617290Y157842D01*
Y79691D01*
G02X1616866Y79292I-400J0D01*
G03X1616774Y79295I-95J-1499D01*
G03X1615272Y77793I0J-1502D01*
G03X1615347Y77324I1502J0D01*
G02X1614967Y76800I-380J-124D01*
G01X1613625D01*
G02X1613245Y77324I0J400D01*
G03X1613320Y77793I-1427J469D01*
G03X1610316I-1502J0D01*
G03X1610394Y77316I1502J1D01*
G02X1609973Y76791I-379J-127D01*
G03X1609818Y76799I-155J-1494D01*
G03Y73795I0J-1502D01*
G03X1609973Y73803I0J1502D01*
G02X1610394Y73278I42J-398D01*
G03X1610316Y72801I1424J-478D01*
G03X1613320I1502J0D01*
G03X1613245Y73270I-1502J0D01*
G02X1613625Y73794I380J124D01*
G01X1614967D01*
G02X1615347Y73270I0J-400D01*
G03X1615272Y72801I1427J-469D01*
G03X1616774Y71299I1502J0D01*
G03X1616866Y71302I-3J1502D01*
G02X1617290Y70903I24J-399D01*
G01Y50672D01*
X1619980Y47982D01*
X1624506D01*
G03X1625814Y47218I1308J738D01*
G03X1627316Y48720I0J1502D01*
G03X1627156Y49394I-1502J-1D01*
G01X1627091Y49523D01*
X1630190Y52622D01*
X1710070D01*
X1712670Y50022D01*
Y34792D01*
X1709330Y31452D01*
X1558500D01*
X1554907Y35045D01*
G02X1555048Y35702I283J283D01*
G03X1556017Y37106I-533J1404D01*
G03X1555480Y38257I-1502J0D01*
G02Y38869I258J306D01*
G03X1556017Y40020I-965J1151D01*
G03X1553013I-1502J0D01*
G03X1553550Y38869I1502J0D01*
G02Y38257I-258J-306D01*
G03X1553111Y37639I965J-1151D01*
G02X1552454Y37498I-374J142D01*
G01X1552270Y37682D01*
Y72667D01*
X1552271Y72675D01*
G03X1552276Y72801I-1497J123D01*
G03X1552271Y72927I-1502J3D01*
G01X1552270Y72935D01*
Y73398D01*
G02X1552692Y73797I400J0D01*
G03X1552774Y73795I78J1500D01*
G03Y76799I0J1502D01*
G03X1552692Y76797I-4J-1502D01*
G02X1552270Y77196I-22J399D01*
G01Y77659D01*
X1552271Y77667D01*
G03X1552276Y77793I-1497J123D01*
G03X1552271Y77919I-1502J3D01*
G01X1552270Y77927D01*
Y121899D01*
X1553256Y122885D01*
X1553311Y122899D01*
G03X1554462Y124359I-350J1460D01*
G03X1552960Y125861I-1502J0D01*
G03X1552528Y125797I2J-1502D01*
G01X1552499Y125789D01*
X1552270D01*
Y126438D01*
X1552514D01*
X1552554Y126420D01*
G03X1553189Y126279I635J1361D01*
G03Y129283I0J1502D01*
G03X1552300Y128992I0J-1502D01*
G01X1552162Y128890D01*
X1549480Y131572D01*
X1525520D01*
X1522180Y134912D01*
Y159432D01*
X1527200Y164452D01*
G37*
G36*
G01X1520430Y850573D02*
X1520615Y851173D01*
X1521645D01*
X1521830Y850573D01*
Y850399D01*
X1520430D01*
Y850573D01*
G37*
G36*
G01D02*
X1520615Y851173D01*
X1521645D01*
X1521830Y850573D01*
Y850399D01*
X1520430D01*
Y850573D01*
G37*
G36*
G01X1514431Y852184D02*
X1514246Y851584D01*
X1513216D01*
X1513031Y852184D01*
Y852358D01*
X1514431D01*
Y852184D01*
G37*
G36*
G01X1525544Y852181D02*
X1525359Y851581D01*
X1524329D01*
X1524144Y852181D01*
Y852356D01*
X1525544D01*
Y852181D01*
G37*
G36*
G01X1523648Y848980D02*
X1523463Y848380D01*
X1522433D01*
X1522248Y848980D01*
Y849155D01*
X1523648D01*
Y848980D01*
G37*
G36*
G01X1519971Y848972D02*
X1519786Y848372D01*
X1518756D01*
X1518571Y848972D01*
Y849146D01*
X1519971D01*
Y848972D01*
G37*
G36*
G01X1523648Y848980D02*
X1523463Y848380D01*
X1522433D01*
X1522248Y848980D01*
Y849155D01*
X1523648D01*
Y848980D01*
G37*
G36*
G01X1519971Y848972D02*
X1519786Y848372D01*
X1518756D01*
X1518571Y848972D01*
Y849146D01*
X1519971D01*
Y848972D01*
G37*
G36*
G01X1523671Y868205D02*
X1523486Y867605D01*
X1522456D01*
X1522271Y868205D01*
Y868380D01*
X1523671D01*
Y868205D01*
G37*
G36*
G01D02*
X1523486Y867605D01*
X1522456D01*
X1522271Y868205D01*
Y868380D01*
X1523671D01*
Y868205D01*
G37*
G36*
G01X1518571Y853779D02*
X1518756Y854379D01*
X1519786D01*
X1519971Y853779D01*
Y853604D01*
X1518571D01*
Y853779D01*
G37*
G36*
G01X1522239D02*
X1522424Y854379D01*
X1523454D01*
X1523639Y853779D01*
Y853605D01*
X1522239D01*
Y853779D01*
G37*
G36*
G01X1518571D02*
X1518756Y854379D01*
X1519786D01*
X1519971Y853779D01*
Y853604D01*
X1518571D01*
Y853779D01*
G37*
G36*
G01X1522239D02*
X1522424Y854379D01*
X1523454D01*
X1523639Y853779D01*
Y853605D01*
X1522239D01*
Y853779D01*
G37*
G36*
G01X1525487Y858593D02*
X1525302Y857993D01*
X1524272D01*
X1524087Y858593D01*
Y858767D01*
X1525487D01*
Y858593D01*
G37*
G36*
G01X1521821D02*
X1521636Y857993D01*
X1520606D01*
X1520421Y858593D01*
Y858768D01*
X1521821D01*
Y858593D01*
G37*
G36*
G01X1525487D02*
X1525302Y857993D01*
X1524272D01*
X1524087Y858593D01*
Y858767D01*
X1525487D01*
Y858593D01*
G37*
G36*
G01X1521821D02*
X1521636Y857993D01*
X1520606D01*
X1520421Y858593D01*
Y858768D01*
X1521821D01*
Y858593D01*
G37*
G36*
G01X1524087Y856985D02*
X1524272Y857585D01*
X1525302D01*
X1525487Y856985D01*
Y856811D01*
X1524087D01*
Y856985D01*
G37*
G36*
G01X1520421D02*
X1520606Y857585D01*
X1521636D01*
X1521821Y856985D01*
Y856810D01*
X1520421D01*
Y856985D01*
G37*
G36*
G01X1524087D02*
X1524272Y857585D01*
X1525302D01*
X1525487Y856985D01*
Y856811D01*
X1524087D01*
Y856985D01*
G37*
G36*
G01X1520421D02*
X1520606Y857585D01*
X1521636D01*
X1521821Y856985D01*
Y856810D01*
X1520421D01*
Y856985D01*
G37*
G36*
G01X1522304Y860189D02*
X1522489Y860789D01*
X1523519D01*
X1523704Y860189D01*
Y860015D01*
X1522304D01*
Y860189D01*
G37*
G36*
G01D02*
X1522489Y860789D01*
X1523519D01*
X1523704Y860189D01*
Y860015D01*
X1522304D01*
Y860189D01*
G37*
G36*
G01X1523704Y855387D02*
X1523519Y854787D01*
X1522489D01*
X1522304Y855387D01*
Y855562D01*
X1523704D01*
Y855387D01*
G37*
G36*
G01X1519938D02*
X1519753Y854787D01*
X1518723D01*
X1518538Y855387D01*
Y855562D01*
X1519938D01*
Y855387D01*
G37*
G36*
G01X1523704D02*
X1523519Y854787D01*
X1522489D01*
X1522304Y855387D01*
Y855562D01*
X1523704D01*
Y855387D01*
G37*
G36*
G01X1519938D02*
X1519753Y854787D01*
X1518723D01*
X1518538Y855387D01*
Y855562D01*
X1519938D01*
Y855387D01*
G37*
G36*
G01X1524121Y869801D02*
X1524306Y870401D01*
X1525336D01*
X1525521Y869801D01*
Y869627D01*
X1524121D01*
Y869801D01*
G37*
G36*
G01X1520421D02*
X1520606Y870401D01*
X1521636D01*
X1521821Y869801D01*
Y869627D01*
X1520421D01*
Y869801D01*
G37*
G36*
G01X1524121D02*
X1524306Y870401D01*
X1525336D01*
X1525521Y869801D01*
Y869627D01*
X1524121D01*
Y869801D01*
G37*
G36*
G01X1520421D02*
X1520606Y870401D01*
X1521636D01*
X1521821Y869801D01*
Y869627D01*
X1520421D01*
Y869801D01*
G37*
G36*
G01X1514871Y898641D02*
X1515056Y899241D01*
X1516086D01*
X1516271Y898641D01*
Y898466D01*
X1514871D01*
Y898641D01*
G37*
G36*
G01X1511171D02*
X1511356Y899241D01*
X1512386D01*
X1512571Y898641D01*
Y898466D01*
X1511171D01*
Y898641D01*
G37*
G36*
G01X1514871D02*
X1515056Y899241D01*
X1516086D01*
X1516271Y898641D01*
Y898466D01*
X1514871D01*
Y898641D01*
G37*
G36*
G01X1511171D02*
X1511356Y899241D01*
X1512386D01*
X1512571Y898641D01*
Y898466D01*
X1511171D01*
Y898641D01*
G37*
G36*
G01X1509321Y895435D02*
X1509506Y896035D01*
X1510536D01*
X1510721Y895435D01*
Y895261D01*
X1509321D01*
Y895435D01*
G37*
G36*
G01X1513021D02*
X1513206Y896035D01*
X1514236D01*
X1514421Y895435D01*
Y895261D01*
X1513021D01*
Y895435D01*
G37*
G36*
G01X1509321D02*
X1509506Y896035D01*
X1510536D01*
X1510721Y895435D01*
Y895261D01*
X1509321D01*
Y895435D01*
G37*
G36*
G01X1513021D02*
X1513206Y896035D01*
X1514236D01*
X1514421Y895435D01*
Y895261D01*
X1513021D01*
Y895435D01*
G37*
G36*
G01X1510721Y897045D02*
X1510536Y896445D01*
X1509506D01*
X1509321Y897045D01*
Y897219D01*
X1510721D01*
Y897045D01*
G37*
G36*
G01X1514421D02*
X1514236Y896445D01*
X1513206D01*
X1513021Y897045D01*
Y897219D01*
X1514421D01*
Y897045D01*
G37*
G36*
G01X1510721D02*
X1510536Y896445D01*
X1509506D01*
X1509321Y897045D01*
Y897219D01*
X1510721D01*
Y897045D01*
G37*
G36*
G01X1514421D02*
X1514236Y896445D01*
X1513206D01*
X1513021Y897045D01*
Y897219D01*
X1514421D01*
Y897045D01*
G37*
G36*
G01X1512571Y893841D02*
X1512386Y893241D01*
X1511356D01*
X1511171Y893841D01*
Y894015D01*
X1512571D01*
Y893841D01*
G37*
G36*
G01D02*
X1512386Y893241D01*
X1511356D01*
X1511171Y893841D01*
Y894015D01*
X1512571D01*
Y893841D01*
G37*
G36*
G01X1516271Y900251D02*
X1516086Y899651D01*
X1515056D01*
X1514871Y900251D01*
Y900425D01*
X1516271D01*
Y900251D01*
G37*
G36*
G01X1512570Y900249D02*
X1512385Y899649D01*
X1511355D01*
X1511170Y900249D01*
Y900423D01*
X1512570D01*
Y900249D01*
G37*
G36*
G01X1516271Y900251D02*
X1516086Y899651D01*
X1515056D01*
X1514871Y900251D01*
Y900425D01*
X1516271D01*
Y900251D01*
G37*
G36*
G01X1512570Y900249D02*
X1512385Y899649D01*
X1511355D01*
X1511170Y900249D01*
Y900423D01*
X1512570D01*
Y900249D01*
G37*
G36*
G01X1515703Y916848D02*
X1515091Y916708D01*
X1514576Y917600D01*
X1515003Y918060D01*
X1515154Y918147D01*
X1515854Y916935D01*
X1515703Y916848D01*
G37*
G36*
G01X1518121Y916271D02*
X1517936Y915671D01*
X1516906D01*
X1516721Y916271D01*
Y916445D01*
X1518121D01*
Y916271D01*
G37*
G36*
G01X1521821D02*
X1521636Y915671D01*
X1520606D01*
X1520421Y916271D01*
Y916445D01*
X1521821D01*
Y916271D01*
G37*
G36*
G01X1515703Y916848D02*
X1515091Y916708D01*
X1514576Y917600D01*
X1515003Y918060D01*
X1515154Y918147D01*
X1515854Y916935D01*
X1515703Y916848D01*
G37*
G36*
G01X1518121Y916271D02*
X1517936Y915671D01*
X1516906D01*
X1516721Y916271D01*
Y916445D01*
X1518121D01*
Y916271D01*
G37*
G36*
G01X1521821D02*
X1521636Y915671D01*
X1520606D01*
X1520421Y916271D01*
Y916445D01*
X1521821D01*
Y916271D01*
G37*
G36*
G01X1516271Y913067D02*
X1516086Y912467D01*
X1515056D01*
X1514871Y913067D01*
Y913241D01*
X1516271D01*
Y913067D01*
G37*
G36*
G01X1510721Y916271D02*
X1510536Y915671D01*
X1509506D01*
X1509321Y916271D01*
Y916445D01*
X1510721D01*
Y916271D01*
G37*
G36*
G01X1513853Y913644D02*
X1513241Y913504D01*
X1512726Y914396D01*
X1513153Y914856D01*
X1513304Y914943D01*
X1514004Y913731D01*
X1513853Y913644D01*
G37*
G36*
G01X1519971Y913067D02*
X1519786Y912467D01*
X1518756D01*
X1518571Y913067D01*
Y913241D01*
X1519971D01*
Y913067D01*
G37*
G36*
G01X1516271D02*
X1516086Y912467D01*
X1515056D01*
X1514871Y913067D01*
Y913241D01*
X1516271D01*
Y913067D01*
G37*
G36*
G01X1510721Y916271D02*
X1510536Y915671D01*
X1509506D01*
X1509321Y916271D01*
Y916445D01*
X1510721D01*
Y916271D01*
G37*
G36*
G01X1513853Y913644D02*
X1513241Y913504D01*
X1512726Y914396D01*
X1513153Y914856D01*
X1513304Y914943D01*
X1514004Y913731D01*
X1513853Y913644D01*
G37*
G36*
G01X1519971Y913067D02*
X1519786Y912467D01*
X1518756D01*
X1518571Y913067D01*
Y913241D01*
X1519971D01*
Y913067D01*
G37*
G36*
G01X1516721Y914661D02*
X1516906Y915261D01*
X1517936D01*
X1518121Y914661D01*
Y914487D01*
X1516721D01*
Y914661D01*
G37*
G36*
G01X1513589Y917288D02*
X1514201Y917428D01*
X1514716Y916536D01*
X1514289Y916076D01*
X1514138Y915989D01*
X1513438Y917201D01*
X1513589Y917288D01*
G37*
G36*
G01X1520421Y914661D02*
X1520606Y915261D01*
X1521636D01*
X1521821Y914661D01*
Y914487D01*
X1520421D01*
Y914661D01*
G37*
G36*
G01X1516721D02*
X1516906Y915261D01*
X1517936D01*
X1518121Y914661D01*
Y914487D01*
X1516721D01*
Y914661D01*
G37*
G36*
G01X1513589Y917288D02*
X1514201Y917428D01*
X1514716Y916536D01*
X1514289Y916076D01*
X1514138Y915989D01*
X1513438Y917201D01*
X1513589Y917288D01*
G37*
G36*
G01X1520421Y914661D02*
X1520606Y915261D01*
X1521636D01*
X1521821Y914661D01*
Y914487D01*
X1520421D01*
Y914661D01*
G37*
G36*
G01X1511171Y911457D02*
X1511356Y912057D01*
X1512386D01*
X1512571Y911457D01*
Y911283D01*
X1511171D01*
Y911457D01*
G37*
G36*
G01X1514871D02*
X1515056Y912057D01*
X1516086D01*
X1516271Y911457D01*
Y911283D01*
X1514871D01*
Y911457D01*
G37*
G36*
G01X1511171D02*
X1511356Y912057D01*
X1512386D01*
X1512571Y911457D01*
Y911283D01*
X1511171D01*
Y911457D01*
G37*
G36*
G01X1514871D02*
X1515056Y912057D01*
X1516086D01*
X1516271Y911457D01*
Y911283D01*
X1514871D01*
Y911457D01*
G37*
G36*
G01X1509321Y908253D02*
X1509506Y908853D01*
X1510536D01*
X1510721Y908253D01*
Y908078D01*
X1509321D01*
Y908253D01*
G37*
G36*
G01X1513021D02*
X1513206Y908853D01*
X1514236D01*
X1514421Y908253D01*
Y908078D01*
X1513021D01*
Y908253D01*
G37*
G36*
G01X1516721D02*
X1516906Y908853D01*
X1517936D01*
X1518121Y908253D01*
Y908078D01*
X1516721D01*
Y908253D01*
G37*
G36*
G01X1509321D02*
X1509506Y908853D01*
X1510536D01*
X1510721Y908253D01*
Y908078D01*
X1509321D01*
Y908253D01*
G37*
G36*
G01X1513021D02*
X1513206Y908853D01*
X1514236D01*
X1514421Y908253D01*
Y908078D01*
X1513021D01*
Y908253D01*
G37*
G36*
G01X1516721D02*
X1516906Y908853D01*
X1517936D01*
X1518121Y908253D01*
Y908078D01*
X1516721D01*
Y908253D01*
G37*
G36*
G01X1518121Y909861D02*
X1517936Y909261D01*
X1516906D01*
X1516721Y909861D01*
Y910036D01*
X1518121D01*
Y909861D01*
G37*
G36*
G01X1514421D02*
X1514236Y909261D01*
X1513206D01*
X1513021Y909861D01*
Y910036D01*
X1514421D01*
Y909861D01*
G37*
G36*
G01X1510721D02*
X1510536Y909261D01*
X1509506D01*
X1509321Y909861D01*
Y910036D01*
X1510721D01*
Y909861D01*
G37*
G36*
G01X1518121D02*
X1517936Y909261D01*
X1516906D01*
X1516721Y909861D01*
Y910036D01*
X1518121D01*
Y909861D01*
G37*
G36*
G01X1514421D02*
X1514236Y909261D01*
X1513206D01*
X1513021Y909861D01*
Y910036D01*
X1514421D01*
Y909861D01*
G37*
G36*
G01X1510721D02*
X1510536Y909261D01*
X1509506D01*
X1509321Y909861D01*
Y910036D01*
X1510721D01*
Y909861D01*
G37*
G36*
G01X1512571Y906657D02*
X1512386Y906057D01*
X1511356D01*
X1511171Y906657D01*
Y906832D01*
X1512571D01*
Y906657D01*
G37*
G36*
G01X1516271D02*
X1516086Y906057D01*
X1515056D01*
X1514871Y906657D01*
Y906832D01*
X1516271D01*
Y906657D01*
G37*
G36*
G01X1512571D02*
X1512386Y906057D01*
X1511356D01*
X1511171Y906657D01*
Y906832D01*
X1512571D01*
Y906657D01*
G37*
G36*
G01X1516271D02*
X1516086Y906057D01*
X1515056D01*
X1514871Y906657D01*
Y906832D01*
X1516271D01*
Y906657D01*
G37*
G36*
G01X1514421Y903453D02*
X1514236Y902853D01*
X1513206D01*
X1513021Y903453D01*
Y903628D01*
X1514421D01*
Y903453D01*
G37*
G36*
G01X1510721D02*
X1510536Y902853D01*
X1509506D01*
X1509321Y903453D01*
Y903628D01*
X1510721D01*
Y903453D01*
G37*
G36*
G01X1514421D02*
X1514236Y902853D01*
X1513206D01*
X1513021Y903453D01*
Y903628D01*
X1514421D01*
Y903453D01*
G37*
G36*
G01X1510721D02*
X1510536Y902853D01*
X1509506D01*
X1509321Y903453D01*
Y903628D01*
X1510721D01*
Y903453D01*
G37*
G36*
G01X1513021Y901845D02*
X1513206Y902445D01*
X1514236D01*
X1514421Y901845D01*
Y901670D01*
X1513021D01*
Y901845D01*
G37*
G36*
G01X1509321D02*
X1509506Y902445D01*
X1510536D01*
X1510721Y901845D01*
Y901670D01*
X1509321D01*
Y901845D01*
G37*
G36*
G01X1513021D02*
X1513206Y902445D01*
X1514236D01*
X1514421Y901845D01*
Y901670D01*
X1513021D01*
Y901845D01*
G37*
G36*
G01X1509321D02*
X1509506Y902445D01*
X1510536D01*
X1510721Y901845D01*
Y901670D01*
X1509321D01*
Y901845D01*
G37*
G36*
G01X1514871Y905049D02*
X1515056Y905649D01*
X1516086D01*
X1516271Y905049D01*
Y904874D01*
X1514871D01*
Y905049D01*
G37*
G36*
G01X1511171D02*
X1511356Y905649D01*
X1512386D01*
X1512571Y905049D01*
Y904874D01*
X1511171D01*
Y905049D01*
G37*
G36*
G01X1514871D02*
X1515056Y905649D01*
X1516086D01*
X1516271Y905049D01*
Y904874D01*
X1514871D01*
Y905049D01*
G37*
G36*
G01X1511171D02*
X1511356Y905649D01*
X1512386D01*
X1512571Y905049D01*
Y904874D01*
X1511171D01*
Y905049D01*
G37*
G36*
G01X1516237Y932291D02*
X1516052Y931691D01*
X1515022D01*
X1514837Y932291D01*
Y932465D01*
X1516237D01*
Y932291D01*
G37*
G36*
G01X1512537D02*
X1512352Y931691D01*
X1511322D01*
X1511137Y932291D01*
Y932465D01*
X1512537D01*
Y932291D01*
G37*
G36*
G01X1519937D02*
X1519752Y931691D01*
X1518722D01*
X1518537Y932291D01*
Y932465D01*
X1519937D01*
Y932291D01*
G37*
G36*
G01X1523106Y929658D02*
X1522494Y929518D01*
X1521979Y930410D01*
X1522406Y930870D01*
X1522557Y930957D01*
X1523257Y929745D01*
X1523106Y929658D01*
G37*
G36*
G01X1516237Y932291D02*
X1516052Y931691D01*
X1515022D01*
X1514837Y932291D01*
Y932465D01*
X1516237D01*
Y932291D01*
G37*
G36*
G01X1512537D02*
X1512352Y931691D01*
X1511322D01*
X1511137Y932291D01*
Y932465D01*
X1512537D01*
Y932291D01*
G37*
G36*
G01X1519937D02*
X1519752Y931691D01*
X1518722D01*
X1518537Y932291D01*
Y932465D01*
X1519937D01*
Y932291D01*
G37*
G36*
G01X1523106Y929658D02*
X1522494Y929518D01*
X1521979Y930410D01*
X1522406Y930870D01*
X1522557Y930957D01*
X1523257Y929745D01*
X1523106Y929658D01*
G37*
G36*
G01X1514837Y930685D02*
X1515022Y931285D01*
X1516052D01*
X1516237Y930685D01*
Y930510D01*
X1514837D01*
Y930685D01*
G37*
G36*
G01X1511137D02*
X1511322Y931285D01*
X1512352D01*
X1512537Y930685D01*
Y930510D01*
X1511137D01*
Y930685D01*
G37*
G36*
G01X1520985Y930113D02*
X1521597Y930253D01*
X1522112Y929361D01*
X1521685Y928901D01*
X1521534Y928814D01*
X1520834Y930026D01*
X1520985Y930113D01*
G37*
G36*
G01X1518537Y930685D02*
X1518722Y931285D01*
X1519752D01*
X1519937Y930685D01*
Y930510D01*
X1518537D01*
Y930685D01*
G37*
G36*
G01X1514837D02*
X1515022Y931285D01*
X1516052D01*
X1516237Y930685D01*
Y930510D01*
X1514837D01*
Y930685D01*
G37*
G36*
G01X1511137D02*
X1511322Y931285D01*
X1512352D01*
X1512537Y930685D01*
Y930510D01*
X1511137D01*
Y930685D01*
G37*
G36*
G01X1520985Y930113D02*
X1521597Y930253D01*
X1522112Y929361D01*
X1521685Y928901D01*
X1521534Y928814D01*
X1520834Y930026D01*
X1520985Y930113D01*
G37*
G36*
G01X1518537Y930685D02*
X1518722Y931285D01*
X1519752D01*
X1519937Y930685D01*
Y930510D01*
X1518537D01*
Y930685D01*
G37*
G36*
G01X1512571Y919475D02*
X1512386Y918875D01*
X1511356D01*
X1511171Y919475D01*
Y919649D01*
X1512571D01*
Y919475D01*
G37*
G36*
G01D02*
X1512386Y918875D01*
X1511356D01*
X1511171Y919475D01*
Y919649D01*
X1512571D01*
Y919475D01*
G37*
G36*
G01X1513021Y921071D02*
X1513206Y921671D01*
X1514236D01*
X1514421Y921071D01*
Y920896D01*
X1513021D01*
Y921071D01*
G37*
G36*
G01X1515431Y920508D02*
X1516043Y920648D01*
X1516558Y919756D01*
X1516131Y919296D01*
X1515980Y919209D01*
X1515280Y920421D01*
X1515431Y920508D01*
G37*
G36*
G01X1509321Y921071D02*
X1509506Y921671D01*
X1510536D01*
X1510721Y921071D01*
Y920896D01*
X1509321D01*
Y921071D01*
G37*
G36*
G01X1518571Y917865D02*
X1518756Y918465D01*
X1519786D01*
X1519971Y917865D01*
Y917691D01*
X1518571D01*
Y917865D01*
G37*
G36*
G01X1513021Y921071D02*
X1513206Y921671D01*
X1514236D01*
X1514421Y921071D01*
Y920896D01*
X1513021D01*
Y921071D01*
G37*
G36*
G01X1515431Y920508D02*
X1516043Y920648D01*
X1516558Y919756D01*
X1516131Y919296D01*
X1515980Y919209D01*
X1515280Y920421D01*
X1515431Y920508D01*
G37*
G36*
G01X1509321Y921071D02*
X1509506Y921671D01*
X1510536D01*
X1510721Y921071D01*
Y920896D01*
X1509321D01*
Y921071D01*
G37*
G36*
G01X1518571Y917865D02*
X1518756Y918465D01*
X1519786D01*
X1519971Y917865D01*
Y917691D01*
X1518571D01*
Y917865D01*
G37*
G36*
G01X1511171D02*
X1511356Y918465D01*
X1512386D01*
X1512571Y917865D01*
Y917691D01*
X1511171D01*
Y917865D01*
G37*
G36*
G01D02*
X1511356Y918465D01*
X1512386D01*
X1512571Y917865D01*
Y917691D01*
X1511171D01*
Y917865D01*
G37*
G36*
G01X1522834Y933320D02*
X1523446Y933460D01*
X1523961Y932568D01*
X1523534Y932108D01*
X1523383Y932021D01*
X1522683Y933233D01*
X1522834Y933320D01*
G37*
G36*
G01D02*
X1523446Y933460D01*
X1523961Y932568D01*
X1523534Y932108D01*
X1523383Y932021D01*
X1522683Y933233D01*
X1522834Y933320D01*
G37*
G36*
G01X1518154Y929087D02*
X1517969Y928487D01*
X1516939D01*
X1516754Y929087D01*
Y929261D01*
X1518154D01*
Y929087D01*
G37*
G36*
G01X1514454D02*
X1514269Y928487D01*
X1513239D01*
X1513054Y929087D01*
Y929261D01*
X1514454D01*
Y929087D01*
G37*
G36*
G01X1510754D02*
X1510569Y928487D01*
X1509539D01*
X1509354Y929087D01*
Y929261D01*
X1510754D01*
Y929087D01*
G37*
G36*
G01X1523637Y925883D02*
X1523452Y925283D01*
X1522422D01*
X1522237Y925883D01*
Y926057D01*
X1523637D01*
Y925883D01*
G37*
G36*
G01X1521257Y926451D02*
X1520645Y926311D01*
X1520130Y927203D01*
X1520557Y927663D01*
X1520708Y927750D01*
X1521408Y926538D01*
X1521257Y926451D01*
G37*
G36*
G01X1518154Y929087D02*
X1517969Y928487D01*
X1516939D01*
X1516754Y929087D01*
Y929261D01*
X1518154D01*
Y929087D01*
G37*
G36*
G01X1514454D02*
X1514269Y928487D01*
X1513239D01*
X1513054Y929087D01*
Y929261D01*
X1514454D01*
Y929087D01*
G37*
G36*
G01X1510754D02*
X1510569Y928487D01*
X1509539D01*
X1509354Y929087D01*
Y929261D01*
X1510754D01*
Y929087D01*
G37*
G36*
G01X1523637Y925883D02*
X1523452Y925283D01*
X1522422D01*
X1522237Y925883D01*
Y926057D01*
X1523637D01*
Y925883D01*
G37*
G36*
G01X1521257Y926451D02*
X1520645Y926311D01*
X1520130Y927203D01*
X1520557Y927663D01*
X1520708Y927750D01*
X1521408Y926538D01*
X1521257Y926451D01*
G37*
G36*
G01X1517561Y920037D02*
X1516949Y919897D01*
X1516434Y920789D01*
X1516861Y921249D01*
X1517012Y921336D01*
X1517712Y920124D01*
X1517561Y920037D01*
G37*
G36*
G01X1514454Y922679D02*
X1514269Y922079D01*
X1513239D01*
X1513054Y922679D01*
Y922853D01*
X1514454D01*
Y922679D01*
G37*
G36*
G01X1510721D02*
X1510536Y922079D01*
X1509506D01*
X1509321Y922679D01*
Y922854D01*
X1510721D01*
Y922679D01*
G37*
G36*
G01X1523671Y919475D02*
X1523486Y918875D01*
X1522456D01*
X1522271Y919475D01*
Y919649D01*
X1523671D01*
Y919475D01*
G37*
G36*
G01X1519971D02*
X1519786Y918875D01*
X1518756D01*
X1518571Y919475D01*
Y919649D01*
X1519971D01*
Y919475D01*
G37*
G36*
G01X1517561Y920037D02*
X1516949Y919897D01*
X1516434Y920789D01*
X1516861Y921249D01*
X1517012Y921336D01*
X1517712Y920124D01*
X1517561Y920037D01*
G37*
G36*
G01X1514454Y922679D02*
X1514269Y922079D01*
X1513239D01*
X1513054Y922679D01*
Y922853D01*
X1514454D01*
Y922679D01*
G37*
G36*
G01X1510721D02*
X1510536Y922079D01*
X1509506D01*
X1509321Y922679D01*
Y922854D01*
X1510721D01*
Y922679D01*
G37*
G36*
G01X1523671Y919475D02*
X1523486Y918875D01*
X1522456D01*
X1522271Y919475D01*
Y919649D01*
X1523671D01*
Y919475D01*
G37*
G36*
G01X1519971D02*
X1519786Y918875D01*
X1518756D01*
X1518571Y919475D01*
Y919649D01*
X1519971D01*
Y919475D01*
G37*
G36*
G01X1513054Y927479D02*
X1513239Y928079D01*
X1514269D01*
X1514454Y927479D01*
Y927305D01*
X1513054D01*
Y927479D01*
G37*
G36*
G01X1509321D02*
X1509506Y928079D01*
X1510536D01*
X1510721Y927479D01*
Y927304D01*
X1509321D01*
Y927479D01*
G37*
G36*
G01X1516754D02*
X1516939Y928079D01*
X1517969D01*
X1518154Y927479D01*
Y927305D01*
X1516754D01*
Y927479D01*
G37*
G36*
G01X1519134Y926911D02*
X1519746Y927051D01*
X1520261Y926159D01*
X1519834Y925699D01*
X1519683Y925612D01*
X1518983Y926824D01*
X1519134Y926911D01*
G37*
G36*
G01X1513054Y927479D02*
X1513239Y928079D01*
X1514269D01*
X1514454Y927479D01*
Y927305D01*
X1513054D01*
Y927479D01*
G37*
G36*
G01X1509321D02*
X1509506Y928079D01*
X1510536D01*
X1510721Y927479D01*
Y927304D01*
X1509321D01*
Y927479D01*
G37*
G36*
G01X1516754D02*
X1516939Y928079D01*
X1517969D01*
X1518154Y927479D01*
Y927305D01*
X1516754D01*
Y927479D01*
G37*
G36*
G01X1519134Y926911D02*
X1519746Y927051D01*
X1520261Y926159D01*
X1519834Y925699D01*
X1519683Y925612D01*
X1518983Y926824D01*
X1519134Y926911D01*
G37*
G36*
G01X1517306Y923669D02*
X1517918Y923809D01*
X1518433Y922917D01*
X1518006Y922457D01*
X1517855Y922370D01*
X1517155Y923582D01*
X1517306Y923669D01*
G37*
G36*
G01X1514837Y924275D02*
X1515022Y924875D01*
X1516052D01*
X1516237Y924275D01*
Y924101D01*
X1514837D01*
Y924275D01*
G37*
G36*
G01X1511147D02*
X1511332Y924875D01*
X1512362D01*
X1512547Y924275D01*
Y924100D01*
X1511147D01*
Y924275D01*
G37*
G36*
G01X1520421Y921071D02*
X1520606Y921671D01*
X1521636D01*
X1521821Y921071D01*
Y920896D01*
X1520421D01*
Y921071D01*
G37*
G36*
G01X1517306Y923669D02*
X1517918Y923809D01*
X1518433Y922917D01*
X1518006Y922457D01*
X1517855Y922370D01*
X1517155Y923582D01*
X1517306Y923669D01*
G37*
G36*
G01X1514837Y924275D02*
X1515022Y924875D01*
X1516052D01*
X1516237Y924275D01*
Y924101D01*
X1514837D01*
Y924275D01*
G37*
G36*
G01X1511147D02*
X1511332Y924875D01*
X1512362D01*
X1512547Y924275D01*
Y924100D01*
X1511147D01*
Y924275D01*
G37*
G36*
G01X1520421Y921071D02*
X1520606Y921671D01*
X1521636D01*
X1521821Y921071D01*
Y920896D01*
X1520421D01*
Y921071D01*
G37*
G36*
G01X1516237Y925883D02*
X1516052Y925283D01*
X1515022D01*
X1514837Y925883D01*
Y926057D01*
X1516237D01*
Y925883D01*
G37*
G36*
G01X1512547D02*
X1512362Y925283D01*
X1511332D01*
X1511147Y925883D01*
Y926058D01*
X1512547D01*
Y925883D01*
G37*
G36*
G01X1521854Y922679D02*
X1521669Y922079D01*
X1520639D01*
X1520454Y922679D01*
Y922853D01*
X1521854D01*
Y922679D01*
G37*
G36*
G01X1519385Y923285D02*
X1518773Y923145D01*
X1518258Y924037D01*
X1518685Y924497D01*
X1518836Y924584D01*
X1519536Y923372D01*
X1519385Y923285D01*
G37*
G36*
G01X1516237Y925883D02*
X1516052Y925283D01*
X1515022D01*
X1514837Y925883D01*
Y926057D01*
X1516237D01*
Y925883D01*
G37*
G36*
G01X1512547D02*
X1512362Y925283D01*
X1511332D01*
X1511147Y925883D01*
Y926058D01*
X1512547D01*
Y925883D01*
G37*
G36*
G01X1521854Y922679D02*
X1521669Y922079D01*
X1520639D01*
X1520454Y922679D01*
Y922853D01*
X1521854D01*
Y922679D01*
G37*
G36*
G01X1519385Y923285D02*
X1518773Y923145D01*
X1518258Y924037D01*
X1518685Y924497D01*
X1518836Y924584D01*
X1519536Y923372D01*
X1519385Y923285D01*
G37*
G36*
G01X1514421Y948313D02*
X1514236Y947713D01*
X1513206D01*
X1513021Y948313D01*
Y948488D01*
X1514421D01*
Y948313D01*
G37*
G36*
G01X1518121D02*
X1517936Y947713D01*
X1516906D01*
X1516721Y948313D01*
Y948488D01*
X1518121D01*
Y948313D01*
G37*
G36*
G01X1510721D02*
X1510536Y947713D01*
X1509506D01*
X1509321Y948313D01*
Y948488D01*
X1510721D01*
Y948313D01*
G37*
G36*
G01X1521821D02*
X1521636Y947713D01*
X1520606D01*
X1520421Y948313D01*
Y948488D01*
X1521821D01*
Y948313D01*
G37*
G36*
G01X1514421D02*
X1514236Y947713D01*
X1513206D01*
X1513021Y948313D01*
Y948488D01*
X1514421D01*
Y948313D01*
G37*
G36*
G01X1518121D02*
X1517936Y947713D01*
X1516906D01*
X1516721Y948313D01*
Y948488D01*
X1518121D01*
Y948313D01*
G37*
G36*
G01X1510721D02*
X1510536Y947713D01*
X1509506D01*
X1509321Y948313D01*
Y948488D01*
X1510721D01*
Y948313D01*
G37*
G36*
G01X1521821D02*
X1521636Y947713D01*
X1520606D01*
X1520421Y948313D01*
Y948488D01*
X1521821D01*
Y948313D01*
G37*
G36*
G01X1516721Y940295D02*
X1516906Y940895D01*
X1517936D01*
X1518121Y940295D01*
Y940121D01*
X1516721D01*
Y940295D01*
G37*
G36*
G01X1513021D02*
X1513206Y940895D01*
X1514236D01*
X1514421Y940295D01*
Y940121D01*
X1513021D01*
Y940295D01*
G37*
G36*
G01X1509321D02*
X1509506Y940895D01*
X1510536D01*
X1510721Y940295D01*
Y940121D01*
X1509321D01*
Y940295D01*
G37*
G36*
G01X1520421D02*
X1520606Y940895D01*
X1521636D01*
X1521821Y940295D01*
Y940121D01*
X1520421D01*
Y940295D01*
G37*
G36*
G01X1516721D02*
X1516906Y940895D01*
X1517936D01*
X1518121Y940295D01*
Y940121D01*
X1516721D01*
Y940295D01*
G37*
G36*
G01X1513021D02*
X1513206Y940895D01*
X1514236D01*
X1514421Y940295D01*
Y940121D01*
X1513021D01*
Y940295D01*
G37*
G36*
G01X1509321D02*
X1509506Y940895D01*
X1510536D01*
X1510721Y940295D01*
Y940121D01*
X1509321D01*
Y940295D01*
G37*
G36*
G01X1520421D02*
X1520606Y940895D01*
X1521636D01*
X1521821Y940295D01*
Y940121D01*
X1520421D01*
Y940295D01*
G37*
G36*
G01X1514871Y937091D02*
X1515056Y937691D01*
X1516086D01*
X1516271Y937091D01*
Y936917D01*
X1514871D01*
Y937091D01*
G37*
G36*
G01X1511171D02*
X1511356Y937691D01*
X1512386D01*
X1512571Y937091D01*
Y936917D01*
X1511171D01*
Y937091D01*
G37*
G36*
G01X1518571D02*
X1518756Y937691D01*
X1519786D01*
X1519971Y937091D01*
Y936917D01*
X1518571D01*
Y937091D01*
G37*
G36*
G01X1514871D02*
X1515056Y937691D01*
X1516086D01*
X1516271Y937091D01*
Y936917D01*
X1514871D01*
Y937091D01*
G37*
G36*
G01X1511171D02*
X1511356Y937691D01*
X1512386D01*
X1512571Y937091D01*
Y936917D01*
X1511171D01*
Y937091D01*
G37*
G36*
G01X1518571D02*
X1518756Y937691D01*
X1519786D01*
X1519971Y937091D01*
Y936917D01*
X1518571D01*
Y937091D01*
G37*
G36*
G01X1516271Y938701D02*
X1516086Y938101D01*
X1515056D01*
X1514871Y938701D01*
Y938875D01*
X1516271D01*
Y938701D01*
G37*
G36*
G01X1512571D02*
X1512386Y938101D01*
X1511356D01*
X1511171Y938701D01*
Y938875D01*
X1512571D01*
Y938701D01*
G37*
G36*
G01X1523671D02*
X1523486Y938101D01*
X1522456D01*
X1522271Y938701D01*
Y938875D01*
X1523671D01*
Y938701D01*
G37*
G36*
G01X1519971D02*
X1519786Y938101D01*
X1518756D01*
X1518571Y938701D01*
Y938875D01*
X1519971D01*
Y938701D01*
G37*
G36*
G01X1516271D02*
X1516086Y938101D01*
X1515056D01*
X1514871Y938701D01*
Y938875D01*
X1516271D01*
Y938701D01*
G37*
G36*
G01X1512571D02*
X1512386Y938101D01*
X1511356D01*
X1511171Y938701D01*
Y938875D01*
X1512571D01*
Y938701D01*
G37*
G36*
G01X1523671D02*
X1523486Y938101D01*
X1522456D01*
X1522271Y938701D01*
Y938875D01*
X1523671D01*
Y938701D01*
G37*
G36*
G01X1519971D02*
X1519786Y938101D01*
X1518756D01*
X1518571Y938701D01*
Y938875D01*
X1519971D01*
Y938701D01*
G37*
G36*
G01X1518121Y935495D02*
X1517936Y934895D01*
X1516906D01*
X1516721Y935495D01*
Y935670D01*
X1518121D01*
Y935495D01*
G37*
G36*
G01X1514421D02*
X1514236Y934895D01*
X1513206D01*
X1513021Y935495D01*
Y935670D01*
X1514421D01*
Y935495D01*
G37*
G36*
G01X1510721D02*
X1510536Y934895D01*
X1509506D01*
X1509321Y935495D01*
Y935670D01*
X1510721D01*
Y935495D01*
G37*
G36*
G01X1521821D02*
X1521636Y934895D01*
X1520606D01*
X1520421Y935495D01*
Y935670D01*
X1521821D01*
Y935495D01*
G37*
G36*
G01X1518121D02*
X1517936Y934895D01*
X1516906D01*
X1516721Y935495D01*
Y935670D01*
X1518121D01*
Y935495D01*
G37*
G36*
G01X1514421D02*
X1514236Y934895D01*
X1513206D01*
X1513021Y935495D01*
Y935670D01*
X1514421D01*
Y935495D01*
G37*
G36*
G01X1510721D02*
X1510536Y934895D01*
X1509506D01*
X1509321Y935495D01*
Y935670D01*
X1510721D01*
Y935495D01*
G37*
G36*
G01X1521821D02*
X1521636Y934895D01*
X1520606D01*
X1520421Y935495D01*
Y935670D01*
X1521821D01*
Y935495D01*
G37*
G36*
G01X1516754Y933889D02*
X1516939Y934489D01*
X1517969D01*
X1518154Y933889D01*
Y933714D01*
X1516754D01*
Y933889D01*
G37*
G36*
G01X1509354D02*
X1509539Y934489D01*
X1510569D01*
X1510754Y933889D01*
Y933714D01*
X1509354D01*
Y933889D01*
G37*
G36*
G01X1513054D02*
X1513239Y934489D01*
X1514269D01*
X1514454Y933889D01*
Y933714D01*
X1513054D01*
Y933889D01*
G37*
G36*
G01X1520454D02*
X1520639Y934489D01*
X1521669D01*
X1521854Y933889D01*
Y933714D01*
X1520454D01*
Y933889D01*
G37*
G36*
G01X1516754D02*
X1516939Y934489D01*
X1517969D01*
X1518154Y933889D01*
Y933714D01*
X1516754D01*
Y933889D01*
G37*
G36*
G01X1509354D02*
X1509539Y934489D01*
X1510569D01*
X1510754Y933889D01*
Y933714D01*
X1509354D01*
Y933889D01*
G37*
G36*
G01X1513054D02*
X1513239Y934489D01*
X1514269D01*
X1514454Y933889D01*
Y933714D01*
X1513054D01*
Y933889D01*
G37*
G36*
G01X1520454D02*
X1520639Y934489D01*
X1521669D01*
X1521854Y933889D01*
Y933714D01*
X1520454D01*
Y933889D01*
G37*
G36*
G01X1516237Y945107D02*
X1516052Y944507D01*
X1515022D01*
X1514837Y945107D01*
Y945282D01*
X1516237D01*
Y945107D01*
G37*
G36*
G01X1512558Y945109D02*
X1512373Y944509D01*
X1511343D01*
X1511158Y945109D01*
Y945283D01*
X1512558D01*
Y945109D01*
G37*
G36*
G01X1523637Y945107D02*
X1523452Y944507D01*
X1522422D01*
X1522237Y945107D01*
Y945282D01*
X1523637D01*
Y945107D01*
G37*
G36*
G01X1519937D02*
X1519752Y944507D01*
X1518722D01*
X1518537Y945107D01*
Y945282D01*
X1519937D01*
Y945107D01*
G37*
G36*
G01X1516237D02*
X1516052Y944507D01*
X1515022D01*
X1514837Y945107D01*
Y945282D01*
X1516237D01*
Y945107D01*
G37*
G36*
G01X1512558Y945109D02*
X1512373Y944509D01*
X1511343D01*
X1511158Y945109D01*
Y945283D01*
X1512558D01*
Y945109D01*
G37*
G36*
G01X1523637Y945107D02*
X1523452Y944507D01*
X1522422D01*
X1522237Y945107D01*
Y945282D01*
X1523637D01*
Y945107D01*
G37*
G36*
G01X1519937D02*
X1519752Y944507D01*
X1518722D01*
X1518537Y945107D01*
Y945282D01*
X1519937D01*
Y945107D01*
G37*
G36*
G01X1514837Y943501D02*
X1515022Y944101D01*
X1516052D01*
X1516237Y943501D01*
Y943326D01*
X1514837D01*
Y943501D01*
G37*
G36*
G01X1511171Y943499D02*
X1511356Y944099D01*
X1512386D01*
X1512571Y943499D01*
Y943324D01*
X1511171D01*
Y943499D01*
G37*
G36*
G01X1518537Y943501D02*
X1518722Y944101D01*
X1519752D01*
X1519937Y943501D01*
Y943326D01*
X1518537D01*
Y943501D01*
G37*
G36*
G01X1522237D02*
X1522422Y944101D01*
X1523452D01*
X1523637Y943501D01*
Y943326D01*
X1522237D01*
Y943501D01*
G37*
G36*
G01X1514837D02*
X1515022Y944101D01*
X1516052D01*
X1516237Y943501D01*
Y943326D01*
X1514837D01*
Y943501D01*
G37*
G36*
G01X1511171Y943499D02*
X1511356Y944099D01*
X1512386D01*
X1512571Y943499D01*
Y943324D01*
X1511171D01*
Y943499D01*
G37*
G36*
G01X1518537Y943501D02*
X1518722Y944101D01*
X1519752D01*
X1519937Y943501D01*
Y943326D01*
X1518537D01*
Y943501D01*
G37*
G36*
G01X1522237D02*
X1522422Y944101D01*
X1523452D01*
X1523637Y943501D01*
Y943326D01*
X1522237D01*
Y943501D01*
G37*
G36*
G01X1516754Y946705D02*
X1516939Y947305D01*
X1517969D01*
X1518154Y946705D01*
Y946531D01*
X1516754D01*
Y946705D01*
G37*
G36*
G01X1513054D02*
X1513239Y947305D01*
X1514269D01*
X1514454Y946705D01*
Y946531D01*
X1513054D01*
Y946705D01*
G37*
G36*
G01X1509321D02*
X1509506Y947305D01*
X1510536D01*
X1510721Y946705D01*
Y946530D01*
X1509321D01*
Y946705D01*
G37*
G36*
G01X1520454D02*
X1520639Y947305D01*
X1521669D01*
X1521854Y946705D01*
Y946531D01*
X1520454D01*
Y946705D01*
G37*
G36*
G01X1516754D02*
X1516939Y947305D01*
X1517969D01*
X1518154Y946705D01*
Y946531D01*
X1516754D01*
Y946705D01*
G37*
G36*
G01X1513054D02*
X1513239Y947305D01*
X1514269D01*
X1514454Y946705D01*
Y946531D01*
X1513054D01*
Y946705D01*
G37*
G36*
G01X1509321D02*
X1509506Y947305D01*
X1510536D01*
X1510721Y946705D01*
Y946530D01*
X1509321D01*
Y946705D01*
G37*
G36*
G01X1520454D02*
X1520639Y947305D01*
X1521669D01*
X1521854Y946705D01*
Y946531D01*
X1520454D01*
Y946705D01*
G37*
G36*
G01X1518154Y941903D02*
X1517969Y941303D01*
X1516939D01*
X1516754Y941903D01*
Y942078D01*
X1518154D01*
Y941903D01*
G37*
G36*
G01X1514454D02*
X1514269Y941303D01*
X1513239D01*
X1513054Y941903D01*
Y942078D01*
X1514454D01*
Y941903D01*
G37*
G36*
G01X1510721Y941905D02*
X1510536Y941305D01*
X1509506D01*
X1509321Y941905D01*
Y942079D01*
X1510721D01*
Y941905D01*
G37*
G36*
G01X1521854Y941903D02*
X1521669Y941303D01*
X1520639D01*
X1520454Y941903D01*
Y942078D01*
X1521854D01*
Y941903D01*
G37*
G36*
G01X1518154D02*
X1517969Y941303D01*
X1516939D01*
X1516754Y941903D01*
Y942078D01*
X1518154D01*
Y941903D01*
G37*
G36*
G01X1514454D02*
X1514269Y941303D01*
X1513239D01*
X1513054Y941903D01*
Y942078D01*
X1514454D01*
Y941903D01*
G37*
G36*
G01X1510721Y941905D02*
X1510536Y941305D01*
X1509506D01*
X1509321Y941905D01*
Y942079D01*
X1510721D01*
Y941905D01*
G37*
G36*
G01X1521854Y941903D02*
X1521669Y941303D01*
X1520639D01*
X1520454Y941903D01*
Y942078D01*
X1521854D01*
Y941903D01*
G37*
G36*
G01X1516721Y953113D02*
X1516906Y953713D01*
X1517936D01*
X1518121Y953113D01*
Y952938D01*
X1516721D01*
Y953113D01*
G37*
G36*
G01X1513021D02*
X1513206Y953713D01*
X1514236D01*
X1514421Y953113D01*
Y952938D01*
X1513021D01*
Y953113D01*
G37*
G36*
G01X1509321D02*
X1509506Y953713D01*
X1510536D01*
X1510721Y953113D01*
Y952938D01*
X1509321D01*
Y953113D01*
G37*
G36*
G01X1520421D02*
X1520606Y953713D01*
X1521636D01*
X1521821Y953113D01*
Y952938D01*
X1520421D01*
Y953113D01*
G37*
G36*
G01X1516721D02*
X1516906Y953713D01*
X1517936D01*
X1518121Y953113D01*
Y952938D01*
X1516721D01*
Y953113D01*
G37*
G36*
G01X1513021D02*
X1513206Y953713D01*
X1514236D01*
X1514421Y953113D01*
Y952938D01*
X1513021D01*
Y953113D01*
G37*
G36*
G01X1509321D02*
X1509506Y953713D01*
X1510536D01*
X1510721Y953113D01*
Y952938D01*
X1509321D01*
Y953113D01*
G37*
G36*
G01X1520421D02*
X1520606Y953713D01*
X1521636D01*
X1521821Y953113D01*
Y952938D01*
X1520421D01*
Y953113D01*
G37*
G36*
G01X1511171Y949909D02*
X1511356Y950509D01*
X1512386D01*
X1512571Y949909D01*
Y949734D01*
X1511171D01*
Y949909D01*
G37*
G36*
G01X1514871D02*
X1515056Y950509D01*
X1516086D01*
X1516271Y949909D01*
Y949734D01*
X1514871D01*
Y949909D01*
G37*
G36*
G01X1518571D02*
X1518756Y950509D01*
X1519786D01*
X1519971Y949909D01*
Y949734D01*
X1518571D01*
Y949909D01*
G37*
G36*
G01X1511171D02*
X1511356Y950509D01*
X1512386D01*
X1512571Y949909D01*
Y949734D01*
X1511171D01*
Y949909D01*
G37*
G36*
G01X1514871D02*
X1515056Y950509D01*
X1516086D01*
X1516271Y949909D01*
Y949734D01*
X1514871D01*
Y949909D01*
G37*
G36*
G01X1518571D02*
X1518756Y950509D01*
X1519786D01*
X1519971Y949909D01*
Y949734D01*
X1518571D01*
Y949909D01*
G37*
G36*
G01X1512571Y951517D02*
X1512386Y950917D01*
X1511356D01*
X1511171Y951517D01*
Y951692D01*
X1512571D01*
Y951517D01*
G37*
G36*
G01X1516271D02*
X1516086Y950917D01*
X1515056D01*
X1514871Y951517D01*
Y951692D01*
X1516271D01*
Y951517D01*
G37*
G36*
G01X1519971D02*
X1519786Y950917D01*
X1518756D01*
X1518571Y951517D01*
Y951692D01*
X1519971D01*
Y951517D01*
G37*
G36*
G01X1523671D02*
X1523486Y950917D01*
X1522456D01*
X1522271Y951517D01*
Y951692D01*
X1523671D01*
Y951517D01*
G37*
G36*
G01X1512571D02*
X1512386Y950917D01*
X1511356D01*
X1511171Y951517D01*
Y951692D01*
X1512571D01*
Y951517D01*
G37*
G36*
G01X1516271D02*
X1516086Y950917D01*
X1515056D01*
X1514871Y951517D01*
Y951692D01*
X1516271D01*
Y951517D01*
G37*
G36*
G01X1519971D02*
X1519786Y950917D01*
X1518756D01*
X1518571Y951517D01*
Y951692D01*
X1519971D01*
Y951517D01*
G37*
G36*
G01X1523671D02*
X1523486Y950917D01*
X1522456D01*
X1522271Y951517D01*
Y951692D01*
X1523671D01*
Y951517D01*
G37*
G36*
G01X1509321Y959521D02*
X1509506Y960121D01*
X1510536D01*
X1510721Y959521D01*
Y959347D01*
X1509321D01*
Y959521D01*
G37*
G36*
G01X1513021D02*
X1513206Y960121D01*
X1514236D01*
X1514421Y959521D01*
Y959347D01*
X1513021D01*
Y959521D01*
G37*
G36*
G01X1509321D02*
X1509506Y960121D01*
X1510536D01*
X1510721Y959521D01*
Y959347D01*
X1509321D01*
Y959521D01*
G37*
G36*
G01X1513021D02*
X1513206Y960121D01*
X1514236D01*
X1514421Y959521D01*
Y959347D01*
X1513021D01*
Y959521D01*
G37*
G36*
G01X1512571Y957927D02*
X1512386Y957327D01*
X1511356D01*
X1511171Y957927D01*
Y958101D01*
X1512571D01*
Y957927D01*
G37*
G36*
G01D02*
X1512386Y957327D01*
X1511356D01*
X1511171Y957927D01*
Y958101D01*
X1512571D01*
Y957927D01*
G37*
G36*
G01X1511147Y962725D02*
X1511332Y963325D01*
X1512362D01*
X1512547Y962725D01*
Y962551D01*
X1511147D01*
Y962725D01*
G37*
G36*
G01D02*
X1511332Y963325D01*
X1512362D01*
X1512547Y962725D01*
Y962551D01*
X1511147D01*
Y962725D01*
G37*
G36*
G01X1510721Y961131D02*
X1510536Y960531D01*
X1509506D01*
X1509321Y961131D01*
Y961305D01*
X1510721D01*
Y961131D01*
G37*
G36*
G01D02*
X1510536Y960531D01*
X1509506D01*
X1509321Y961131D01*
Y961305D01*
X1510721D01*
Y961131D01*
G37*
G36*
G01X1511153Y1006897D02*
X1510968Y1006297D01*
X1509938D01*
X1509753Y1006897D01*
Y1007072D01*
X1511153D01*
Y1006897D01*
G37*
G36*
G01X1514893Y1006895D02*
X1514708Y1006295D01*
X1513678D01*
X1513493Y1006895D01*
Y1007070D01*
X1514893D01*
Y1006895D01*
G37*
G36*
G01X1518587D02*
X1518402Y1006295D01*
X1517372D01*
X1517187Y1006895D01*
Y1007070D01*
X1518587D01*
Y1006895D01*
G37*
G36*
G01X1511153Y1006897D02*
X1510968Y1006297D01*
X1509938D01*
X1509753Y1006897D01*
Y1007072D01*
X1511153D01*
Y1006897D01*
G37*
G36*
G01X1514893Y1006895D02*
X1514708Y1006295D01*
X1513678D01*
X1513493Y1006895D01*
Y1007070D01*
X1514893D01*
Y1006895D01*
G37*
G36*
G01X1518587D02*
X1518402Y1006295D01*
X1517372D01*
X1517187Y1006895D01*
Y1007070D01*
X1518587D01*
Y1006895D01*
G37*
G36*
G01X1513003Y1003693D02*
X1512818Y1003093D01*
X1511788D01*
X1511603Y1003693D01*
Y1003867D01*
X1513003D01*
Y1003693D01*
G37*
G36*
G01X1516670Y1003691D02*
X1516485Y1003091D01*
X1515455D01*
X1515270Y1003691D01*
Y1003866D01*
X1516670D01*
Y1003691D01*
G37*
G36*
G01X1520370D02*
X1520185Y1003091D01*
X1519155D01*
X1518970Y1003691D01*
Y1003866D01*
X1520370D01*
Y1003691D01*
G37*
G36*
G01X1513003Y1003693D02*
X1512818Y1003093D01*
X1511788D01*
X1511603Y1003693D01*
Y1003867D01*
X1513003D01*
Y1003693D01*
G37*
G36*
G01X1516670Y1003691D02*
X1516485Y1003091D01*
X1515455D01*
X1515270Y1003691D01*
Y1003866D01*
X1516670D01*
Y1003691D01*
G37*
G36*
G01X1520370D02*
X1520185Y1003091D01*
X1519155D01*
X1518970Y1003691D01*
Y1003866D01*
X1520370D01*
Y1003691D01*
G37*
G36*
G01X1511603Y1008493D02*
X1511788Y1009093D01*
X1512818D01*
X1513003Y1008493D01*
Y1008318D01*
X1511603D01*
Y1008493D01*
G37*
G36*
G01X1515270D02*
X1515455Y1009093D01*
X1516485D01*
X1516670Y1008493D01*
Y1008319D01*
X1515270D01*
Y1008493D01*
G37*
G36*
G01X1518971D02*
X1519156Y1009093D01*
X1520186D01*
X1520371Y1008493D01*
Y1008319D01*
X1518971D01*
Y1008493D01*
G37*
G36*
G01X1511603D02*
X1511788Y1009093D01*
X1512818D01*
X1513003Y1008493D01*
Y1008318D01*
X1511603D01*
Y1008493D01*
G37*
G36*
G01X1515270D02*
X1515455Y1009093D01*
X1516485D01*
X1516670Y1008493D01*
Y1008319D01*
X1515270D01*
Y1008493D01*
G37*
G36*
G01X1518971D02*
X1519156Y1009093D01*
X1520186D01*
X1520371Y1008493D01*
Y1008319D01*
X1518971D01*
Y1008493D01*
G37*
G36*
G01X1509753Y1005289D02*
X1509938Y1005889D01*
X1510968D01*
X1511153Y1005289D01*
Y1005114D01*
X1509753D01*
Y1005289D01*
G37*
G36*
G01X1513433D02*
X1513618Y1005889D01*
X1514648D01*
X1514833Y1005289D01*
Y1005114D01*
X1513433D01*
Y1005289D01*
G37*
G36*
G01X1517187D02*
X1517372Y1005889D01*
X1518402D01*
X1518587Y1005289D01*
Y1005114D01*
X1517187D01*
Y1005289D01*
G37*
G36*
G01X1520887D02*
X1521072Y1005889D01*
X1522102D01*
X1522287Y1005289D01*
Y1005114D01*
X1520887D01*
Y1005289D01*
G37*
G36*
G01X1509753D02*
X1509938Y1005889D01*
X1510968D01*
X1511153Y1005289D01*
Y1005114D01*
X1509753D01*
Y1005289D01*
G37*
G36*
G01X1513433D02*
X1513618Y1005889D01*
X1514648D01*
X1514833Y1005289D01*
Y1005114D01*
X1513433D01*
Y1005289D01*
G37*
G36*
G01X1517187D02*
X1517372Y1005889D01*
X1518402D01*
X1518587Y1005289D01*
Y1005114D01*
X1517187D01*
Y1005289D01*
G37*
G36*
G01X1520887D02*
X1521072Y1005889D01*
X1522102D01*
X1522287Y1005289D01*
Y1005114D01*
X1520887D01*
Y1005289D01*
G37*
G36*
G01X1523271Y1030345D02*
X1523883Y1030485D01*
X1524398Y1029593D01*
X1523971Y1029133D01*
X1523820Y1029046D01*
X1523120Y1030258D01*
X1523271Y1030345D01*
G37*
G36*
G01D02*
X1523883Y1030485D01*
X1524398Y1029593D01*
X1523971Y1029133D01*
X1523820Y1029046D01*
X1523120Y1030258D01*
X1523271Y1030345D01*
G37*
G36*
G01X1515303Y1027719D02*
X1515488Y1028319D01*
X1516518D01*
X1516703Y1027719D01*
Y1027544D01*
X1515303D01*
Y1027719D01*
G37*
G36*
G01X1511603D02*
X1511788Y1028319D01*
X1512818D01*
X1513003Y1027719D01*
Y1027544D01*
X1511603D01*
Y1027719D01*
G37*
G36*
G01X1521413Y1027156D02*
X1522025Y1027296D01*
X1522540Y1026404D01*
X1522113Y1025944D01*
X1521962Y1025857D01*
X1521262Y1027069D01*
X1521413Y1027156D01*
G37*
G36*
G01X1519003Y1027719D02*
X1519188Y1028319D01*
X1520218D01*
X1520403Y1027719D01*
Y1027544D01*
X1519003D01*
Y1027719D01*
G37*
G36*
G01X1515303D02*
X1515488Y1028319D01*
X1516518D01*
X1516703Y1027719D01*
Y1027544D01*
X1515303D01*
Y1027719D01*
G37*
G36*
G01X1511603D02*
X1511788Y1028319D01*
X1512818D01*
X1513003Y1027719D01*
Y1027544D01*
X1511603D01*
Y1027719D01*
G37*
G36*
G01X1521413Y1027156D02*
X1522025Y1027296D01*
X1522540Y1026404D01*
X1522113Y1025944D01*
X1521962Y1025857D01*
X1521262Y1027069D01*
X1521413Y1027156D01*
G37*
G36*
G01X1519003Y1027719D02*
X1519188Y1028319D01*
X1520218D01*
X1520403Y1027719D01*
Y1027544D01*
X1519003D01*
Y1027719D01*
G37*
G36*
G01X1516703Y1029327D02*
X1516518Y1028727D01*
X1515488D01*
X1515303Y1029327D01*
Y1029502D01*
X1516703D01*
Y1029327D01*
G37*
G36*
G01X1513003D02*
X1512818Y1028727D01*
X1511788D01*
X1511603Y1029327D01*
Y1029502D01*
X1513003D01*
Y1029327D01*
G37*
G36*
G01X1523543Y1026685D02*
X1522931Y1026545D01*
X1522416Y1027437D01*
X1522843Y1027897D01*
X1522994Y1027984D01*
X1523694Y1026772D01*
X1523543Y1026685D01*
G37*
G36*
G01X1520403Y1029327D02*
X1520218Y1028727D01*
X1519188D01*
X1519003Y1029327D01*
Y1029502D01*
X1520403D01*
Y1029327D01*
G37*
G36*
G01X1516703D02*
X1516518Y1028727D01*
X1515488D01*
X1515303Y1029327D01*
Y1029502D01*
X1516703D01*
Y1029327D01*
G37*
G36*
G01X1513003D02*
X1512818Y1028727D01*
X1511788D01*
X1511603Y1029327D01*
Y1029502D01*
X1513003D01*
Y1029327D01*
G37*
G36*
G01X1523543Y1026685D02*
X1522931Y1026545D01*
X1522416Y1027437D01*
X1522843Y1027897D01*
X1522994Y1027984D01*
X1523694Y1026772D01*
X1523543Y1026685D01*
G37*
G36*
G01X1520403Y1029327D02*
X1520218Y1028727D01*
X1519188D01*
X1519003Y1029327D01*
Y1029502D01*
X1520403D01*
Y1029327D01*
G37*
G36*
G01X1518553Y1026123D02*
X1518368Y1025523D01*
X1517338D01*
X1517153Y1026123D01*
Y1026297D01*
X1518553D01*
Y1026123D01*
G37*
G36*
G01X1514853D02*
X1514668Y1025523D01*
X1513638D01*
X1513453Y1026123D01*
Y1026297D01*
X1514853D01*
Y1026123D01*
G37*
G36*
G01X1511153D02*
X1510968Y1025523D01*
X1509938D01*
X1509753Y1026123D01*
Y1026297D01*
X1511153D01*
Y1026123D01*
G37*
G36*
G01X1518553D02*
X1518368Y1025523D01*
X1517338D01*
X1517153Y1026123D01*
Y1026297D01*
X1518553D01*
Y1026123D01*
G37*
G36*
G01X1514853D02*
X1514668Y1025523D01*
X1513638D01*
X1513453Y1026123D01*
Y1026297D01*
X1514853D01*
Y1026123D01*
G37*
G36*
G01X1511153D02*
X1510968Y1025523D01*
X1509938D01*
X1509753Y1026123D01*
Y1026297D01*
X1511153D01*
Y1026123D01*
G37*
G36*
G01X1525360Y1029946D02*
X1524748Y1029806D01*
X1524233Y1030698D01*
X1524660Y1031158D01*
X1524811Y1031245D01*
X1525511Y1030033D01*
X1525360Y1029946D01*
G37*
G36*
G01D02*
X1524748Y1029806D01*
X1524233Y1030698D01*
X1524660Y1031158D01*
X1524811Y1031245D01*
X1525511Y1030033D01*
X1525360Y1029946D01*
G37*
G36*
G01X1509787Y1043741D02*
X1509972Y1044341D01*
X1511002D01*
X1511187Y1043741D01*
Y1043566D01*
X1509787D01*
Y1043741D01*
G37*
G36*
G01X1513487D02*
X1513672Y1044341D01*
X1514702D01*
X1514887Y1043741D01*
Y1043566D01*
X1513487D01*
Y1043741D01*
G37*
G36*
G01X1517187D02*
X1517372Y1044341D01*
X1518402D01*
X1518587Y1043741D01*
Y1043566D01*
X1517187D01*
Y1043741D01*
G37*
G36*
G01X1520887D02*
X1521072Y1044341D01*
X1522102D01*
X1522287Y1043741D01*
Y1043566D01*
X1520887D01*
Y1043741D01*
G37*
G36*
G01X1509787D02*
X1509972Y1044341D01*
X1511002D01*
X1511187Y1043741D01*
Y1043566D01*
X1509787D01*
Y1043741D01*
G37*
G36*
G01X1513487D02*
X1513672Y1044341D01*
X1514702D01*
X1514887Y1043741D01*
Y1043566D01*
X1513487D01*
Y1043741D01*
G37*
G36*
G01X1517187D02*
X1517372Y1044341D01*
X1518402D01*
X1518587Y1043741D01*
Y1043566D01*
X1517187D01*
Y1043741D01*
G37*
G36*
G01X1520887D02*
X1521072Y1044341D01*
X1522102D01*
X1522287Y1043741D01*
Y1043566D01*
X1520887D01*
Y1043741D01*
G37*
G36*
G01X1515303Y1040535D02*
X1515488Y1041135D01*
X1516518D01*
X1516703Y1040535D01*
Y1040361D01*
X1515303D01*
Y1040535D01*
G37*
G36*
G01X1511603D02*
X1511788Y1041135D01*
X1512818D01*
X1513003Y1040535D01*
Y1040361D01*
X1511603D01*
Y1040535D01*
G37*
G36*
G01X1518970Y1040537D02*
X1519155Y1041137D01*
X1520185D01*
X1520370Y1040537D01*
Y1040362D01*
X1518970D01*
Y1040537D01*
G37*
G36*
G01X1522670D02*
X1522855Y1041137D01*
X1523885D01*
X1524070Y1040537D01*
Y1040362D01*
X1522670D01*
Y1040537D01*
G37*
G36*
G01X1515303Y1040535D02*
X1515488Y1041135D01*
X1516518D01*
X1516703Y1040535D01*
Y1040361D01*
X1515303D01*
Y1040535D01*
G37*
G36*
G01X1511603D02*
X1511788Y1041135D01*
X1512818D01*
X1513003Y1040535D01*
Y1040361D01*
X1511603D01*
Y1040535D01*
G37*
G36*
G01X1518970Y1040537D02*
X1519155Y1041137D01*
X1520185D01*
X1520370Y1040537D01*
Y1040362D01*
X1518970D01*
Y1040537D01*
G37*
G36*
G01X1522670D02*
X1522855Y1041137D01*
X1523885D01*
X1524070Y1040537D01*
Y1040362D01*
X1522670D01*
Y1040537D01*
G37*
G36*
G01X1512970Y1042143D02*
X1512785Y1041543D01*
X1511755D01*
X1511570Y1042143D01*
Y1042318D01*
X1512970D01*
Y1042143D01*
G37*
G36*
G01X1516670D02*
X1516485Y1041543D01*
X1515455D01*
X1515270Y1042143D01*
Y1042318D01*
X1516670D01*
Y1042143D01*
G37*
G36*
G01X1520370D02*
X1520185Y1041543D01*
X1519155D01*
X1518970Y1042143D01*
Y1042318D01*
X1520370D01*
Y1042143D01*
G37*
G36*
G01X1524070D02*
X1523885Y1041543D01*
X1522855D01*
X1522670Y1042143D01*
Y1042318D01*
X1524070D01*
Y1042143D01*
G37*
G36*
G01X1512970D02*
X1512785Y1041543D01*
X1511755D01*
X1511570Y1042143D01*
Y1042318D01*
X1512970D01*
Y1042143D01*
G37*
G36*
G01X1516670D02*
X1516485Y1041543D01*
X1515455D01*
X1515270Y1042143D01*
Y1042318D01*
X1516670D01*
Y1042143D01*
G37*
G36*
G01X1520370D02*
X1520185Y1041543D01*
X1519155D01*
X1518970Y1042143D01*
Y1042318D01*
X1520370D01*
Y1042143D01*
G37*
G36*
G01X1524070D02*
X1523885Y1041543D01*
X1522855D01*
X1522670Y1042143D01*
Y1042318D01*
X1524070D01*
Y1042143D01*
G37*
G36*
G01X1511153Y1038941D02*
X1510968Y1038341D01*
X1509938D01*
X1509753Y1038941D01*
Y1039115D01*
X1511153D01*
Y1038941D01*
G37*
G36*
G01X1514853D02*
X1514668Y1038341D01*
X1513638D01*
X1513453Y1038941D01*
Y1039115D01*
X1514853D01*
Y1038941D01*
G37*
G36*
G01X1518577Y1038939D02*
X1518392Y1038339D01*
X1517362D01*
X1517177Y1038939D01*
Y1039114D01*
X1518577D01*
Y1038939D01*
G37*
G36*
G01X1522287D02*
X1522102Y1038339D01*
X1521072D01*
X1520887Y1038939D01*
Y1039114D01*
X1522287D01*
Y1038939D01*
G37*
G36*
G01X1511153Y1038941D02*
X1510968Y1038341D01*
X1509938D01*
X1509753Y1038941D01*
Y1039115D01*
X1511153D01*
Y1038941D01*
G37*
G36*
G01X1514853D02*
X1514668Y1038341D01*
X1513638D01*
X1513453Y1038941D01*
Y1039115D01*
X1514853D01*
Y1038941D01*
G37*
G36*
G01X1518577Y1038939D02*
X1518392Y1038339D01*
X1517362D01*
X1517177Y1038939D01*
Y1039114D01*
X1518577D01*
Y1038939D01*
G37*
G36*
G01X1522287D02*
X1522102Y1038339D01*
X1521072D01*
X1520887Y1038939D01*
Y1039114D01*
X1522287D01*
Y1038939D01*
G37*
G36*
G01X1517153Y1030923D02*
X1517338Y1031523D01*
X1518368D01*
X1518553Y1030923D01*
Y1030748D01*
X1517153D01*
Y1030923D01*
G37*
G36*
G01X1513453D02*
X1513638Y1031523D01*
X1514668D01*
X1514853Y1030923D01*
Y1030748D01*
X1513453D01*
Y1030923D01*
G37*
G36*
G01X1509753D02*
X1509938Y1031523D01*
X1510968D01*
X1511153Y1030923D01*
Y1030748D01*
X1509753D01*
Y1030923D01*
G37*
G36*
G01X1520853D02*
X1521038Y1031523D01*
X1522068D01*
X1522253Y1030923D01*
Y1030748D01*
X1520853D01*
Y1030923D01*
G37*
G36*
G01X1517153D02*
X1517338Y1031523D01*
X1518368D01*
X1518553Y1030923D01*
Y1030748D01*
X1517153D01*
Y1030923D01*
G37*
G36*
G01X1513453D02*
X1513638Y1031523D01*
X1514668D01*
X1514853Y1030923D01*
Y1030748D01*
X1513453D01*
Y1030923D01*
G37*
G36*
G01X1509753D02*
X1509938Y1031523D01*
X1510968D01*
X1511153Y1030923D01*
Y1030748D01*
X1509753D01*
Y1030923D01*
G37*
G36*
G01X1520853D02*
X1521038Y1031523D01*
X1522068D01*
X1522253Y1030923D01*
Y1030748D01*
X1520853D01*
Y1030923D01*
G37*
G36*
G01X1515270Y1046945D02*
X1515455Y1047545D01*
X1516485D01*
X1516670Y1046945D01*
Y1046771D01*
X1515270D01*
Y1046945D01*
G37*
G36*
G01X1511570D02*
X1511755Y1047545D01*
X1512785D01*
X1512970Y1046945D01*
Y1046771D01*
X1511570D01*
Y1046945D01*
G37*
G36*
G01X1522670D02*
X1522855Y1047545D01*
X1523885D01*
X1524070Y1046945D01*
Y1046771D01*
X1522670D01*
Y1046945D01*
G37*
G36*
G01X1518970D02*
X1519155Y1047545D01*
X1520185D01*
X1520370Y1046945D01*
Y1046771D01*
X1518970D01*
Y1046945D01*
G37*
G36*
G01X1515270D02*
X1515455Y1047545D01*
X1516485D01*
X1516670Y1046945D01*
Y1046771D01*
X1515270D01*
Y1046945D01*
G37*
G36*
G01X1511570D02*
X1511755Y1047545D01*
X1512785D01*
X1512970Y1046945D01*
Y1046771D01*
X1511570D01*
Y1046945D01*
G37*
G36*
G01X1522670D02*
X1522855Y1047545D01*
X1523885D01*
X1524070Y1046945D01*
Y1046771D01*
X1522670D01*
Y1046945D01*
G37*
G36*
G01X1518970D02*
X1519155Y1047545D01*
X1520185D01*
X1520370Y1046945D01*
Y1046771D01*
X1518970D01*
Y1046945D01*
G37*
G36*
G01X1518587Y1045347D02*
X1518402Y1044747D01*
X1517372D01*
X1517187Y1045347D01*
Y1045522D01*
X1518587D01*
Y1045347D01*
G37*
G36*
G01X1514887D02*
X1514702Y1044747D01*
X1513672D01*
X1513487Y1045347D01*
Y1045522D01*
X1514887D01*
Y1045347D01*
G37*
G36*
G01X1511187D02*
X1511002Y1044747D01*
X1509972D01*
X1509787Y1045347D01*
Y1045522D01*
X1511187D01*
Y1045347D01*
G37*
G36*
G01X1525987D02*
X1525802Y1044747D01*
X1524772D01*
X1524587Y1045347D01*
Y1045522D01*
X1525987D01*
Y1045347D01*
G37*
G36*
G01X1522287D02*
X1522102Y1044747D01*
X1521072D01*
X1520887Y1045347D01*
Y1045522D01*
X1522287D01*
Y1045347D01*
G37*
G36*
G01X1518587D02*
X1518402Y1044747D01*
X1517372D01*
X1517187Y1045347D01*
Y1045522D01*
X1518587D01*
Y1045347D01*
G37*
G36*
G01X1514887D02*
X1514702Y1044747D01*
X1513672D01*
X1513487Y1045347D01*
Y1045522D01*
X1514887D01*
Y1045347D01*
G37*
G36*
G01X1511187D02*
X1511002Y1044747D01*
X1509972D01*
X1509787Y1045347D01*
Y1045522D01*
X1511187D01*
Y1045347D01*
G37*
G36*
G01X1525987D02*
X1525802Y1044747D01*
X1524772D01*
X1524587Y1045347D01*
Y1045522D01*
X1525987D01*
Y1045347D01*
G37*
G36*
G01X1522287D02*
X1522102Y1044747D01*
X1521072D01*
X1520887Y1045347D01*
Y1045522D01*
X1522287D01*
Y1045347D01*
G37*
G36*
G01X1516703Y1035735D02*
X1516518Y1035135D01*
X1515488D01*
X1515303Y1035735D01*
Y1035910D01*
X1516703D01*
Y1035735D01*
G37*
G36*
G01X1513003D02*
X1512818Y1035135D01*
X1511788D01*
X1511603Y1035735D01*
Y1035910D01*
X1513003D01*
Y1035735D01*
G37*
G36*
G01X1524137D02*
X1523952Y1035135D01*
X1522922D01*
X1522737Y1035735D01*
Y1035909D01*
X1524137D01*
Y1035735D01*
G37*
G36*
G01X1520427D02*
X1520242Y1035135D01*
X1519212D01*
X1519027Y1035735D01*
Y1035909D01*
X1520427D01*
Y1035735D01*
G37*
G36*
G01X1516703D02*
X1516518Y1035135D01*
X1515488D01*
X1515303Y1035735D01*
Y1035910D01*
X1516703D01*
Y1035735D01*
G37*
G36*
G01X1513003D02*
X1512818Y1035135D01*
X1511788D01*
X1511603Y1035735D01*
Y1035910D01*
X1513003D01*
Y1035735D01*
G37*
G36*
G01X1524137D02*
X1523952Y1035135D01*
X1522922D01*
X1522737Y1035735D01*
Y1035909D01*
X1524137D01*
Y1035735D01*
G37*
G36*
G01X1520427D02*
X1520242Y1035135D01*
X1519212D01*
X1519027Y1035735D01*
Y1035909D01*
X1520427D01*
Y1035735D01*
G37*
G36*
G01X1515303Y1034127D02*
X1515488Y1034727D01*
X1516518D01*
X1516703Y1034127D01*
Y1033952D01*
X1515303D01*
Y1034127D01*
G37*
G36*
G01X1511603D02*
X1511788Y1034727D01*
X1512818D01*
X1513003Y1034127D01*
Y1033952D01*
X1511603D01*
Y1034127D01*
G37*
G36*
G01X1525117Y1033559D02*
X1525729Y1033699D01*
X1526244Y1032807D01*
X1525817Y1032347D01*
X1525666Y1032260D01*
X1524966Y1033472D01*
X1525117Y1033559D01*
G37*
G36*
G01X1522737Y1034127D02*
X1522922Y1034727D01*
X1523952D01*
X1524137Y1034127D01*
Y1033953D01*
X1522737D01*
Y1034127D01*
G37*
G36*
G01X1519027D02*
X1519212Y1034727D01*
X1520242D01*
X1520427Y1034127D01*
Y1033953D01*
X1519027D01*
Y1034127D01*
G37*
G36*
G01X1515303D02*
X1515488Y1034727D01*
X1516518D01*
X1516703Y1034127D01*
Y1033952D01*
X1515303D01*
Y1034127D01*
G37*
G36*
G01X1511603D02*
X1511788Y1034727D01*
X1512818D01*
X1513003Y1034127D01*
Y1033952D01*
X1511603D01*
Y1034127D01*
G37*
G36*
G01X1525117Y1033559D02*
X1525729Y1033699D01*
X1526244Y1032807D01*
X1525817Y1032347D01*
X1525666Y1032260D01*
X1524966Y1033472D01*
X1525117Y1033559D01*
G37*
G36*
G01X1522737Y1034127D02*
X1522922Y1034727D01*
X1523952D01*
X1524137Y1034127D01*
Y1033953D01*
X1522737D01*
Y1034127D01*
G37*
G36*
G01X1519027D02*
X1519212Y1034727D01*
X1520242D01*
X1520427Y1034127D01*
Y1033953D01*
X1519027D01*
Y1034127D01*
G37*
G36*
G01X1517153Y1037331D02*
X1517338Y1037931D01*
X1518368D01*
X1518553Y1037331D01*
Y1037157D01*
X1517153D01*
Y1037331D01*
G37*
G36*
G01X1513453D02*
X1513638Y1037931D01*
X1514668D01*
X1514853Y1037331D01*
Y1037157D01*
X1513453D01*
Y1037331D01*
G37*
G36*
G01X1509753Y1037329D02*
X1509938Y1037929D01*
X1510968D01*
X1511153Y1037329D01*
Y1037154D01*
X1509753D01*
Y1037329D01*
G37*
G36*
G01X1524553D02*
X1524738Y1037929D01*
X1525768D01*
X1525953Y1037329D01*
Y1037155D01*
X1524553D01*
Y1037329D01*
G37*
G36*
G01X1520820Y1037333D02*
X1521005Y1037933D01*
X1522035D01*
X1522220Y1037333D01*
Y1037158D01*
X1520820D01*
Y1037333D01*
G37*
G36*
G01X1517153Y1037331D02*
X1517338Y1037931D01*
X1518368D01*
X1518553Y1037331D01*
Y1037157D01*
X1517153D01*
Y1037331D01*
G37*
G36*
G01X1513453D02*
X1513638Y1037931D01*
X1514668D01*
X1514853Y1037331D01*
Y1037157D01*
X1513453D01*
Y1037331D01*
G37*
G36*
G01X1509753Y1037329D02*
X1509938Y1037929D01*
X1510968D01*
X1511153Y1037329D01*
Y1037154D01*
X1509753D01*
Y1037329D01*
G37*
G36*
G01X1524553D02*
X1524738Y1037929D01*
X1525768D01*
X1525953Y1037329D01*
Y1037155D01*
X1524553D01*
Y1037329D01*
G37*
G36*
G01X1520820Y1037333D02*
X1521005Y1037933D01*
X1522035D01*
X1522220Y1037333D01*
Y1037158D01*
X1520820D01*
Y1037333D01*
G37*
G36*
G01X1518553Y1032531D02*
X1518368Y1031931D01*
X1517338D01*
X1517153Y1032531D01*
Y1032706D01*
X1518553D01*
Y1032531D01*
G37*
G36*
G01X1514852D02*
X1514667Y1031931D01*
X1513637D01*
X1513452Y1032531D01*
Y1032705D01*
X1514852D01*
Y1032531D01*
G37*
G36*
G01X1511152D02*
X1510967Y1031931D01*
X1509937D01*
X1509752Y1032531D01*
Y1032705D01*
X1511152D01*
Y1032531D01*
G37*
G36*
G01X1522220D02*
X1522035Y1031931D01*
X1521005D01*
X1520820Y1032531D01*
Y1032705D01*
X1522220D01*
Y1032531D01*
G37*
G36*
G01X1518553D02*
X1518368Y1031931D01*
X1517338D01*
X1517153Y1032531D01*
Y1032706D01*
X1518553D01*
Y1032531D01*
G37*
G36*
G01X1514852D02*
X1514667Y1031931D01*
X1513637D01*
X1513452Y1032531D01*
Y1032705D01*
X1514852D01*
Y1032531D01*
G37*
G36*
G01X1511152D02*
X1510967Y1031931D01*
X1509937D01*
X1509752Y1032531D01*
Y1032705D01*
X1511152D01*
Y1032531D01*
G37*
G36*
G01X1522220D02*
X1522035Y1031931D01*
X1521005D01*
X1520820Y1032531D01*
Y1032705D01*
X1522220D01*
Y1032531D01*
G37*
G36*
G01X1517187Y1062967D02*
X1517372Y1063567D01*
X1518402D01*
X1518587Y1062967D01*
Y1062792D01*
X1517187D01*
Y1062967D01*
G37*
G36*
G01X1513487D02*
X1513672Y1063567D01*
X1514702D01*
X1514887Y1062967D01*
Y1062792D01*
X1513487D01*
Y1062967D01*
G37*
G36*
G01X1509787D02*
X1509972Y1063567D01*
X1511002D01*
X1511187Y1062967D01*
Y1062792D01*
X1509787D01*
Y1062967D01*
G37*
G36*
G01X1520887D02*
X1521072Y1063567D01*
X1522102D01*
X1522287Y1062967D01*
Y1062792D01*
X1520887D01*
Y1062967D01*
G37*
G36*
G01X1517187D02*
X1517372Y1063567D01*
X1518402D01*
X1518587Y1062967D01*
Y1062792D01*
X1517187D01*
Y1062967D01*
G37*
G36*
G01X1513487D02*
X1513672Y1063567D01*
X1514702D01*
X1514887Y1062967D01*
Y1062792D01*
X1513487D01*
Y1062967D01*
G37*
G36*
G01X1509787D02*
X1509972Y1063567D01*
X1511002D01*
X1511187Y1062967D01*
Y1062792D01*
X1509787D01*
Y1062967D01*
G37*
G36*
G01X1520887D02*
X1521072Y1063567D01*
X1522102D01*
X1522287Y1062967D01*
Y1062792D01*
X1520887D01*
Y1062967D01*
G37*
G36*
G01X1511603Y1059761D02*
X1511788Y1060361D01*
X1512818D01*
X1513003Y1059761D01*
Y1059586D01*
X1511603D01*
Y1059761D01*
G37*
G36*
G01X1515302D02*
X1515487Y1060361D01*
X1516517D01*
X1516702Y1059761D01*
Y1059586D01*
X1515302D01*
Y1059761D01*
G37*
G36*
G01X1518977D02*
X1519162Y1060361D01*
X1520192D01*
X1520377Y1059761D01*
Y1059586D01*
X1518977D01*
Y1059761D01*
G37*
G36*
G01X1522676D02*
X1522861Y1060361D01*
X1523891D01*
X1524076Y1059761D01*
Y1059586D01*
X1522676D01*
Y1059761D01*
G37*
G36*
G01X1511603D02*
X1511788Y1060361D01*
X1512818D01*
X1513003Y1059761D01*
Y1059586D01*
X1511603D01*
Y1059761D01*
G37*
G36*
G01X1515302D02*
X1515487Y1060361D01*
X1516517D01*
X1516702Y1059761D01*
Y1059586D01*
X1515302D01*
Y1059761D01*
G37*
G36*
G01X1518977D02*
X1519162Y1060361D01*
X1520192D01*
X1520377Y1059761D01*
Y1059586D01*
X1518977D01*
Y1059761D01*
G37*
G36*
G01X1522676D02*
X1522861Y1060361D01*
X1523891D01*
X1524076Y1059761D01*
Y1059586D01*
X1522676D01*
Y1059761D01*
G37*
G36*
G01X1516670Y1061369D02*
X1516485Y1060769D01*
X1515455D01*
X1515270Y1061369D01*
Y1061543D01*
X1516670D01*
Y1061369D01*
G37*
G36*
G01X1512970D02*
X1512785Y1060769D01*
X1511755D01*
X1511570Y1061369D01*
Y1061543D01*
X1512970D01*
Y1061369D01*
G37*
G36*
G01X1520370D02*
X1520185Y1060769D01*
X1519155D01*
X1518970Y1061369D01*
Y1061543D01*
X1520370D01*
Y1061369D01*
G37*
G36*
G01X1524070D02*
X1523885Y1060769D01*
X1522855D01*
X1522670Y1061369D01*
Y1061543D01*
X1524070D01*
Y1061369D01*
G37*
G36*
G01X1516670D02*
X1516485Y1060769D01*
X1515455D01*
X1515270Y1061369D01*
Y1061543D01*
X1516670D01*
Y1061369D01*
G37*
G36*
G01X1512970D02*
X1512785Y1060769D01*
X1511755D01*
X1511570Y1061369D01*
Y1061543D01*
X1512970D01*
Y1061369D01*
G37*
G36*
G01X1520370D02*
X1520185Y1060769D01*
X1519155D01*
X1518970Y1061369D01*
Y1061543D01*
X1520370D01*
Y1061369D01*
G37*
G36*
G01X1524070D02*
X1523885Y1060769D01*
X1522855D01*
X1522670Y1061369D01*
Y1061543D01*
X1524070D01*
Y1061369D01*
G37*
G36*
G01X1518575Y1058165D02*
X1518390Y1057565D01*
X1517360D01*
X1517175Y1058165D01*
Y1058340D01*
X1518575D01*
Y1058165D01*
G37*
G36*
G01X1511177D02*
X1510992Y1057565D01*
X1509962D01*
X1509777Y1058165D01*
Y1058340D01*
X1511177D01*
Y1058165D01*
G37*
G36*
G01X1514829D02*
X1514644Y1057565D01*
X1513614D01*
X1513429Y1058165D01*
Y1058340D01*
X1514829D01*
Y1058165D01*
G37*
G36*
G01X1525973D02*
X1525788Y1057565D01*
X1524758D01*
X1524573Y1058165D01*
Y1058340D01*
X1525973D01*
Y1058165D01*
G37*
G36*
G01X1522274D02*
X1522089Y1057565D01*
X1521059D01*
X1520874Y1058165D01*
Y1058340D01*
X1522274D01*
Y1058165D01*
G37*
G36*
G01X1518575D02*
X1518390Y1057565D01*
X1517360D01*
X1517175Y1058165D01*
Y1058340D01*
X1518575D01*
Y1058165D01*
G37*
G36*
G01X1511177D02*
X1510992Y1057565D01*
X1509962D01*
X1509777Y1058165D01*
Y1058340D01*
X1511177D01*
Y1058165D01*
G37*
G36*
G01X1514829D02*
X1514644Y1057565D01*
X1513614D01*
X1513429Y1058165D01*
Y1058340D01*
X1514829D01*
Y1058165D01*
G37*
G36*
G01X1525973D02*
X1525788Y1057565D01*
X1524758D01*
X1524573Y1058165D01*
Y1058340D01*
X1525973D01*
Y1058165D01*
G37*
G36*
G01X1522274D02*
X1522089Y1057565D01*
X1521059D01*
X1520874Y1058165D01*
Y1058340D01*
X1522274D01*
Y1058165D01*
G37*
G36*
G01X1517128Y1050149D02*
X1517313Y1050749D01*
X1518343D01*
X1518528Y1050149D01*
Y1049974D01*
X1517128D01*
Y1050149D01*
G37*
G36*
G01X1513429D02*
X1513614Y1050749D01*
X1514644D01*
X1514829Y1050149D01*
Y1049974D01*
X1513429D01*
Y1050149D01*
G37*
G36*
G01X1509777D02*
X1509962Y1050749D01*
X1510992D01*
X1511177Y1050149D01*
Y1049974D01*
X1509777D01*
Y1050149D01*
G37*
G36*
G01X1524526D02*
X1524711Y1050749D01*
X1525741D01*
X1525926Y1050149D01*
Y1049974D01*
X1524526D01*
Y1050149D01*
G37*
G36*
G01X1520827D02*
X1521012Y1050749D01*
X1522042D01*
X1522227Y1050149D01*
Y1049974D01*
X1520827D01*
Y1050149D01*
G37*
G36*
G01X1517128D02*
X1517313Y1050749D01*
X1518343D01*
X1518528Y1050149D01*
Y1049974D01*
X1517128D01*
Y1050149D01*
G37*
G36*
G01X1513429D02*
X1513614Y1050749D01*
X1514644D01*
X1514829Y1050149D01*
Y1049974D01*
X1513429D01*
Y1050149D01*
G37*
G36*
G01X1509777D02*
X1509962Y1050749D01*
X1510992D01*
X1511177Y1050149D01*
Y1049974D01*
X1509777D01*
Y1050149D01*
G37*
G36*
G01X1524526D02*
X1524711Y1050749D01*
X1525741D01*
X1525926Y1050149D01*
Y1049974D01*
X1524526D01*
Y1050149D01*
G37*
G36*
G01X1520827D02*
X1521012Y1050749D01*
X1522042D01*
X1522227Y1050149D01*
Y1049974D01*
X1520827D01*
Y1050149D01*
G37*
G36*
G01X1516726Y1048553D02*
X1516541Y1047953D01*
X1515511D01*
X1515326Y1048553D01*
Y1048727D01*
X1516726D01*
Y1048553D01*
G37*
G36*
G01X1513003D02*
X1512818Y1047953D01*
X1511788D01*
X1511603Y1048553D01*
Y1048727D01*
X1513003D01*
Y1048553D01*
G37*
G36*
G01X1524124D02*
X1523939Y1047953D01*
X1522909D01*
X1522724Y1048553D01*
Y1048727D01*
X1524124D01*
Y1048553D01*
G37*
G36*
G01X1520425D02*
X1520240Y1047953D01*
X1519210D01*
X1519025Y1048553D01*
Y1048727D01*
X1520425D01*
Y1048553D01*
G37*
G36*
G01X1516726D02*
X1516541Y1047953D01*
X1515511D01*
X1515326Y1048553D01*
Y1048727D01*
X1516726D01*
Y1048553D01*
G37*
G36*
G01X1513003D02*
X1512818Y1047953D01*
X1511788D01*
X1511603Y1048553D01*
Y1048727D01*
X1513003D01*
Y1048553D01*
G37*
G36*
G01X1524124D02*
X1523939Y1047953D01*
X1522909D01*
X1522724Y1048553D01*
Y1048727D01*
X1524124D01*
Y1048553D01*
G37*
G36*
G01X1520425D02*
X1520240Y1047953D01*
X1519210D01*
X1519025Y1048553D01*
Y1048727D01*
X1520425D01*
Y1048553D01*
G37*
G36*
G01X1516736Y1054961D02*
X1516551Y1054361D01*
X1515521D01*
X1515336Y1054961D01*
Y1055135D01*
X1516736D01*
Y1054961D01*
G37*
G36*
G01X1513003D02*
X1512818Y1054361D01*
X1511788D01*
X1511603Y1054961D01*
Y1055136D01*
X1513003D01*
Y1054961D01*
G37*
G36*
G01X1524134D02*
X1523949Y1054361D01*
X1522919D01*
X1522734Y1054961D01*
Y1055136D01*
X1524134D01*
Y1054961D01*
G37*
G36*
G01X1520435D02*
X1520250Y1054361D01*
X1519220D01*
X1519035Y1054961D01*
Y1055135D01*
X1520435D01*
Y1054961D01*
G37*
G36*
G01X1516736D02*
X1516551Y1054361D01*
X1515521D01*
X1515336Y1054961D01*
Y1055135D01*
X1516736D01*
Y1054961D01*
G37*
G36*
G01X1513003D02*
X1512818Y1054361D01*
X1511788D01*
X1511603Y1054961D01*
Y1055136D01*
X1513003D01*
Y1054961D01*
G37*
G36*
G01X1524134D02*
X1523949Y1054361D01*
X1522919D01*
X1522734Y1054961D01*
Y1055136D01*
X1524134D01*
Y1054961D01*
G37*
G36*
G01X1520435D02*
X1520250Y1054361D01*
X1519220D01*
X1519035Y1054961D01*
Y1055135D01*
X1520435D01*
Y1054961D01*
G37*
G36*
G01X1515336Y1053353D02*
X1515521Y1053953D01*
X1516551D01*
X1516736Y1053353D01*
Y1053179D01*
X1515336D01*
Y1053353D01*
G37*
G36*
G01X1511603D02*
X1511788Y1053953D01*
X1512818D01*
X1513003Y1053353D01*
Y1053178D01*
X1511603D01*
Y1053353D01*
G37*
G36*
G01X1522724D02*
X1522909Y1053953D01*
X1523939D01*
X1524124Y1053353D01*
Y1053178D01*
X1522724D01*
Y1053353D01*
G37*
G36*
G01X1519035D02*
X1519220Y1053953D01*
X1520250D01*
X1520435Y1053353D01*
Y1053179D01*
X1519035D01*
Y1053353D01*
G37*
G36*
G01X1515336D02*
X1515521Y1053953D01*
X1516551D01*
X1516736Y1053353D01*
Y1053179D01*
X1515336D01*
Y1053353D01*
G37*
G36*
G01X1511603D02*
X1511788Y1053953D01*
X1512818D01*
X1513003Y1053353D01*
Y1053178D01*
X1511603D01*
Y1053353D01*
G37*
G36*
G01X1522724D02*
X1522909Y1053953D01*
X1523939D01*
X1524124Y1053353D01*
Y1053178D01*
X1522724D01*
Y1053353D01*
G37*
G36*
G01X1519035D02*
X1519220Y1053953D01*
X1520250D01*
X1520435Y1053353D01*
Y1053179D01*
X1519035D01*
Y1053353D01*
G37*
G36*
G01X1517119Y1056557D02*
X1517304Y1057157D01*
X1518334D01*
X1518519Y1056557D01*
Y1056383D01*
X1517119D01*
Y1056557D01*
G37*
G36*
G01X1513429D02*
X1513614Y1057157D01*
X1514644D01*
X1514829Y1056557D01*
Y1056382D01*
X1513429D01*
Y1056557D01*
G37*
G36*
G01X1509777D02*
X1509962Y1057157D01*
X1510992D01*
X1511177Y1056557D01*
Y1056382D01*
X1509777D01*
Y1056557D01*
G37*
G36*
G01X1524526D02*
X1524711Y1057157D01*
X1525741D01*
X1525926Y1056557D01*
Y1056382D01*
X1524526D01*
Y1056557D01*
G37*
G36*
G01X1520811D02*
X1520996Y1057157D01*
X1522026D01*
X1522211Y1056557D01*
Y1056382D01*
X1520811D01*
Y1056557D01*
G37*
G36*
G01X1517119D02*
X1517304Y1057157D01*
X1518334D01*
X1518519Y1056557D01*
Y1056383D01*
X1517119D01*
Y1056557D01*
G37*
G36*
G01X1513429D02*
X1513614Y1057157D01*
X1514644D01*
X1514829Y1056557D01*
Y1056382D01*
X1513429D01*
Y1056557D01*
G37*
G36*
G01X1509777D02*
X1509962Y1057157D01*
X1510992D01*
X1511177Y1056557D01*
Y1056382D01*
X1509777D01*
Y1056557D01*
G37*
G36*
G01X1524526D02*
X1524711Y1057157D01*
X1525741D01*
X1525926Y1056557D01*
Y1056382D01*
X1524526D01*
Y1056557D01*
G37*
G36*
G01X1520811D02*
X1520996Y1057157D01*
X1522026D01*
X1522211Y1056557D01*
Y1056382D01*
X1520811D01*
Y1056557D01*
G37*
G36*
G01X1511177Y1051757D02*
X1510992Y1051157D01*
X1509962D01*
X1509777Y1051757D01*
Y1051931D01*
X1511177D01*
Y1051757D01*
G37*
G36*
G01X1518519Y1051755D02*
X1518334Y1051155D01*
X1517304D01*
X1517119Y1051755D01*
Y1051930D01*
X1518519D01*
Y1051755D01*
G37*
G36*
G01X1514829Y1051757D02*
X1514644Y1051157D01*
X1513614D01*
X1513429Y1051757D01*
Y1051931D01*
X1514829D01*
Y1051757D01*
G37*
G36*
G01X1525973D02*
X1525788Y1051157D01*
X1524758D01*
X1524573Y1051757D01*
Y1051931D01*
X1525973D01*
Y1051757D01*
G37*
G36*
G01X1522211D02*
X1522026Y1051157D01*
X1520996D01*
X1520811Y1051757D01*
Y1051931D01*
X1522211D01*
Y1051757D01*
G37*
G36*
G01X1511177D02*
X1510992Y1051157D01*
X1509962D01*
X1509777Y1051757D01*
Y1051931D01*
X1511177D01*
Y1051757D01*
G37*
G36*
G01X1518519Y1051755D02*
X1518334Y1051155D01*
X1517304D01*
X1517119Y1051755D01*
Y1051930D01*
X1518519D01*
Y1051755D01*
G37*
G36*
G01X1514829Y1051757D02*
X1514644Y1051157D01*
X1513614D01*
X1513429Y1051757D01*
Y1051931D01*
X1514829D01*
Y1051757D01*
G37*
G36*
G01X1525973D02*
X1525788Y1051157D01*
X1524758D01*
X1524573Y1051757D01*
Y1051931D01*
X1525973D01*
Y1051757D01*
G37*
G36*
G01X1522211D02*
X1522026Y1051157D01*
X1520996D01*
X1520811Y1051757D01*
Y1051931D01*
X1522211D01*
Y1051757D01*
G37*
G36*
G01X1518553Y1077391D02*
X1518368Y1076791D01*
X1517338D01*
X1517153Y1077391D01*
Y1077566D01*
X1518553D01*
Y1077391D01*
G37*
G36*
G01X1514853D02*
X1514668Y1076791D01*
X1513638D01*
X1513453Y1077391D01*
Y1077566D01*
X1514853D01*
Y1077391D01*
G37*
G36*
G01X1511177D02*
X1510992Y1076791D01*
X1509962D01*
X1509777Y1077391D01*
Y1077566D01*
X1511177D01*
Y1077391D01*
G37*
G36*
G01X1518553D02*
X1518368Y1076791D01*
X1517338D01*
X1517153Y1077391D01*
Y1077566D01*
X1518553D01*
Y1077391D01*
G37*
G36*
G01X1514853D02*
X1514668Y1076791D01*
X1513638D01*
X1513453Y1077391D01*
Y1077566D01*
X1514853D01*
Y1077391D01*
G37*
G36*
G01X1511177D02*
X1510992Y1076791D01*
X1509962D01*
X1509777Y1077391D01*
Y1077566D01*
X1511177D01*
Y1077391D01*
G37*
G36*
G01X1517187Y1069375D02*
X1517372Y1069975D01*
X1518402D01*
X1518587Y1069375D01*
Y1069200D01*
X1517187D01*
Y1069375D01*
G37*
G36*
G01X1513487D02*
X1513672Y1069975D01*
X1514702D01*
X1514887Y1069375D01*
Y1069200D01*
X1513487D01*
Y1069375D01*
G37*
G36*
G01X1509754Y1069373D02*
X1509939Y1069973D01*
X1510969D01*
X1511154Y1069373D01*
Y1069199D01*
X1509754D01*
Y1069373D01*
G37*
G36*
G01X1520887Y1069375D02*
X1521072Y1069975D01*
X1522102D01*
X1522287Y1069375D01*
Y1069200D01*
X1520887D01*
Y1069375D01*
G37*
G36*
G01X1517187D02*
X1517372Y1069975D01*
X1518402D01*
X1518587Y1069375D01*
Y1069200D01*
X1517187D01*
Y1069375D01*
G37*
G36*
G01X1513487D02*
X1513672Y1069975D01*
X1514702D01*
X1514887Y1069375D01*
Y1069200D01*
X1513487D01*
Y1069375D01*
G37*
G36*
G01X1509754Y1069373D02*
X1509939Y1069973D01*
X1510969D01*
X1511154Y1069373D01*
Y1069199D01*
X1509754D01*
Y1069373D01*
G37*
G36*
G01X1520887Y1069375D02*
X1521072Y1069975D01*
X1522102D01*
X1522287Y1069375D01*
Y1069200D01*
X1520887D01*
Y1069375D01*
G37*
G36*
G01X1515270Y1066171D02*
X1515455Y1066771D01*
X1516485D01*
X1516670Y1066171D01*
Y1065996D01*
X1515270D01*
Y1066171D01*
G37*
G36*
G01X1511570D02*
X1511755Y1066771D01*
X1512785D01*
X1512970Y1066171D01*
Y1065996D01*
X1511570D01*
Y1066171D01*
G37*
G36*
G01X1518970D02*
X1519155Y1066771D01*
X1520185D01*
X1520370Y1066171D01*
Y1065996D01*
X1518970D01*
Y1066171D01*
G37*
G36*
G01X1515270D02*
X1515455Y1066771D01*
X1516485D01*
X1516670Y1066171D01*
Y1065996D01*
X1515270D01*
Y1066171D01*
G37*
G36*
G01X1511570D02*
X1511755Y1066771D01*
X1512785D01*
X1512970Y1066171D01*
Y1065996D01*
X1511570D01*
Y1066171D01*
G37*
G36*
G01X1518970D02*
X1519155Y1066771D01*
X1520185D01*
X1520370Y1066171D01*
Y1065996D01*
X1518970D01*
Y1066171D01*
G37*
G36*
G01X1516670Y1067777D02*
X1516485Y1067177D01*
X1515455D01*
X1515270Y1067777D01*
Y1067952D01*
X1516670D01*
Y1067777D01*
G37*
G36*
G01X1512970D02*
X1512785Y1067177D01*
X1511755D01*
X1511570Y1067777D01*
Y1067952D01*
X1512970D01*
Y1067777D01*
G37*
G36*
G01X1520370D02*
X1520185Y1067177D01*
X1519155D01*
X1518970Y1067777D01*
Y1067952D01*
X1520370D01*
Y1067777D01*
G37*
G36*
G01X1516670D02*
X1516485Y1067177D01*
X1515455D01*
X1515270Y1067777D01*
Y1067952D01*
X1516670D01*
Y1067777D01*
G37*
G36*
G01X1512970D02*
X1512785Y1067177D01*
X1511755D01*
X1511570Y1067777D01*
Y1067952D01*
X1512970D01*
Y1067777D01*
G37*
G36*
G01X1520370D02*
X1520185Y1067177D01*
X1519155D01*
X1518970Y1067777D01*
Y1067952D01*
X1520370D01*
Y1067777D01*
G37*
G36*
G01X1514887Y1064573D02*
X1514702Y1063973D01*
X1513672D01*
X1513487Y1064573D01*
Y1064748D01*
X1514887D01*
Y1064573D01*
G37*
G36*
G01X1511187D02*
X1511002Y1063973D01*
X1509972D01*
X1509787Y1064573D01*
Y1064748D01*
X1511187D01*
Y1064573D01*
G37*
G36*
G01X1518587D02*
X1518402Y1063973D01*
X1517372D01*
X1517187Y1064573D01*
Y1064748D01*
X1518587D01*
Y1064573D01*
G37*
G36*
G01X1514887D02*
X1514702Y1063973D01*
X1513672D01*
X1513487Y1064573D01*
Y1064748D01*
X1514887D01*
Y1064573D01*
G37*
G36*
G01X1511187D02*
X1511002Y1063973D01*
X1509972D01*
X1509787Y1064573D01*
Y1064748D01*
X1511187D01*
Y1064573D01*
G37*
G36*
G01X1518587D02*
X1518402Y1063973D01*
X1517372D01*
X1517187Y1064573D01*
Y1064748D01*
X1518587D01*
Y1064573D01*
G37*
G36*
G01X1515303Y1078987D02*
X1515488Y1079587D01*
X1516518D01*
X1516703Y1078987D01*
Y1078812D01*
X1515303D01*
Y1078987D01*
G37*
G36*
G01X1511603D02*
X1511788Y1079587D01*
X1512818D01*
X1513003Y1078987D01*
Y1078812D01*
X1511603D01*
Y1078987D01*
G37*
G36*
G01X1519003D02*
X1519188Y1079587D01*
X1520218D01*
X1520403Y1078987D01*
Y1078812D01*
X1519003D01*
Y1078987D01*
G37*
G36*
G01X1515303D02*
X1515488Y1079587D01*
X1516518D01*
X1516703Y1078987D01*
Y1078812D01*
X1515303D01*
Y1078987D01*
G37*
G36*
G01X1511603D02*
X1511788Y1079587D01*
X1512818D01*
X1513003Y1078987D01*
Y1078812D01*
X1511603D01*
Y1078987D01*
G37*
G36*
G01X1519003D02*
X1519188Y1079587D01*
X1520218D01*
X1520403Y1078987D01*
Y1078812D01*
X1519003D01*
Y1078987D01*
G37*
G36*
G01X1516703Y1074187D02*
X1516518Y1073587D01*
X1515488D01*
X1515303Y1074187D01*
Y1074362D01*
X1516703D01*
Y1074187D01*
G37*
G36*
G01X1513003D02*
X1512818Y1073587D01*
X1511788D01*
X1511603Y1074187D01*
Y1074362D01*
X1513003D01*
Y1074187D01*
G37*
G36*
G01X1520425D02*
X1520240Y1073587D01*
X1519210D01*
X1519025Y1074187D01*
Y1074362D01*
X1520425D01*
Y1074187D01*
G37*
G36*
G01X1516703D02*
X1516518Y1073587D01*
X1515488D01*
X1515303Y1074187D01*
Y1074362D01*
X1516703D01*
Y1074187D01*
G37*
G36*
G01X1513003D02*
X1512818Y1073587D01*
X1511788D01*
X1511603Y1074187D01*
Y1074362D01*
X1513003D01*
Y1074187D01*
G37*
G36*
G01X1520425D02*
X1520240Y1073587D01*
X1519210D01*
X1519025Y1074187D01*
Y1074362D01*
X1520425D01*
Y1074187D01*
G37*
G36*
G01X1515270Y1072579D02*
X1515455Y1073179D01*
X1516485D01*
X1516670Y1072579D01*
Y1072405D01*
X1515270D01*
Y1072579D01*
G37*
G36*
G01X1511570D02*
X1511755Y1073179D01*
X1512785D01*
X1512970Y1072579D01*
Y1072405D01*
X1511570D01*
Y1072579D01*
G37*
G36*
G01X1518970D02*
X1519155Y1073179D01*
X1520185D01*
X1520370Y1072579D01*
Y1072405D01*
X1518970D01*
Y1072579D01*
G37*
G36*
G01X1515270D02*
X1515455Y1073179D01*
X1516485D01*
X1516670Y1072579D01*
Y1072405D01*
X1515270D01*
Y1072579D01*
G37*
G36*
G01X1511570D02*
X1511755Y1073179D01*
X1512785D01*
X1512970Y1072579D01*
Y1072405D01*
X1511570D01*
Y1072579D01*
G37*
G36*
G01X1518970D02*
X1519155Y1073179D01*
X1520185D01*
X1520370Y1072579D01*
Y1072405D01*
X1518970D01*
Y1072579D01*
G37*
G36*
G01X1517129Y1075783D02*
X1517314Y1076383D01*
X1518344D01*
X1518529Y1075783D01*
Y1075608D01*
X1517129D01*
Y1075783D01*
G37*
G36*
G01X1513453D02*
X1513638Y1076383D01*
X1514668D01*
X1514853Y1075783D01*
Y1075608D01*
X1513453D01*
Y1075783D01*
G37*
G36*
G01X1509777D02*
X1509962Y1076383D01*
X1510992D01*
X1511177Y1075783D01*
Y1075608D01*
X1509777D01*
Y1075783D01*
G37*
G36*
G01X1517129D02*
X1517314Y1076383D01*
X1518344D01*
X1518529Y1075783D01*
Y1075608D01*
X1517129D01*
Y1075783D01*
G37*
G36*
G01X1513453D02*
X1513638Y1076383D01*
X1514668D01*
X1514853Y1075783D01*
Y1075608D01*
X1513453D01*
Y1075783D01*
G37*
G36*
G01X1509777D02*
X1509962Y1076383D01*
X1510992D01*
X1511177Y1075783D01*
Y1075608D01*
X1509777D01*
Y1075783D01*
G37*
G36*
G01X1518587Y1070981D02*
X1518402Y1070381D01*
X1517372D01*
X1517187Y1070981D01*
Y1071156D01*
X1518587D01*
Y1070981D01*
G37*
G36*
G01X1514887D02*
X1514702Y1070381D01*
X1513672D01*
X1513487Y1070981D01*
Y1071156D01*
X1514887D01*
Y1070981D01*
G37*
G36*
G01X1511187D02*
X1511002Y1070381D01*
X1509972D01*
X1509787Y1070981D01*
Y1071156D01*
X1511187D01*
Y1070981D01*
G37*
G36*
G01X1518587D02*
X1518402Y1070381D01*
X1517372D01*
X1517187Y1070981D01*
Y1071156D01*
X1518587D01*
Y1070981D01*
G37*
G36*
G01X1514887D02*
X1514702Y1070381D01*
X1513672D01*
X1513487Y1070981D01*
Y1071156D01*
X1514887D01*
Y1070981D01*
G37*
G36*
G01X1511187D02*
X1511002Y1070381D01*
X1509972D01*
X1509787Y1070981D01*
Y1071156D01*
X1511187D01*
Y1070981D01*
G37*
G36*
G01X1512970Y1080595D02*
X1512785Y1079995D01*
X1511755D01*
X1511570Y1080595D01*
Y1080769D01*
X1512970D01*
Y1080595D01*
G37*
G36*
G01X1516670D02*
X1516485Y1079995D01*
X1515455D01*
X1515270Y1080595D01*
Y1080769D01*
X1516670D01*
Y1080595D01*
G37*
G36*
G01X1512970D02*
X1512785Y1079995D01*
X1511755D01*
X1511570Y1080595D01*
Y1080769D01*
X1512970D01*
Y1080595D01*
G37*
G36*
G01X1516670D02*
X1516485Y1079995D01*
X1515455D01*
X1515270Y1080595D01*
Y1080769D01*
X1516670D01*
Y1080595D01*
G37*
G36*
G01X1509787Y1082192D02*
X1509972Y1082792D01*
X1511002D01*
X1511187Y1082192D01*
Y1082018D01*
X1509787D01*
Y1082192D01*
G37*
G36*
G01X1513487D02*
X1513672Y1082792D01*
X1514702D01*
X1514887Y1082192D01*
Y1082018D01*
X1513487D01*
Y1082192D01*
G37*
G36*
G01X1517187D02*
X1517372Y1082792D01*
X1518402D01*
X1518587Y1082192D01*
Y1082018D01*
X1517187D01*
Y1082192D01*
G37*
G36*
G01X1509787D02*
X1509972Y1082792D01*
X1511002D01*
X1511187Y1082192D01*
Y1082018D01*
X1509787D01*
Y1082192D01*
G37*
G36*
G01X1513487D02*
X1513672Y1082792D01*
X1514702D01*
X1514887Y1082192D01*
Y1082018D01*
X1513487D01*
Y1082192D01*
G37*
G36*
G01X1517187D02*
X1517372Y1082792D01*
X1518402D01*
X1518587Y1082192D01*
Y1082018D01*
X1517187D01*
Y1082192D01*
G37*
G36*
G01X1513453Y1088599D02*
X1513638Y1089199D01*
X1514668D01*
X1514853Y1088599D01*
Y1088425D01*
X1513453D01*
Y1088599D01*
G37*
G36*
G01X1517153D02*
X1517338Y1089199D01*
X1518368D01*
X1518553Y1088599D01*
Y1088425D01*
X1517153D01*
Y1088599D01*
G37*
G36*
G01X1509777D02*
X1509962Y1089199D01*
X1510992D01*
X1511177Y1088599D01*
Y1088425D01*
X1509777D01*
Y1088599D01*
G37*
G36*
G01X1520985Y1090014D02*
X1520558Y1090474D01*
X1521073Y1091366D01*
X1521685Y1091226D01*
X1521836Y1091139D01*
X1521136Y1089927D01*
X1520985Y1090014D01*
G37*
G36*
G01X1513453Y1088599D02*
X1513638Y1089199D01*
X1514668D01*
X1514853Y1088599D01*
Y1088425D01*
X1513453D01*
Y1088599D01*
G37*
G36*
G01X1517153D02*
X1517338Y1089199D01*
X1518368D01*
X1518553Y1088599D01*
Y1088425D01*
X1517153D01*
Y1088599D01*
G37*
G36*
G01X1509777D02*
X1509962Y1089199D01*
X1510992D01*
X1511177Y1088599D01*
Y1088425D01*
X1509777D01*
Y1088599D01*
G37*
G36*
G01X1520985Y1090014D02*
X1520558Y1090474D01*
X1521073Y1091366D01*
X1521685Y1091226D01*
X1521836Y1091139D01*
X1521136Y1089927D01*
X1520985Y1090014D01*
G37*
G36*
G01X1511570Y1085396D02*
X1511755Y1085996D01*
X1512785D01*
X1512970Y1085396D01*
Y1085222D01*
X1511570D01*
Y1085396D01*
G37*
G36*
G01X1515270D02*
X1515455Y1085996D01*
X1516485D01*
X1516670Y1085396D01*
Y1085222D01*
X1515270D01*
Y1085396D01*
G37*
G36*
G01X1522835Y1086810D02*
X1522408Y1087270D01*
X1522923Y1088162D01*
X1523535Y1088022D01*
X1523686Y1087935D01*
X1522986Y1086723D01*
X1522835Y1086810D01*
G37*
G36*
G01X1518970Y1085396D02*
X1519155Y1085996D01*
X1520185D01*
X1520370Y1085396D01*
Y1085222D01*
X1518970D01*
Y1085396D01*
G37*
G36*
G01X1511570D02*
X1511755Y1085996D01*
X1512785D01*
X1512970Y1085396D01*
Y1085222D01*
X1511570D01*
Y1085396D01*
G37*
G36*
G01X1515270D02*
X1515455Y1085996D01*
X1516485D01*
X1516670Y1085396D01*
Y1085222D01*
X1515270D01*
Y1085396D01*
G37*
G36*
G01X1522835Y1086810D02*
X1522408Y1087270D01*
X1522923Y1088162D01*
X1523535Y1088022D01*
X1523686Y1087935D01*
X1522986Y1086723D01*
X1522835Y1086810D01*
G37*
G36*
G01X1518970Y1085396D02*
X1519155Y1085996D01*
X1520185D01*
X1520370Y1085396D01*
Y1085222D01*
X1518970D01*
Y1085396D01*
G37*
G36*
G01X1513003Y1087005D02*
X1512818Y1086405D01*
X1511788D01*
X1511603Y1087005D01*
Y1087179D01*
X1513003D01*
Y1087005D01*
G37*
G36*
G01X1516703D02*
X1516518Y1086405D01*
X1515488D01*
X1515303Y1087005D01*
Y1087179D01*
X1516703D01*
Y1087005D01*
G37*
G36*
G01X1520403D02*
X1520218Y1086405D01*
X1519188D01*
X1519003Y1087005D01*
Y1087179D01*
X1520403D01*
Y1087005D01*
G37*
G36*
G01X1522121Y1088794D02*
X1522548Y1088334D01*
X1522033Y1087442D01*
X1521421Y1087582D01*
X1521270Y1087669D01*
X1521970Y1088881D01*
X1522121Y1088794D01*
G37*
G36*
G01X1513003Y1087005D02*
X1512818Y1086405D01*
X1511788D01*
X1511603Y1087005D01*
Y1087179D01*
X1513003D01*
Y1087005D01*
G37*
G36*
G01X1516703D02*
X1516518Y1086405D01*
X1515488D01*
X1515303Y1087005D01*
Y1087179D01*
X1516703D01*
Y1087005D01*
G37*
G36*
G01X1520403D02*
X1520218Y1086405D01*
X1519188D01*
X1519003Y1087005D01*
Y1087179D01*
X1520403D01*
Y1087005D01*
G37*
G36*
G01X1522121Y1088794D02*
X1522548Y1088334D01*
X1522033Y1087442D01*
X1521421Y1087582D01*
X1521270Y1087669D01*
X1521970Y1088881D01*
X1522121Y1088794D01*
G37*
G36*
G01X1518587Y1083799D02*
X1518402Y1083199D01*
X1517372D01*
X1517187Y1083799D01*
Y1083974D01*
X1518587D01*
Y1083799D01*
G37*
G36*
G01X1511187D02*
X1511002Y1083199D01*
X1509972D01*
X1509787Y1083799D01*
Y1083974D01*
X1511187D01*
Y1083799D01*
G37*
G36*
G01X1514887D02*
X1514702Y1083199D01*
X1513672D01*
X1513487Y1083799D01*
Y1083974D01*
X1514887D01*
Y1083799D01*
G37*
G36*
G01X1522287D02*
X1522102Y1083199D01*
X1521072D01*
X1520887Y1083799D01*
Y1083974D01*
X1522287D01*
Y1083799D01*
G37*
G36*
G01X1518587D02*
X1518402Y1083199D01*
X1517372D01*
X1517187Y1083799D01*
Y1083974D01*
X1518587D01*
Y1083799D01*
G37*
G36*
G01X1511187D02*
X1511002Y1083199D01*
X1509972D01*
X1509787Y1083799D01*
Y1083974D01*
X1511187D01*
Y1083799D01*
G37*
G36*
G01X1514887D02*
X1514702Y1083199D01*
X1513672D01*
X1513487Y1083799D01*
Y1083974D01*
X1514887D01*
Y1083799D01*
G37*
G36*
G01X1522287D02*
X1522102Y1083199D01*
X1521072D01*
X1520887Y1083799D01*
Y1083974D01*
X1522287D01*
Y1083799D01*
G37*
G36*
G01X1518413Y1095187D02*
X1518840Y1094727D01*
X1518325Y1093835D01*
X1517713Y1093975D01*
X1517562Y1094062D01*
X1518262Y1095274D01*
X1518413Y1095187D01*
G37*
G36*
G01X1516703Y1093413D02*
X1516518Y1092813D01*
X1515488D01*
X1515303Y1093413D01*
Y1093587D01*
X1516703D01*
Y1093413D01*
G37*
G36*
G01X1512979Y1093411D02*
X1512794Y1092811D01*
X1511764D01*
X1511579Y1093411D01*
Y1093586D01*
X1512979D01*
Y1093411D01*
G37*
G36*
G01X1518413Y1095187D02*
X1518840Y1094727D01*
X1518325Y1093835D01*
X1517713Y1093975D01*
X1517562Y1094062D01*
X1518262Y1095274D01*
X1518413Y1095187D01*
G37*
G36*
G01X1516703Y1093413D02*
X1516518Y1092813D01*
X1515488D01*
X1515303Y1093413D01*
Y1093587D01*
X1516703D01*
Y1093413D01*
G37*
G36*
G01X1512979Y1093411D02*
X1512794Y1092811D01*
X1511764D01*
X1511579Y1093411D01*
Y1093586D01*
X1512979D01*
Y1093411D01*
G37*
G36*
G01X1515303Y1091803D02*
X1515488Y1092403D01*
X1516518D01*
X1516703Y1091803D01*
Y1091629D01*
X1515303D01*
Y1091803D01*
G37*
G36*
G01X1511579Y1091804D02*
X1511764Y1092404D01*
X1512794D01*
X1512979Y1091804D01*
Y1091630D01*
X1511579D01*
Y1091804D01*
G37*
G36*
G01X1519143Y1093234D02*
X1518716Y1093694D01*
X1519231Y1094586D01*
X1519843Y1094446D01*
X1519994Y1094359D01*
X1519294Y1093147D01*
X1519143Y1093234D01*
G37*
G36*
G01X1515303Y1091803D02*
X1515488Y1092403D01*
X1516518D01*
X1516703Y1091803D01*
Y1091629D01*
X1515303D01*
Y1091803D01*
G37*
G36*
G01X1511579Y1091804D02*
X1511764Y1092404D01*
X1512794D01*
X1512979Y1091804D01*
Y1091630D01*
X1511579D01*
Y1091804D01*
G37*
G36*
G01X1519143Y1093234D02*
X1518716Y1093694D01*
X1519231Y1094586D01*
X1519843Y1094446D01*
X1519994Y1094359D01*
X1519294Y1093147D01*
X1519143Y1093234D01*
G37*
G36*
G01X1513453Y1095008D02*
X1513638Y1095608D01*
X1514668D01*
X1514853Y1095008D01*
Y1094834D01*
X1513453D01*
Y1095008D01*
G37*
G36*
G01X1509786Y1095009D02*
X1509971Y1095609D01*
X1511001D01*
X1511186Y1095009D01*
Y1094835D01*
X1509786D01*
Y1095009D01*
G37*
G36*
G01X1513453Y1095008D02*
X1513638Y1095608D01*
X1514668D01*
X1514853Y1095008D01*
Y1094834D01*
X1513453D01*
Y1095008D01*
G37*
G36*
G01X1509786Y1095009D02*
X1509971Y1095609D01*
X1511001D01*
X1511186Y1095009D01*
Y1094835D01*
X1509786D01*
Y1095009D01*
G37*
G36*
G01X1518553Y1090209D02*
X1518368Y1089609D01*
X1517338D01*
X1517153Y1090209D01*
Y1090383D01*
X1518553D01*
Y1090209D01*
G37*
G36*
G01X1514853D02*
X1514668Y1089609D01*
X1513638D01*
X1513453Y1090209D01*
Y1090383D01*
X1514853D01*
Y1090209D01*
G37*
G36*
G01X1511186Y1090207D02*
X1511001Y1089607D01*
X1509971D01*
X1509786Y1090207D01*
Y1090382D01*
X1511186D01*
Y1090207D01*
G37*
G36*
G01X1522113Y1095187D02*
X1522540Y1094727D01*
X1522025Y1093835D01*
X1521413Y1093975D01*
X1521262Y1094062D01*
X1521962Y1095274D01*
X1522113Y1095187D01*
G37*
G36*
G01X1520271Y1091998D02*
X1520698Y1091538D01*
X1520183Y1090646D01*
X1519571Y1090786D01*
X1519420Y1090873D01*
X1520120Y1092085D01*
X1520271Y1091998D01*
G37*
G36*
G01X1518553Y1090209D02*
X1518368Y1089609D01*
X1517338D01*
X1517153Y1090209D01*
Y1090383D01*
X1518553D01*
Y1090209D01*
G37*
G36*
G01X1514853D02*
X1514668Y1089609D01*
X1513638D01*
X1513453Y1090209D01*
Y1090383D01*
X1514853D01*
Y1090209D01*
G37*
G36*
G01X1511186Y1090207D02*
X1511001Y1089607D01*
X1509971D01*
X1509786Y1090207D01*
Y1090382D01*
X1511186D01*
Y1090207D01*
G37*
G36*
G01X1522113Y1095187D02*
X1522540Y1094727D01*
X1522025Y1093835D01*
X1521413Y1093975D01*
X1521262Y1094062D01*
X1521962Y1095274D01*
X1522113Y1095187D01*
G37*
G36*
G01X1520271Y1091998D02*
X1520698Y1091538D01*
X1520183Y1090646D01*
X1519571Y1090786D01*
X1519420Y1090873D01*
X1520120Y1092085D01*
X1520271Y1091998D01*
G37*
G36*
G01X1509729Y1101417D02*
X1509914Y1102017D01*
X1510944D01*
X1511129Y1101417D01*
Y1101243D01*
X1509729D01*
Y1101417D01*
G37*
G36*
G01X1517153Y1107825D02*
X1517338Y1108425D01*
X1518368D01*
X1518553Y1107825D01*
Y1107651D01*
X1517153D01*
Y1107825D01*
G37*
G36*
G01X1515435Y1106036D02*
X1515008Y1106496D01*
X1515523Y1107388D01*
X1516135Y1107248D01*
X1516286Y1107161D01*
X1515586Y1105949D01*
X1515435Y1106036D01*
G37*
G36*
G01X1513593Y1102847D02*
X1513166Y1103307D01*
X1513681Y1104199D01*
X1514293Y1104059D01*
X1514444Y1103972D01*
X1513744Y1102760D01*
X1513593Y1102847D01*
G37*
G36*
G01X1520830Y1107827D02*
X1521015Y1108427D01*
X1522045D01*
X1522230Y1107827D01*
Y1107652D01*
X1520830D01*
Y1107827D01*
G37*
G36*
G01X1509729Y1101417D02*
X1509914Y1102017D01*
X1510944D01*
X1511129Y1101417D01*
Y1101243D01*
X1509729D01*
Y1101417D01*
G37*
G36*
G01X1517153Y1107825D02*
X1517338Y1108425D01*
X1518368D01*
X1518553Y1107825D01*
Y1107651D01*
X1517153D01*
Y1107825D01*
G37*
G36*
G01X1515435Y1106036D02*
X1515008Y1106496D01*
X1515523Y1107388D01*
X1516135Y1107248D01*
X1516286Y1107161D01*
X1515586Y1105949D01*
X1515435Y1106036D01*
G37*
G36*
G01X1513593Y1102847D02*
X1513166Y1103307D01*
X1513681Y1104199D01*
X1514293Y1104059D01*
X1514444Y1103972D01*
X1513744Y1102760D01*
X1513593Y1102847D01*
G37*
G36*
G01X1520830Y1107827D02*
X1521015Y1108427D01*
X1522045D01*
X1522230Y1107827D01*
Y1107652D01*
X1520830D01*
Y1107827D01*
G37*
G36*
G01X1511153Y1096617D02*
X1510968Y1096017D01*
X1509938D01*
X1509753Y1096617D01*
Y1096792D01*
X1511153D01*
Y1096617D01*
G37*
G36*
G01X1514853D02*
X1514668Y1096017D01*
X1513638D01*
X1513453Y1096617D01*
Y1096792D01*
X1514853D01*
Y1096617D01*
G37*
G36*
G01X1518421Y1101611D02*
X1518848Y1101151D01*
X1518333Y1100259D01*
X1517721Y1100399D01*
X1517570Y1100486D01*
X1518270Y1101698D01*
X1518421Y1101611D01*
G37*
G36*
G01X1516571Y1098407D02*
X1516998Y1097947D01*
X1516483Y1097055D01*
X1515871Y1097195D01*
X1515720Y1097282D01*
X1516420Y1098494D01*
X1516571Y1098407D01*
G37*
G36*
G01X1522278Y1103025D02*
X1522093Y1102425D01*
X1521063D01*
X1520878Y1103025D01*
Y1103199D01*
X1522278D01*
Y1103025D01*
G37*
G36*
G01X1511153Y1096617D02*
X1510968Y1096017D01*
X1509938D01*
X1509753Y1096617D01*
Y1096792D01*
X1511153D01*
Y1096617D01*
G37*
G36*
G01X1514853D02*
X1514668Y1096017D01*
X1513638D01*
X1513453Y1096617D01*
Y1096792D01*
X1514853D01*
Y1096617D01*
G37*
G36*
G01X1518421Y1101611D02*
X1518848Y1101151D01*
X1518333Y1100259D01*
X1517721Y1100399D01*
X1517570Y1100486D01*
X1518270Y1101698D01*
X1518421Y1101611D01*
G37*
G36*
G01X1516571Y1098407D02*
X1516998Y1097947D01*
X1516483Y1097055D01*
X1515871Y1097195D01*
X1515720Y1097282D01*
X1516420Y1098494D01*
X1516571Y1098407D01*
G37*
G36*
G01X1522278Y1103025D02*
X1522093Y1102425D01*
X1521063D01*
X1520878Y1103025D01*
Y1103199D01*
X1522278D01*
Y1103025D01*
G37*
G36*
G01X1513003Y1099822D02*
X1512818Y1099222D01*
X1511788D01*
X1511603Y1099822D01*
Y1099996D01*
X1513003D01*
Y1099822D01*
G37*
G36*
G01X1514721Y1101611D02*
X1515148Y1101151D01*
X1514633Y1100259D01*
X1514021Y1100399D01*
X1513870Y1100486D01*
X1514570Y1101698D01*
X1514721Y1101611D01*
G37*
G36*
G01X1516563Y1104800D02*
X1516990Y1104340D01*
X1516475Y1103448D01*
X1515863Y1103588D01*
X1515712Y1103675D01*
X1516412Y1104887D01*
X1516563Y1104800D01*
G37*
G36*
G01X1524128Y1106230D02*
X1523943Y1105630D01*
X1522913D01*
X1522728Y1106230D01*
Y1106404D01*
X1524128D01*
Y1106230D01*
G37*
G36*
G01X1520427D02*
X1520242Y1105630D01*
X1519212D01*
X1519027Y1106230D01*
Y1106404D01*
X1520427D01*
Y1106230D01*
G37*
G36*
G01X1513003Y1099822D02*
X1512818Y1099222D01*
X1511788D01*
X1511603Y1099822D01*
Y1099996D01*
X1513003D01*
Y1099822D01*
G37*
G36*
G01X1514721Y1101611D02*
X1515148Y1101151D01*
X1514633Y1100259D01*
X1514021Y1100399D01*
X1513870Y1100486D01*
X1514570Y1101698D01*
X1514721Y1101611D01*
G37*
G36*
G01X1516563Y1104800D02*
X1516990Y1104340D01*
X1516475Y1103448D01*
X1515863Y1103588D01*
X1515712Y1103675D01*
X1516412Y1104887D01*
X1516563Y1104800D01*
G37*
G36*
G01X1524128Y1106230D02*
X1523943Y1105630D01*
X1522913D01*
X1522728Y1106230D01*
Y1106404D01*
X1524128D01*
Y1106230D01*
G37*
G36*
G01X1520427D02*
X1520242Y1105630D01*
X1519212D01*
X1519027Y1106230D01*
Y1106404D01*
X1520427D01*
Y1106230D01*
G37*
G36*
G01X1515435Y1099627D02*
X1515008Y1100087D01*
X1515523Y1100979D01*
X1516135Y1100839D01*
X1516286Y1100752D01*
X1515586Y1099540D01*
X1515435Y1099627D01*
G37*
G36*
G01X1511603Y1098212D02*
X1511788Y1098812D01*
X1512818D01*
X1513003Y1098212D01*
Y1098038D01*
X1511603D01*
Y1098212D01*
G37*
G36*
G01X1517293Y1102847D02*
X1516866Y1103307D01*
X1517381Y1104199D01*
X1517993Y1104059D01*
X1518144Y1103972D01*
X1517444Y1102760D01*
X1517293Y1102847D01*
G37*
G36*
G01X1518980Y1104623D02*
X1519165Y1105223D01*
X1520195D01*
X1520380Y1104623D01*
Y1104448D01*
X1518980D01*
Y1104623D01*
G37*
G36*
G01X1515435Y1099627D02*
X1515008Y1100087D01*
X1515523Y1100979D01*
X1516135Y1100839D01*
X1516286Y1100752D01*
X1515586Y1099540D01*
X1515435Y1099627D01*
G37*
G36*
G01X1511603Y1098212D02*
X1511788Y1098812D01*
X1512818D01*
X1513003Y1098212D01*
Y1098038D01*
X1511603D01*
Y1098212D01*
G37*
G36*
G01X1517293Y1102847D02*
X1516866Y1103307D01*
X1517381Y1104199D01*
X1517993Y1104059D01*
X1518144Y1103972D01*
X1517444Y1102760D01*
X1517293Y1102847D01*
G37*
G36*
G01X1518980Y1104623D02*
X1519165Y1105223D01*
X1520195D01*
X1520380Y1104623D01*
Y1104448D01*
X1518980D01*
Y1104623D01*
G37*
G36*
G01X1520271Y1098407D02*
X1520698Y1097947D01*
X1520183Y1097055D01*
X1519571Y1097195D01*
X1519420Y1097282D01*
X1520120Y1098494D01*
X1520271Y1098407D01*
G37*
G36*
G01D02*
X1520698Y1097947D01*
X1520183Y1097055D01*
X1519571Y1097195D01*
X1519420Y1097282D01*
X1520120Y1098494D01*
X1520271Y1098407D01*
G37*
G36*
G01X1520993Y1096439D02*
X1520566Y1096899D01*
X1521081Y1097791D01*
X1521693Y1097651D01*
X1521844Y1097564D01*
X1521144Y1096352D01*
X1520993Y1096439D01*
G37*
G36*
G01D02*
X1520566Y1096899D01*
X1521081Y1097791D01*
X1521693Y1097651D01*
X1521844Y1097564D01*
X1521144Y1096352D01*
X1520993Y1096439D01*
G37*
G36*
G01X1517285Y1096423D02*
X1516858Y1096883D01*
X1517373Y1097775D01*
X1517985Y1097635D01*
X1518136Y1097548D01*
X1517436Y1096336D01*
X1517285Y1096423D01*
G37*
G36*
G01X1520853Y1101416D02*
X1521038Y1102016D01*
X1522068D01*
X1522253Y1101416D01*
Y1101242D01*
X1520853D01*
Y1101416D01*
G37*
G36*
G01X1519135Y1099627D02*
X1518708Y1100087D01*
X1519223Y1100979D01*
X1519835Y1100839D01*
X1519986Y1100752D01*
X1519286Y1099540D01*
X1519135Y1099627D01*
G37*
G36*
G01X1517285Y1096423D02*
X1516858Y1096883D01*
X1517373Y1097775D01*
X1517985Y1097635D01*
X1518136Y1097548D01*
X1517436Y1096336D01*
X1517285Y1096423D01*
G37*
G36*
G01X1520853Y1101416D02*
X1521038Y1102016D01*
X1522068D01*
X1522253Y1101416D01*
Y1101242D01*
X1520853D01*
Y1101416D01*
G37*
G36*
G01X1519135Y1099627D02*
X1518708Y1100087D01*
X1519223Y1100979D01*
X1519835Y1100839D01*
X1519986Y1100752D01*
X1519286Y1099540D01*
X1519135Y1099627D01*
G37*
G36*
G01X1527787Y863393D02*
X1527972Y863993D01*
X1529002D01*
X1529187Y863393D01*
Y863219D01*
X1527787D01*
Y863393D01*
G37*
G36*
G01D02*
X1527972Y863993D01*
X1529002D01*
X1529187Y863393D01*
Y863219D01*
X1527787D01*
Y863393D01*
G37*
G36*
G01X1531487D02*
X1531672Y863993D01*
X1532702D01*
X1532887Y863393D01*
Y863219D01*
X1531487D01*
Y863393D01*
G37*
G36*
G01D02*
X1531672Y863993D01*
X1532702D01*
X1532887Y863393D01*
Y863219D01*
X1531487D01*
Y863393D01*
G37*
G36*
G01X1527371Y868205D02*
X1527186Y867605D01*
X1526156D01*
X1525971Y868205D01*
Y868380D01*
X1527371D01*
Y868205D01*
G37*
G36*
G01D02*
X1527186Y867605D01*
X1526156D01*
X1525971Y868205D01*
Y868380D01*
X1527371D01*
Y868205D01*
G37*
G36*
G01X1527404Y861797D02*
X1527219Y861197D01*
X1526189D01*
X1526004Y861797D01*
Y861971D01*
X1527404D01*
Y861797D01*
G37*
G36*
G01X1531104D02*
X1530919Y861197D01*
X1529889D01*
X1529704Y861797D01*
Y861971D01*
X1531104D01*
Y861797D01*
G37*
G36*
G01X1527404D02*
X1527219Y861197D01*
X1526189D01*
X1526004Y861797D01*
Y861971D01*
X1527404D01*
Y861797D01*
G37*
G36*
G01X1531104D02*
X1530919Y861197D01*
X1529889D01*
X1529704Y861797D01*
Y861971D01*
X1531104D01*
Y861797D01*
G37*
G36*
G01X1525939Y853779D02*
X1526124Y854379D01*
X1527154D01*
X1527339Y853779D01*
Y853605D01*
X1525939D01*
Y853779D01*
G37*
G36*
G01D02*
X1526124Y854379D01*
X1527154D01*
X1527339Y853779D01*
Y853605D01*
X1525939D01*
Y853779D01*
G37*
G36*
G01X1529187Y858593D02*
X1529002Y857993D01*
X1527972D01*
X1527787Y858593D01*
Y858767D01*
X1529187D01*
Y858593D01*
G37*
G36*
G01D02*
X1529002Y857993D01*
X1527972D01*
X1527787Y858593D01*
Y858767D01*
X1529187D01*
Y858593D01*
G37*
G36*
G01X1527787Y856985D02*
X1527972Y857585D01*
X1529002D01*
X1529187Y856985D01*
Y856811D01*
X1527787D01*
Y856985D01*
G37*
G36*
G01D02*
X1527972Y857585D01*
X1529002D01*
X1529187Y856985D01*
Y856811D01*
X1527787D01*
Y856985D01*
G37*
G36*
G01X1529704Y860189D02*
X1529889Y860789D01*
X1530919D01*
X1531104Y860189D01*
Y860015D01*
X1529704D01*
Y860189D01*
G37*
G36*
G01X1526004D02*
X1526189Y860789D01*
X1527219D01*
X1527404Y860189D01*
Y860015D01*
X1526004D01*
Y860189D01*
G37*
G36*
G01X1529704D02*
X1529889Y860789D01*
X1530919D01*
X1531104Y860189D01*
Y860015D01*
X1529704D01*
Y860189D01*
G37*
G36*
G01X1526004D02*
X1526189Y860789D01*
X1527219D01*
X1527404Y860189D01*
Y860015D01*
X1526004D01*
Y860189D01*
G37*
G36*
G01X1527404Y855387D02*
X1527219Y854787D01*
X1526189D01*
X1526004Y855387D01*
Y855562D01*
X1527404D01*
Y855387D01*
G37*
G36*
G01D02*
X1527219Y854787D01*
X1526189D01*
X1526004Y855387D01*
Y855562D01*
X1527404D01*
Y855387D01*
G37*
G36*
G01X1528153Y869901D02*
X1528439Y870460D01*
X1529454Y870281D01*
X1529532Y869658D01*
X1529501Y869486D01*
X1528123Y869730D01*
X1528153Y869901D01*
G37*
G36*
G01D02*
X1528439Y870460D01*
X1529454Y870281D01*
X1529532Y869658D01*
X1529501Y869486D01*
X1528123Y869730D01*
X1528153Y869901D01*
G37*
G36*
G01X1527823Y1048553D02*
X1527638Y1047953D01*
X1526608D01*
X1526423Y1048553D01*
Y1048727D01*
X1527823D01*
Y1048553D01*
G37*
G36*
G01D02*
X1527638Y1047953D01*
X1526608D01*
X1526423Y1048553D01*
Y1048727D01*
X1527823D01*
Y1048553D01*
G37*
G36*
G01X1580607Y616392D02*
X1609270D01*
X1611140Y614522D01*
Y585672D01*
X1608770Y583302D01*
X1567360D01*
X1566704Y583958D01*
Y613696D01*
X1569400Y616392D01*
X1573393D01*
X1573403Y616202D01*
G03X1580597I3597J186D01*
G01X1580607Y616392D01*
G37*
G36*
G01X1570930Y654232D02*
X1609620D01*
X1612029Y651823D01*
G02X1612006Y651235I-282J-283D01*
G03X1611478Y650092I973J-1143D01*
G03X1612380Y648715I1502J0D01*
G01X1612500Y648663D01*
Y627791D01*
X1612380Y627739D01*
G03X1611478Y626362I600J-1377D01*
G03X1611884Y625335I1502J0D01*
G02Y624789I-292J-273D01*
G03X1611478Y623762I1096J-1027D01*
G03X1612380Y622385I1502J0D01*
G01X1612500Y622333D01*
Y620472D01*
X1610120Y618092D01*
X1580173D01*
G03X1573827I-3173J-1703D01*
G01X1568380D01*
X1566170Y620302D01*
Y649472D01*
X1570930Y654232D01*
G37*
G36*
G01X1570410Y726862D02*
X1608721D01*
G02X1609011Y726187I0J-400D01*
G03X1608598Y725152I1090J-1035D01*
G03X1610100Y723650I1502J0D01*
G03X1611479Y724558I0J1501D01*
G02X1612130Y724682I367J-158D01*
G01X1612330Y724482D01*
Y719446D01*
G03Y716738I650J-1354D01*
G01Y695716D01*
G03X1611478Y694362I650J-1354D01*
G03X1611884Y693335I1502J0D01*
G02Y692789I-292J-273D01*
G03X1611478Y691762I1096J-1027D01*
G03X1612330Y690408I1502J0D01*
G01Y685446D01*
G03Y682738I650J-1354D01*
G01Y661716D01*
G03X1611478Y660362I650J-1354D01*
G03X1611820Y659408I1502J0D01*
G02X1611807Y659139I-154J-127D01*
G01X1609110Y656442D01*
X1570590D01*
X1567020Y660012D01*
Y723472D01*
X1570410Y726862D01*
G37*
G36*
G01X1712741Y551816D02*
X1703306D01*
G03Y548312I0J-1752D01*
G01X1705489D01*
G02X1705879Y547832I-1J-399D01*
G01X1705875Y547812D01*
Y547808D01*
X1705871Y547789D01*
G03X1705844Y547520I1475J-284D01*
G01Y547487D01*
G03X1707346Y546002I1502J17D01*
G03X1707514Y546011I4J1502D01*
G02X1707936Y545594I22J-400D01*
G03X1707930Y545513I1743J-170D01*
G03X1707928Y545432I1750J-84D01*
G01Y545431D01*
G03X1709689Y543680I1752J1D01*
G01X1711735D01*
G03X1712391Y543808I-1J1752D01*
G01X1712536Y543866D01*
X1712764Y543553D01*
X1712445Y543234D01*
X1709694D01*
G03X1708456Y542720I1J-1751D01*
G01X1708118Y542382D01*
G03X1707604Y541144I1237J-1239D01*
G03X1709356Y539392I1752J0D01*
G03X1710390Y539730I0J1751D01*
G01X1713170D01*
G03X1714408Y540244I-1J1751D01*
G01X1717508Y543344D01*
G03X1718022Y544582I-1237J1239D01*
G01Y546557D01*
X1728233Y556768D01*
X1752744D01*
G03X1753982Y557282I-1J1751D01*
G01X1761454Y564753D01*
X1761604Y564903D01*
G02X1762287Y564621I283J-283D01*
G01Y473261D01*
X1743006Y453980D01*
X1698411D01*
G02X1698147Y454680I1J400D01*
G03X1698722Y455862I-927J1182D01*
G03X1695718I-1502J0D01*
G03X1696293Y454680I1502J0D01*
G02X1696029Y453980I-265J-300D01*
G01X1694911D01*
G02X1694647Y454680I1J400D01*
G03X1695222Y455862I-927J1182D01*
G03X1692218I-1502J0D01*
G03X1692793Y454680I1502J0D01*
G02X1692529Y453980I-265J-300D01*
G01X1631511D01*
X1615810Y469681D01*
Y558750D01*
X1618921D01*
G03X1619806Y559117I-1J1252D01*
G01X1636698Y576010D01*
X1675101D01*
G03X1675986Y576377I-1J1252D01*
G01X1681585Y581976D01*
G03X1681952Y582861I-885J886D01*
G01Y599533D01*
G03X1681585Y600418I-1252J-1D01*
G01X1670916Y611087D01*
G03X1670031Y611454I-886J-885D01*
G01X1668958D01*
X1665662Y614750D01*
Y617122D01*
G03X1665912Y617951I-1252J830D01*
G01Y617953D01*
G03X1662908I-1502J0D01*
G01Y617951D01*
G03X1663158Y617122I1502J1D01*
G01Y614232D01*
G03X1663525Y613347I1252J1D01*
G01X1664460Y612412D01*
X1667554Y609317D01*
G03X1668439Y608950I886J885D01*
G01X1669512D01*
X1679448Y599014D01*
Y583380D01*
X1674582Y578514D01*
X1636179D01*
G03X1635294Y578147I1J-1252D01*
G01X1618402Y561254D01*
X1615810D01*
Y582649D01*
X1615984Y582672D01*
G03Y585452I-184J1390D01*
G01X1615810Y585475D01*
Y648700D01*
X1615956Y648741D01*
G03Y651443I-376J1351D01*
G01X1615810Y651484D01*
Y656370D01*
X1615956Y656411D01*
G03X1616982Y657762I-376J1351D01*
G03X1616542Y658782I-1402J0D01*
G02Y659342I286J280D01*
G03X1616982Y660362I-962J1020D01*
G03X1616968Y660562I-1402J2D01*
G03X1615956Y661713I-1388J-200D01*
G01X1615810Y661754D01*
Y682700D01*
X1615956Y682741D01*
G03Y685443I-376J1351D01*
G01X1615810Y685484D01*
Y690370D01*
X1615956Y690411D01*
G03X1616982Y691762I-376J1351D01*
G03X1616542Y692782I-1402J0D01*
G02Y693342I286J280D01*
G03X1616982Y694362I-962J1020D01*
G03X1616968Y694562I-1402J2D01*
G03X1615956Y695713I-1388J-200D01*
G01X1615810Y695754D01*
Y716700D01*
X1615956Y716741D01*
G03Y719443I-376J1351D01*
G01X1615810Y719484D01*
Y720216D01*
X1619302Y723708D01*
X1715481D01*
X1722711Y716478D01*
Y696355D01*
X1733061Y686005D01*
X1758551D01*
X1762287Y682269D01*
Y576126D01*
X1750382Y564220D01*
X1725871D01*
G03X1724633Y563707I0J-1750D01*
G01X1712741Y551816D01*
G37*
G36*
G01X1635750Y441612D02*
X1707520D01*
X1721100Y428032D01*
Y382892D01*
X1719380Y381172D01*
G02X1718703Y381391I-282J283D01*
G03X1717220Y382654I-1483J-239D01*
G03X1715718Y381152I0J-1502D01*
G03X1716981Y379669I1502J0D01*
G02X1717200Y378992I-64J-395D01*
G01X1715840Y377632D01*
X1646100D01*
X1633200Y390532D01*
Y439062D01*
X1635750Y441612D01*
G37*
G36*
G01X1741400Y315462D02*
X1835320D01*
X1849020Y301762D01*
Y220182D01*
X1814300Y185462D01*
X1736241D01*
X1736184Y185568D01*
G03X1733530I-1327J-702D01*
G01X1733473Y185462D01*
X1724744D01*
G03X1723240Y186727I-1504J-262D01*
G03X1721736Y185462I0J-1527D01*
G01X1714300D01*
X1690490Y209272D01*
Y233112D01*
X1709350Y251972D01*
Y305192D01*
X1719610Y315452D01*
X1741390D01*
X1741400Y315462D01*
G37*
G36*
G01X1712541Y1559099D02*
X1831895D01*
X1831954Y1559041D01*
X1838404Y1552591D01*
Y1492176D01*
X1833627Y1487399D01*
X1708361D01*
X1708302Y1487458D01*
X1703327Y1492433D01*
Y1499242D01*
G02X1703936Y1499582I400J-1D01*
G03X1704723Y1499360I786J1280D01*
G03Y1502364I0J1502D01*
G03X1703936Y1502142I-1J-1502D01*
G02X1703327Y1502482I-209J341D01*
G01Y1518742D01*
G02X1703936Y1519082I400J-1D01*
G03X1704723Y1518860I786J1280D01*
G03Y1521864I0J1502D01*
G03X1703936Y1521642I-1J-1502D01*
G02X1703327Y1521982I-209J341D01*
G01Y1539742D01*
G02X1703936Y1540082I400J-1D01*
G03X1704723Y1539860I786J1280D01*
G03Y1542864I0J1502D01*
G03X1703936Y1542642I-1J-1502D01*
G02X1703327Y1542982I-209J341D01*
G01Y1549885D01*
X1703385Y1549944D01*
X1712482Y1559041D01*
X1712541Y1559099D01*
G37*
G36*
G01X1711630Y105802D02*
X1748660D01*
X1751520Y102942D01*
Y46662D01*
X1745800Y40942D01*
X1734690D01*
X1716202Y59430D01*
Y66180D01*
G02X1716659Y66576I400J0D01*
G03X1716875Y66560I219J1486D01*
G03X1718377Y68062I0J1502D01*
G03X1717428Y69459I-1503J0D01*
G02X1717184Y69916I147J372D01*
G03X1717214Y70184I-1222J272D01*
G01Y83890D01*
G03X1716847Y84775I-1252J-1D01*
G01X1716070Y85552D01*
Y93432D01*
X1709940Y99562D01*
Y104112D01*
X1711630Y105802D01*
G37*
G36*
G01X1722931Y135362D02*
X1795220D01*
X1798298Y132283D01*
Y65981D01*
X1786171Y53854D01*
X1783665D01*
G02X1783267Y54297I-1J400D01*
G03X1783276Y54462I-1493J164D01*
G03X1780272I-1502J0D01*
G03X1780281Y54297I1502J-1D01*
G02X1779883Y53854I-397J-43D01*
G01X1778191D01*
X1778148Y53996D01*
G03X1776710Y55064I-1438J-434D01*
G03X1775208Y53562I0J-1502D01*
G03X1775227Y53325I1502J1D01*
G02X1774832Y52862I-395J-63D01*
G01X1773629D01*
G02X1773239Y53350I0J400D01*
G03X1773276Y53682I-1465J331D01*
G03X1770272I-1502J0D01*
G03X1770309Y53350I1502J-1D01*
G02X1769919Y52862I-390J-88D01*
G01X1769120D01*
G02X1768721Y53279I0J400D01*
G03X1768722Y53342I-1501J55D01*
G03X1765718I-1502J0D01*
G03X1765719Y53279I1502J-8D01*
G02X1765320Y52862I-399J-17D01*
G01X1764640D01*
G02X1764240Y53262I0J400D01*
G03X1761236I-1502J0D01*
G02X1760836Y52862I-400J0D01*
G01X1755470D01*
X1753420Y54912D01*
Y104002D01*
X1750350Y107072D01*
X1710300D01*
X1708720Y108652D01*
Y126362D01*
X1712116Y129758D01*
G02X1712394Y129763I142J-141D01*
G03X1713418Y129360I1024J1099D01*
G03X1714920Y130862I0J1502D01*
G03X1714517Y131886I-1502J0D01*
G01X1714385Y132027D01*
X1716492Y134134D01*
X1716627Y134050D01*
G03X1717418Y133825I791J1278D01*
G03X1718913Y135181I0J1502D01*
G01X1718931Y135362D01*
X1719905D01*
X1719923Y135181D01*
G03X1722913I1495J146D01*
G01X1722931Y135362D01*
G37*
G36*
G01X1853753Y309940D02*
G02X1855470Y305794I-4147J-4146D01*
G01Y105632D01*
G02X1855366Y105456I-200J0D01*
G01X1855010Y105261D01*
X1854902Y105265D01*
X1854855Y105294D01*
G03X1853577Y106046I-11156J-17498D01*
G02X1853472Y106222I95J176D01*
G01Y305795D01*
G03X1852341Y308528I-3867J0D01*
G01X1843174Y317695D01*
G02X1839694Y326095I8401J8401D01*
G01Y453169D01*
X1839704Y453214D01*
X1839716Y453236D01*
G03X1839881Y453921I-1337J684D01*
G03X1839716Y454606I-1502J1D01*
G01X1839704Y454628D01*
X1839694Y454673D01*
Y695962D01*
X1839914Y696182D01*
X1841390D01*
X1841691Y695881D01*
Y326095D01*
G03X1844586Y319107I9884J1D01*
G01X1853753Y309940D01*
G37*
%LPC*%
G75*
G36*
G01X44458Y428806D02*
G02X45960Y430308I1502J0D01*
G01X49360D01*
G02X50862Y428806I0J-1502D01*
G01Y428805D01*
G02X50709Y428145I-1502J0D01*
G03X50873Y427620I359J-176D01*
G02X51640Y426310I-735J-1310D01*
G02X48636I-1502J0D01*
G01Y426311D01*
G02X48711Y426779I1502J-1D01*
G03X48331Y427304I-380J125D01*
G01X46989D01*
G03X46609Y426779I0J-400D01*
G02X46684Y426311I-1427J-469D01*
G01Y426310D01*
G02X43680I-1502J0D01*
G02X44447Y427620I1502J0D01*
G03X44611Y428145I-195J349D01*
G02X44458Y428805I1349J660D01*
G01Y428806D01*
G37*
G36*
G01X59668D02*
G02X61171Y430308I1503J-1D01*
G01X64573D01*
G02X66074Y428806I-1J-1502D01*
G02X65920Y428145I-1503J2D01*
G03X66084Y427620I359J-176D01*
G02X66851Y426310I-735J-1310D01*
G02X63847I-1502J0D01*
G01Y426311D01*
G02X63922Y426779I1502J-1D01*
G03X63542Y427304I-380J125D01*
G01X62200D01*
G03X61820Y426779I0J-400D01*
G02X61895Y426311I-1427J-469D01*
G01Y426310D01*
G02X60393Y424808I-1502J0D01*
G02X59042Y425654I0J1502D01*
G01X59033Y425673D01*
G02X58891Y426310I1360J637D01*
G02X59658Y427620I1502J0D01*
G03X59822Y428145I-195J349D01*
G02X59668Y428806I1349J663D01*
G37*
G36*
G01X186290Y442340D02*
G02X185869Y443383I1081J1043D01*
G02X188873I1502J0D01*
G02X188452Y442340I-1502J0D01*
G03Y441785I288J-277D01*
G02X188873Y440742I-1081J-1043D01*
G02X185869I-1502J0D01*
G02X186290Y441785I1502J0D01*
G03Y442340I-288J277D01*
G37*
G36*
G01X178964Y448202D02*
G03X179547I292J274D01*
G02X180640Y448674I1093J-1030D01*
G02Y445670I0J-1502D01*
G02X179547Y446142I0J1502D01*
G03X178964I-292J-274D01*
G02X177871Y445670I-1093J1030D01*
G02Y448674I0J1502D01*
G02X178964Y448202I0J-1502D01*
G37*
G36*
G01X185397Y447911D02*
G03X186075Y447931I333J222D01*
G02X187371Y448674I1296J-759D01*
G02Y445670I0J-1502D01*
G02X186121Y446339I0J1502D01*
G03X185443Y446319I-333J-222D01*
G02X184147Y445576I-1296J759D01*
G02Y448580I0J1502D01*
G02X185397Y447911I0J-1502D01*
G37*
G36*
G01X153360Y447610D02*
G02Y450614I0J1502D01*
G02X154545Y450035I0J-1502D01*
G03X155164Y450021I315J246D01*
G02X156306Y450547I1142J-977D01*
G02X157553Y449883I0J-1503D01*
G03X158145Y449803I332J223D01*
G02X159123Y450166I979J-1139D01*
G01X159125D01*
G02Y447162I0J-1502D01*
G02X157878Y447826I0J1503D01*
G03X157286Y447906I-332J-223D01*
G02X156308Y447543I-979J1139D01*
G01X156306D01*
G02X155121Y448122I0J1502D01*
G03X154502Y448136I-315J-246D01*
G02X153360Y447610I-1142J977D01*
G37*
G36*
G01X81203Y449245D02*
G02X81159Y449604I1458J361D01*
G02X84163I1502J0D01*
G02X83207Y448205I-1502J0D01*
G03X82963Y447736I145J-373D01*
G02X83007Y447377I-1458J-361D01*
G02X82992Y447168I-1502J3D01*
G03X83374Y446713I396J-55D01*
G02X84822Y445212I-54J-1501D01*
G02X81818I-1502J0D01*
G02X81833Y445421I1502J-3D01*
G03X81451Y445876I-396J55D01*
G02X80003Y447377I54J1501D01*
G02X80959Y448776I1502J0D01*
G03X81203Y449245I-145J373D01*
G37*
G36*
G01X44310Y451602D02*
G02X45812Y453104I1502J0D01*
G01X49212D01*
G02X50714Y451602I0J-1502D01*
G01Y451601D01*
G02X50561Y450941I-1502J0D01*
G03X50725Y450416I359J-176D01*
G02X51492Y449106I-735J-1310D01*
G02X48488I-1502J0D01*
G01Y449107D01*
G02X48563Y449575I1502J-1D01*
G03X48183Y450100I-380J125D01*
G01X46841D01*
G03X46461Y449575I0J-400D01*
G02X46536Y449107I-1427J-469D01*
G01Y449106D01*
G02X43532I-1502J0D01*
G02X44299Y450416I1502J0D01*
G03X44463Y450941I-195J349D01*
G02X44310Y451601I1349J660D01*
G01Y451602D01*
G37*
G36*
G01X186367Y454901D02*
G03X187000Y454923I308J255D01*
G02X188221Y455550I1221J-875D01*
G02Y452546I0J-1502D01*
G02X187065Y453089I0J1502D01*
G03X186432Y453067I-308J-255D01*
G02X185211Y452440I-1221J875D01*
G02X183943Y453137I0J1502D01*
G03X183267Y453134I-337J-215D01*
G02X181994Y452430I-1273J799D01*
G02Y455434I0J1502D01*
G02X183262Y454737I0J-1502D01*
G03X183938Y454740I337J215D01*
G02X185211Y455444I1273J-799D01*
G02X186367Y454901I0J-1502D01*
G37*
G36*
G01X172632Y452593D02*
G02Y455597I0J1502D01*
G02X173915Y454876I0J-1502D01*
G03X174547Y454810I341J208D01*
G02X175639Y455281I1092J-1031D01*
G01X175640D01*
G02X176778Y454759I0J-1501D01*
G03X177390Y454764I304J260D01*
G02X178546Y455308I1157J-958D01*
G02Y452304I0J-1502D01*
G02X177408Y452826I0J1501D01*
G03X176796Y452821I-304J-260D01*
G02X175640Y452277I-1157J958D01*
G02X174357Y452998I0J1502D01*
G03X173725Y453064I-341J-208D01*
G02X172633Y452593I-1092J1031D01*
G01X172632D01*
G37*
G36*
G01X32733Y667269D02*
G03X33447I357J179D01*
G02X34790Y668097I1343J-675D01*
G02Y665093I0J-1502D01*
G02X33447Y665921I0J1503D01*
G03X32733I-357J-179D01*
G02X31390Y665093I-1343J675D01*
G02Y668097I0J1502D01*
G02X32733Y667269I0J-1503D01*
G37*
G36*
G01X205234Y738064D02*
G03X205638Y738463I4J400D01*
G02X207140Y739964I1502J-1D01*
G02Y736960I0J-1502D01*
G01X207126D01*
G03X206722Y736561I-4J-400D01*
G02X205220Y735060I-1502J1D01*
G02Y738064I0J1502D01*
G01X205234D01*
G37*
G36*
G01X199220Y737860D02*
G02X200722Y739362I0J1502D01*
G01Y739360D01*
G02X200576Y738715I-1502J1D01*
G03X200996Y738147I361J-173D01*
G02X201220Y738164I225J-1485D01*
G02X199718Y736662I0J-1502D01*
G01Y736664D01*
G02X199864Y737309I1502J-1D01*
G03X199444Y737877I-361J173D01*
G02X199220Y737860I-225J1485D01*
G37*
G36*
G01X37670Y740952D02*
G02Y748156I0J3602D01*
G01X42570D01*
G02Y740952I0J-3602D01*
G01X37670D01*
G37*
G36*
G01X67370D02*
G02Y748156I0J3602D01*
G01X72270D01*
G02Y740952I0J-3602D01*
G01X67370D01*
G37*
G36*
G01X97070D02*
G02Y748156I0J3602D01*
G01X101970D01*
G02Y740952I0J-3602D01*
G01X97070D01*
G37*
G36*
G01X126770D02*
G02Y748156I0J3602D01*
G01X131670D01*
G02Y740952I0J-3602D01*
G01X126770D01*
G37*
G36*
G01X156470D02*
G02Y748156I0J3602D01*
G01X161370D01*
G02Y740952I0J-3602D01*
G01X156470D01*
G37*
G36*
G01X186170D02*
G02Y748156I0J3602D01*
G01X191070D01*
G02Y740952I0J-3602D01*
G01X186170D01*
G37*
G36*
G01X215870D02*
G02Y748156I0J3602D01*
G01X220770D01*
G02Y740952I0J-3602D01*
G01X215870D01*
G37*
G36*
G01X270998Y767626D02*
G02X270706Y768516I1210J890D01*
G02X273710I1502J0D01*
G02X272509Y767044I-1503J0D01*
G03X272267Y766415I80J-392D01*
G02X272559Y765525I-1210J-890D01*
G02X271927Y764301I-1501J0D01*
G03Y763649I232J-326D01*
G02X272559Y762425I-869J-1224D01*
G02X269555I-1502J0D01*
G02X270187Y763649I1501J0D01*
G03Y764301I-232J326D01*
G02X269555Y765525I869J1224D01*
G02X270756Y766997I1503J0D01*
G03X270998Y767626I-80J392D01*
G37*
G36*
G01X351351Y873378D02*
G02X351277Y873810I1227J433D01*
G02X353879I1301J0D01*
G02X352818Y872531I-1301J0D01*
G01X352728Y872514D01*
X351926Y871125D01*
X351956Y871038D01*
G02X352030Y870606I-1227J-433D01*
G02X349428I-1301J0D01*
G02X350489Y871885I1301J0D01*
G01X350579Y871902D01*
X351381Y873291D01*
X351351Y873378D01*
G37*
G36*
G01X358751D02*
G02X358677Y873810I1227J433D01*
G02X361279I1301J0D01*
G02X360218Y872531I-1301J0D01*
G01X360128Y872514D01*
X359326Y871125D01*
X359356Y871038D01*
G02X359430Y870606I-1227J-433D01*
G02X356828I-1301J0D01*
G02X357889Y871885I1301J0D01*
G01X357979Y871902D01*
X358781Y873291D01*
X358751Y873378D01*
G37*
G36*
G01X366151D02*
G02X366077Y873810I1227J433D01*
G02X368679I1301J0D01*
G02X367618Y872531I-1301J0D01*
G01X367528Y872514D01*
X366726Y871125D01*
X366756Y871038D01*
G02X366830Y870606I-1227J-433D01*
G02X364228I-1301J0D01*
G02X365289Y871885I1301J0D01*
G01X365379Y871902D01*
X366181Y873291D01*
X366151Y873378D01*
G37*
G36*
G01X373551D02*
G02X373477Y873810I1227J433D01*
G02X376079I1301J0D01*
G02X375018Y872531I-1301J0D01*
G01X374928Y872514D01*
X374126Y871125D01*
X374156Y871038D01*
G02X374230Y870606I-1227J-433D01*
G02X371628I-1301J0D01*
G02X372689Y871885I1301J0D01*
G01X372779Y871902D01*
X373581Y873291D01*
X373551Y873378D01*
G37*
G36*
G01X376389Y882144D02*
G02X375328Y883423I240J1279D01*
G02X377930I1301J0D01*
G02X377856Y882991I-1301J1D01*
G01X377826Y882904D01*
X378627Y881515D01*
X378718Y881498D01*
G02X379779Y880219I-240J-1279D01*
G02X377177I-1301J0D01*
G02X377251Y880651I1301J-1D01*
G01X377281Y880737D01*
X376479Y882127D01*
X376389Y882144D01*
G37*
G36*
G01X383789D02*
G02X382728Y883423I240J1279D01*
G02X385330I1301J0D01*
G02X385256Y882991I-1301J1D01*
G01X385226Y882904D01*
X386027Y881515D01*
X386118Y881498D01*
G02X387179Y880219I-240J-1279D01*
G02X384577I-1301J0D01*
G02X384651Y880651I1301J-1D01*
G01X384681Y880737D01*
X383879Y882127D01*
X383789Y882144D01*
G37*
G36*
G01X380951Y886195D02*
G02X380877Y886627I1227J433D01*
G02X383479I1301J0D01*
G02X382418Y885348I-1301J0D01*
G01X382328Y885331D01*
X381526Y883942D01*
X381556Y883855D01*
G02X381630Y883423I-1227J-433D01*
G02X379028I-1301J0D01*
G02X380089Y884702I1301J0D01*
G01X380179Y884719D01*
X380981Y886108D01*
X380951Y886195D01*
G37*
G36*
G01X388351D02*
G02X388277Y886627I1227J433D01*
G02X390879I1301J0D01*
G02X389818Y885348I-1301J0D01*
G01X389728Y885331D01*
X388926Y883942D01*
X388956Y883855D01*
G02X389030Y883423I-1227J-433D01*
G02X386428I-1301J0D01*
G02X387489Y884702I1301J0D01*
G01X387579Y884719D01*
X388381Y886108D01*
X388351Y886195D01*
G37*
G36*
G01X74790Y1563362D02*
G03Y1563887I-302J263D01*
G02X74420Y1564874I1131J987D01*
G02X77424I1502J0D01*
G02X77054Y1563887I-1501J0D01*
G03Y1563362I302J-263D01*
G02X77424Y1562374I-1132J-987D01*
G01Y1558974D01*
G02X77054Y1557986I-1502J-1D01*
G03Y1557461I302J-262D01*
G02X77424Y1556474I-1131J-987D01*
G02X74420I-1502J0D01*
G02X74790Y1557461I1501J0D01*
G03Y1557986I-302J263D01*
G02X74420Y1558974I1132J987D01*
G01Y1562374D01*
G02X74790Y1563362I1502J1D01*
G37*
G36*
G01X98604Y1566350D02*
G03X98597Y1566876I-305J259D01*
G02X98214Y1567878I1119J1002D01*
G02X101218I1502J0D01*
G02X100862Y1566907I-1502J0D01*
G03X100869Y1566381I305J-259D01*
G02X101252Y1565378I-1119J-1002D01*
G01Y1561978D01*
G02X100882Y1560990I-1502J-1D01*
G03Y1560465I302J-263D01*
G02X101252Y1559478I-1131J-987D01*
G02X98248I-1502J0D01*
G02X98618Y1560465I1501J0D01*
G03Y1560990I-302J263D01*
G02X98248Y1561978I1132J987D01*
G01Y1565378D01*
G02X98604Y1566350I1502J1D01*
G37*
G36*
G01X148695Y1571028D02*
G03X149075Y1571552I0J400D01*
G02X149000Y1572021I1427J469D01*
G02X152004I1502J0D01*
G02X151229Y1570707I-1501J0D01*
G03X151063Y1570182I194J-350D01*
G02X151214Y1569525I-1351J-656D01*
G02X149712Y1568022I-1502J-1D01*
G01X146312D01*
G02X144810Y1569525I1J1503D01*
G02X144961Y1570182I1502J1D01*
G03X144795Y1570707I-360J175D01*
G02X144020Y1572021I726J1314D01*
G02X147024I1502J0D01*
G02X146949Y1571552I-1502J0D01*
G03X147329Y1571028I380J-124D01*
G01X148695D01*
G37*
G36*
G01X72701Y1571322D02*
G03X72867Y1571847I-194J350D01*
G02X72716Y1572504I1351J656D01*
G02X74218Y1574006I1502J0D01*
G01X77618D01*
G02X79120Y1572504I0J-1502D01*
G02X78970Y1571849I-1502J-1D01*
G03X79138Y1571325I360J-173D01*
G02X79917Y1570008I-724J-1317D01*
G02X76913I-1502J0D01*
G02X76988Y1570477I1502J0D01*
G03X76608Y1571002I-380J125D01*
G01X75236D01*
G03X74856Y1570477I0J-400D01*
G02X74931Y1570008I-1427J-469D01*
G02X71927I-1502J0D01*
G02X72701Y1571322I1502J0D01*
G37*
G36*
G01X100372Y1576204D02*
G03X100751Y1576582I-21J400D01*
G02X102251Y1578006I1500J-78D01*
G01X105651D01*
G02X107151Y1576582I0J-1502D01*
G03X107530Y1576204I400J22D01*
G02X108953Y1574704I-79J-1500D01*
G02X105949I-1502J0D01*
G02X105952Y1574793I1502J-6D01*
G03X105740Y1575004I-200J11D01*
G02X105651Y1575002I-78J1500D01*
G01X102251D01*
G02X102162Y1575004I-11J1502D01*
G03X101950Y1574793I-12J-200D01*
G02X101953Y1574704I-1499J-95D01*
G02X98949I-1502J0D01*
G02X100372Y1576204I1502J0D01*
G37*
G36*
G01X103371Y1590518D02*
G03Y1591138I-253J310D01*
G02X102816Y1592304I947J1166D01*
G02X105820I1502J0D01*
G02X105265Y1591138I-1502J0D01*
G03Y1590518I253J-310D01*
G02X105820Y1589352I-947J-1166D01*
G02X102816I-1502J0D01*
G02X103371Y1590518I1502J0D01*
G37*
G36*
G01X62908Y1599102D02*
Y1602502D01*
G02X64410Y1604004I1502J0D01*
G02X65071Y1603851I1J-1502D01*
G03X65596Y1604015I176J359D01*
G02X66906Y1604782I1310J-735D01*
G02Y1601778I0J-1502D01*
G02X66437Y1601853I0J1502D01*
G03X65912Y1601473I-125J-380D01*
G01Y1600131D01*
G03X66437Y1599751I400J0D01*
G02X66906Y1599826I469J-1427D01*
G02Y1596822I0J-1502D01*
G02X65596Y1597589I0J1502D01*
G03X65071Y1597753I-349J-195D01*
G02X64410Y1597600I-660J1349D01*
G02X62908Y1599102I0J1502D01*
G37*
G36*
G01X115908Y1588142D02*
G02X115296Y1589352I890J1210D01*
G02X118300I1502J0D01*
G02X117688Y1588142I-1502J0D01*
G03Y1587498I237J-322D01*
G02X118300Y1586288I-890J-1210D01*
G02X115296I-1502J0D01*
G02X115908Y1587498I1502J0D01*
G03Y1588142I-237J322D01*
G37*
G36*
G01X148010Y514810D02*
G02X151014I1502J0D01*
G01Y514809D01*
G02X150825Y514080I-1502J0D01*
G03X151096Y513494I349J-194D01*
G02X152302Y512021I-297J-1473D01*
G02X149298I-1502J0D01*
G01Y512022D01*
G02X149487Y512751I1502J0D01*
G03X149216Y513337I-349J194D01*
G02X148010Y514810I297J1473D01*
G37*
G36*
G01X149557Y492851D02*
G02Y495855I0J1502D01*
G02X150415Y495586I0J-1503D01*
G03X151028Y495802I229J328D01*
G02X152470Y496885I1442J-419D01*
G02Y493881I0J-1502D01*
G02X151612Y494150I0J1503D01*
G03X150999Y493934I-229J-328D01*
G02X149557Y492851I-1442J419D01*
G37*
G36*
G01X138878Y511048D02*
G02X140380Y512550I0J1502D01*
G02X140367Y512355I-1502J2D01*
G03X140883Y511921I397J-52D01*
G02X141329Y511989I447J-1434D01*
G02X142831Y510487I0J-1502D01*
G02X142357Y509392I-1502J0D01*
G03X142385Y508785I274J-292D01*
G02X142964Y507600I-923J-1185D01*
G02X141462Y506098I-1502J0D01*
G02X140324Y506620I0J1501D01*
G03X139682Y506570I-303J-262D01*
G02X138408Y505864I-1274J796D01*
G02Y508868I0J1502D01*
G02X139546Y508346I0J-1501D01*
G03X140188Y508396I303J262D01*
G02X140434Y508695I1273J-797D01*
G03X140406Y509302I-274J292D01*
G02X139827Y510487I923J1185D01*
G02X139840Y510682I1502J-2D01*
G03X139324Y511116I-397J52D01*
G02X138878Y511048I-447J1434D01*
G37*
G36*
G01X113785Y495960D02*
G02X112964Y497235I0J902D01*
G03X113190Y498271I-2273J1039D01*
G03X110689Y500772I-2501J0D01*
G03X108745Y499844I0J-2500D01*
G02X107406Y499773I-701J566D01*
G01Y499774D01*
X104718Y502461D01*
Y504125D01*
G03X104437Y504778I-900J0D01*
G01X104373Y504839D01*
G03X103737Y504722I-275J-290D01*
G02X102384Y503872I-1353J652D01*
G02Y506876I0J1502D01*
G02X103737Y506026I0J-1502D01*
G03X104373Y505909I361J173D01*
G01X104437Y505970D01*
G03X104718Y506623I-619J653D01*
G01Y519502D01*
G02Y521952I869J1225D01*
G01Y523363D01*
X106719Y525364D01*
X122719D01*
X123186Y525831D01*
Y532044D01*
X123740Y532598D01*
X124988D01*
Y543664D01*
G02X125282Y544372I1002J-1D01*
G01X127240Y546330D01*
G02X127948Y546624I709J-708D01*
G01X132547D01*
X138618Y552695D01*
Y587656D01*
G02X138912Y588364I1002J-1D01*
G01X161963Y611415D01*
G02X162671Y611708I708J-709D01*
G01X193925D01*
G02X194633Y611415I0J-1002D01*
G01X196776Y609272D01*
X197214D01*
X197272Y609331D01*
G02X198336Y609773I1064J-1060D01*
G02X199543Y609165I0J-1502D01*
G03X200185I321J239D01*
G02X201392Y609773I1207J-894D01*
G02X202894Y608271I0J-1502D01*
G02X201390Y606769I-1502J0D01*
G01X201306D01*
X199891Y605354D01*
G02X199183Y605060I-709J708D01*
G01X196300D01*
G02X195592Y605354I1J1002D01*
G01X192845Y608100D01*
X163751D01*
X142122Y586471D01*
Y551658D01*
G02X141828Y550950I-1002J1D01*
G01X134292Y543414D01*
G02X133584Y543120I-709J708D01*
G01X128985D01*
X128492Y542627D01*
Y534629D01*
X129676Y533444D01*
X129760D01*
G02X131092Y532640I2J-1502D01*
G03X131806Y532653I354J186D01*
G02X133160Y533504I1354J-652D01*
G02X134035Y533223I0J-1503D01*
G01X134173Y533124D01*
X166273Y565224D01*
G02X166981Y565518I709J-708D01*
G01X186417D01*
X194898Y573999D01*
Y574962D01*
G02X195192Y575670I1002J-1D01*
G01X196692Y577170D01*
G02X197400Y577464I709J-708D01*
G01X198797D01*
G03X199187Y577949I-1J400D01*
G02X199152Y578271I1467J322D01*
G02X200122Y579675I1501J0D01*
G03X200325Y580251I-142J374D01*
G02X200144Y580743I1298J757D01*
G03X199627Y581052I-394J-71D01*
G02X199165Y580979I-463J1429D01*
G01X199164D01*
G02Y583983I0J1502D01*
G02X200642Y582747I0J-1502D01*
G03X201159Y582438I394J71D01*
G02X201621Y582511I463J-1429D01*
G01X201622D01*
G02X203124Y581009I0J-1502D01*
G02X202154Y579605I-1501J0D01*
G03X201951Y579029I142J-374D01*
G02X202156Y578272I-1297J-758D01*
G01Y578271D01*
G02X201142Y576850I-1503J0D01*
G03X200989Y576189I130J-378D01*
G01X201403Y575775D01*
X201479Y575770D01*
G02X202894Y574271I-86J-1499D01*
G02X201392Y572769I-1502J0D01*
G02X200185Y573377I0J1502D01*
G03X199543I-321J-239D01*
G02X198710Y572816I-1207J894D01*
G01X198657Y572803D01*
X188162Y562308D01*
G02X187454Y562014I-709J708D01*
G01X168018D01*
X148299Y542295D01*
X148289Y542283D01*
G02X148187Y542163I-812J586D01*
G01X133930Y527906D01*
Y527692D01*
X133430Y527191D01*
Y519899D01*
X131547Y518014D01*
X119255D01*
X118102Y516861D01*
Y497441D01*
X117804Y497144D01*
X117789Y497109D01*
G02X117009Y496329I-1378J598D01*
G01X116974Y496314D01*
X116621Y495960D01*
X113785D01*
G37*
G36*
G01X128193Y663417D02*
G02X129595Y662015I0J-1402D01*
G01Y662013D01*
G02X129442Y661377I-1402J1D01*
G01X133502Y657317D01*
Y639758D01*
X134088Y639172D01*
X134999D01*
X136224Y640397D01*
Y644056D01*
G02X136518Y644764I1002J-1D01*
G01X139442Y647688D01*
G02X140150Y647982I709J-708D01*
G01X153504D01*
G02X154212Y647688I-1J-1002D01*
G01X169037Y632864D01*
X177463D01*
X189170Y644570D01*
G02X189878Y644864I709J-708D01*
G01X194622D01*
G02X195330Y644570I-1J-1002D01*
G01X196628Y643272D01*
X197217D01*
G02X198336Y643773I1120J-1001D01*
G02X199543Y643165I0J-1502D01*
G03X200185I321J239D01*
G02X201392Y643773I1207J-894D01*
G02X202894Y642271I0J-1502D01*
G02X201390Y640769I-1502J0D01*
G01X201306D01*
X199691Y639154D01*
G02X198983Y638860I-709J708D01*
G01X196500D01*
G02X195792Y639154I1J1002D01*
G01X193585Y641360D01*
X190915D01*
X179208Y629654D01*
G02X178500Y629360I-709J708D01*
G01X168000D01*
G02X167292Y629654I1J1002D01*
G01X152467Y644478D01*
X141382D01*
X139730Y642826D01*
Y632147D01*
G02X139436Y631439I-1002J1D01*
G01X136039Y628042D01*
G02X135331Y627748I-709J708D01*
G01X114666D01*
X114150Y627535D01*
G03X114369Y626771I153J-370D01*
G02X117933Y627066I3565J-21393D01*
G01X117935D01*
G02X96246Y605378I-1J-21688D01*
G02X109851Y625503I21687J0D01*
G03X109702Y626274I-149J371D01*
G01X106049D01*
G02X105341Y626568I1J1002D01*
G01X101561Y630348D01*
G02X101268Y631056I709J708D01*
G01Y633347D01*
G02X100767Y634466I1001J1120D01*
G02X103771I1502J0D01*
G02X103270Y633347I-1502J1D01*
G01Y631471D01*
X106464Y628278D01*
X110709D01*
X114084Y629675D01*
G02X114467Y629752I385J-925D01*
G01X134916D01*
X137726Y632562D01*
Y638101D01*
G03X137044Y638383I-400J-1D01*
G01X136122Y637462D01*
G02X135414Y637168I-709J708D01*
G01X133502D01*
Y636043D01*
X133674Y636019D01*
G02X134969Y634531I-207J-1488D01*
G02X131965I-1502J0D01*
G02X131968Y634633I1502J7D01*
G03X131570Y635060I-399J27D01*
G01X130994D01*
G02X130057Y634701I-937J1043D01*
G01X130055D01*
G02X129348Y634893I1J1402D01*
G01X127075Y632620D01*
X121755D01*
G02X120440Y631845I-1315J728D01*
G02X119423Y632242I0J1501D01*
G03X118857Y632217I-271J-295D01*
G02X117750Y631730I-1107J1015D01*
G02X116532Y632353I0J1502D01*
G03X115857Y632310I-324J-235D01*
G02X114540Y631530I-1317J722D01*
G01X114539D01*
G02X113551Y631901I0J1502D01*
G03X113000Y631878I-263J-301D01*
G02X112195Y631445I-1080J1044D01*
G03X111870Y631016I73J-393D01*
G02X111876Y630879I-1496J-134D01*
G02X110374Y629377I-1502J0D01*
G02X109222Y629915I0J1502D01*
G03X108615Y629923I-307J-256D01*
G02X107489Y629415I-1126J994D01*
G02X105987Y630917I0J1502D01*
G01Y630918D01*
G02X106180Y631654I1502J-1D01*
G03X105890Y632246I-348J196D01*
G02X104608Y633732I220J1486D01*
G02X107612I1502J0D01*
G01Y633731D01*
G02X107419Y632995I-1502J1D01*
G03X107709Y632403I348J-196D01*
G02X108641Y631881I-220J-1486D01*
G03X109248Y631873I307J256D01*
G02X110099Y632356I1127J-994D01*
G03X110424Y632785I-73J393D01*
G02X110418Y632922I1496J134D01*
G02X111920Y634424I1502J0D01*
G01X111921D01*
G02X112909Y634053I0J-1502D01*
G03X113460Y634076I263J301D01*
G02X114540Y634534I1080J-1044D01*
G02X115758Y633911I0J-1502D01*
G03X116433Y633954I324J235D01*
G02X116790Y634387I1317J-722D01*
G01X116662Y634740D01*
X116295D01*
X115533Y635503D01*
X115473Y635798D01*
G03X114509Y637132I-1961J-402D01*
G02X113908Y638172I600J1041D01*
G01Y640907D01*
X115528Y642528D01*
Y655286D01*
X113908Y656907D01*
Y662737D01*
X114874Y663704D01*
X127115D01*
X127555Y663264D01*
G02X128191Y663417I637J-1249D01*
G01X128193D01*
G37*
G36*
G01X185220Y578886D02*
G03X185766I273J292D01*
G02X186793Y579292I1027J-1096D01*
G02X187780Y578922I0J-1501D01*
G03X188306I263J302D01*
G02X189293Y579292I987J-1131D01*
G02X190795Y577790I0J-1502D01*
G02X190389Y576763I-1502J0D01*
G03Y576216I292J-273D01*
G02X190795Y575189I-1096J-1027D01*
G02X189293Y573687I-1502J0D01*
G02X188190Y574170I0J1501D01*
G03X187896I-147J-136D01*
G02X187812Y574086I-1103J1019D01*
G03Y573792I136J-147D01*
G02X188295Y572689I-1018J-1103D01*
G02X186793Y571187I-1502J0D01*
G02X185766Y571593I0J1502D01*
G03X185220I-273J-292D01*
G02X183166I-1027J1096D01*
G03X182620I-273J-292D01*
G02X180566I-1027J1096D01*
G03X180020I-273J-292D01*
G02X177966I-1027J1096D01*
G03X177420I-273J-292D01*
G02X175366I-1027J1096D01*
G03X174820I-273J-292D01*
G02X173793Y571187I-1027J1096D01*
G02X172806Y571557I0J1501D01*
G03X172280I-263J-302D01*
G02X171293Y571187I-987J1131D01*
G02X169791Y572689I0J1502D01*
G02X170161Y573676I1501J0D01*
G03Y574202I-302J263D01*
G02X169791Y575189I1131J987D01*
G02X170197Y576216I1502J0D01*
G03Y576763I-292J274D01*
G02X169791Y577790I1096J1027D01*
G02X171293Y579292I1502J0D01*
G02X172280Y578922I0J-1501D01*
G03X172806I263J302D01*
G02X173793Y579292I987J-1131D01*
G02X174820Y578886I0J-1502D01*
G03X175366I273J292D01*
G02X177420I1027J-1096D01*
G03X177966I273J292D01*
G02X180020I1027J-1096D01*
G03X180566I273J292D01*
G02X182620I1027J-1096D01*
G03X183166I273J292D01*
G02X185220I1027J-1096D01*
G37*
G36*
G01X203637Y597543D02*
G03X204247I305J259D01*
G02X206537I1145J-972D01*
G03X207147I305J259D01*
G02X208292Y598073I1145J-972D01*
G02X209794Y596571I0J-1502D01*
G02X208662Y595115I-1502J0D01*
G03X208367Y594653I98J-388D01*
G02X208394Y594371I-1475J-284D01*
G02X208211Y593653I-1502J0D01*
G03X208454Y593077I352J-191D01*
G02X209523Y591665I-398J-1412D01*
G02X209405Y591089I-1467J0D01*
G03X209566Y590590I368J-157D01*
G02Y588080I-760J-1255D01*
G03X209405Y587581I207J-342D01*
G02X209523Y587005I-1349J-576D01*
G02X209405Y586429I-1467J0D01*
G03X209566Y585930I368J-157D01*
G02X210273Y584675I-760J-1255D01*
G02X207339I-1467J0D01*
G02X207457Y585251I1467J0D01*
G03X207296Y585750I-368J157D01*
G02Y588260I760J1255D01*
G03X207457Y588759I-207J342D01*
G02X207339Y589335I1349J576D01*
G02X207457Y589911I1467J0D01*
G03X207296Y590410I-368J157D01*
G02X206739Y591020I761J1254D01*
G03X206123Y591151I-359J-176D01*
G02X205162Y590803I-961J1153D01*
G02X204017Y591333I0J1502D01*
G03X203407I-305J-259D01*
G02X202262Y590803I-1145J972D01*
G02X200760Y592305I0J1502D01*
G02X202064Y593794I1502J0D01*
G03X202406Y594249I-53J396D01*
G02X202390Y594471I1486J219D01*
G02X202404Y594677I1502J1D01*
G03X202110Y595118I-396J54D01*
G02X200990Y596571I383J1453D01*
G02X202492Y598073I1502J0D01*
G02X203637Y597543I0J-1502D01*
G37*
G36*
G01X172828Y598101D02*
G03Y598673I-280J286D01*
G02X172376Y599747I1050J1074D01*
G02X173878Y601249I1502J0D01*
G02X175026Y600715I0J-1501D01*
G03X175609Y600685I306J258D01*
G02X176651Y601105I1042J-1083D01*
G02X177638Y600735I0J-1501D01*
G03X178164I263J302D01*
G02X180138I987J-1131D01*
G03X180664I263J302D01*
G02X182638I987J-1131D01*
G03X183164I263J302D01*
G02X184151Y601105I987J-1131D01*
G02X185182Y600695I0J-1501D01*
G03X185739Y600702I275J291D01*
G02X186796Y601137I1057J-1067D01*
G02X188298Y599635I0J-1502D01*
G02X187846Y598561I-1502J0D01*
G03Y597989I280J-286D01*
G02Y595841I-1050J-1074D01*
G03Y595269I280J-286D01*
G02X188298Y594195I-1050J-1074D01*
G02X186796Y592693I-1502J0D01*
G02X185765Y593103I0J1501D01*
G03X185208Y593096I-275J-291D01*
G02X184151Y592661I-1057J1067D01*
G02X183164Y593031I0J1501D01*
G03X182638I-263J-302D01*
G02X180664I-987J1131D01*
G03X180138I-263J-302D01*
G02X178164I-987J1131D01*
G03X177638I-263J-302D01*
G02X176651Y592661I-987J1131D01*
G02X175503Y593195I0J1501D01*
G03X174920Y593225I-306J-258D01*
G02X173878Y592805I-1042J1083D01*
G02X172376Y594307I0J1502D01*
G02X172828Y595381I1502J0D01*
G03Y595953I-280J286D01*
G02Y598101I1050J1074D01*
G37*
G36*
G01X200144Y614743D02*
G03X199627Y615052I-394J-71D01*
G02X199165Y614979I-463J1429D01*
G01X199164D01*
G02Y617983I0J1502D01*
G02X200642Y616747I0J-1502D01*
G03X201159Y616438I394J71D01*
G02X201621Y616511I463J-1429D01*
G01X201622D01*
G02X203124Y615009I0J-1502D01*
G02X202154Y613605I-1501J0D01*
G03X201951Y613029I142J-374D01*
G02X202156Y612272I-1297J-758D01*
G01Y612271D01*
G02X199152I-1502J0D01*
G02X200122Y613675I1501J0D01*
G03X200325Y614251I-142J374D01*
G02X200144Y614743I1298J757D01*
G37*
G36*
G01X203637Y665543D02*
G03X204247I305J259D01*
G02X206537I1145J-972D01*
G03X207147I305J259D01*
G02X208292Y666073I1145J-972D01*
G02X209794Y664571I0J-1502D01*
G02X208662Y663115I-1502J0D01*
G03X208367Y662653I98J-388D01*
G02X208394Y662371I-1475J-284D01*
G02X208211Y661653I-1502J0D01*
G03X208454Y661077I352J-191D01*
G02X209523Y659665I-398J-1412D01*
G02X209405Y659089I-1467J0D01*
G03X209566Y658590I368J-157D01*
G02Y656080I-760J-1255D01*
G03X209405Y655581I207J-342D01*
G02X209523Y655005I-1349J-576D01*
G02X209405Y654429I-1467J0D01*
G03X209566Y653930I368J-157D01*
G02X210273Y652675I-760J-1255D01*
G02X207339I-1467J0D01*
G02X207457Y653251I1467J0D01*
G03X207296Y653750I-368J157D01*
G02Y656260I760J1255D01*
G03X207457Y656759I-207J342D01*
G02X207339Y657335I1349J576D01*
G02X207457Y657911I1467J0D01*
G03X207296Y658410I-368J157D01*
G02X206739Y659020I761J1254D01*
G03X206123Y659151I-359J-176D01*
G02X205162Y658803I-961J1153D01*
G02X204017Y659333I0J1502D01*
G03X203407I-305J-259D01*
G02X202262Y658803I-1145J972D01*
G02X200760Y660305I0J1502D01*
G02X202064Y661794I1502J0D01*
G03X202406Y662249I-53J396D01*
G02X202390Y662471I1486J219D01*
G02X202404Y662677I1502J1D01*
G03X202110Y663118I-396J54D01*
G02X200990Y664571I383J1453D01*
G02X202492Y666073I1502J0D01*
G02X203637Y665543I0J-1502D01*
G37*
G36*
G01X209254Y670204D02*
G03X208686I-284J-282D01*
G02X207620Y669760I-1066J1058D01*
G02Y672764I0J1502D01*
G02X208686Y672320I0J-1502D01*
G03X209254I284J282D01*
G02X210320Y672764I1066J-1058D01*
G02Y669760I0J-1502D01*
G02X209254Y670204I0J1502D01*
G37*
G36*
G01X194976Y677144D02*
G03X194405I-285J-280D01*
G02X193332Y676693I-1073J1051D01*
G02Y679697I0J1502D01*
G02X194405Y679246I0J-1502D01*
G03X194976I286J280D01*
G02X196049Y679697I1073J-1051D01*
G02Y676693I0J-1502D01*
G02X194976Y677144I0J1502D01*
G37*
G36*
G01X113935Y680074D02*
X157781D01*
G02X158454Y679795I0J-951D01*
G01X165233Y673016D01*
G02X165512Y672343I-672J-673D01*
G01Y667584D01*
X176902Y656194D01*
X194403D01*
G02X195076Y655915I0J-951D01*
G01X199013Y651978D01*
X199100Y651982D01*
G02X199164Y651983I55J-1501D01*
G02X200642Y650747I0J-1502D01*
G03X201159Y650438I394J71D01*
G02X201621Y650511I463J-1429D01*
G01X201622D01*
G02X203124Y649009I0J-1502D01*
G02X202154Y647605I-1501J0D01*
G03X201951Y647029I142J-374D01*
G02X202156Y646272I-1297J-758D01*
G01Y646271D01*
G02X199152I-1502J0D01*
G02X200122Y647675I1501J0D01*
G03X200325Y648251I-142J374D01*
G02X200144Y648743I1298J757D01*
G03X199627Y649052I-394J-71D01*
G02X199165Y648979I-463J1429D01*
G01X199164D01*
G02X197662Y650481I0J1502D01*
G02X197663Y650545I1502J9D01*
G01X197667Y650632D01*
X194009Y654290D01*
X176508D01*
G02X175835Y654569I0J951D01*
G01X163887Y666517D01*
G02X163608Y667190I672J673D01*
G01Y671949D01*
X157387Y678170D01*
X114329D01*
X111417Y675258D01*
X111403Y675232D01*
G02X111230Y675001I-880J479D01*
G01X108522Y672293D01*
Y662393D01*
G02X108511Y662243I-1001J-2D01*
G02X108547Y661917I-1466J-327D01*
G02X105543I-1502J0D01*
G02X106405Y663276I1502J0D01*
G01X106520Y663330D01*
Y672708D01*
G02X106813Y673416I1002J0D01*
G01X109814Y676417D01*
G02X110045Y676590I710J-707D01*
G01X110071Y676604D01*
X113262Y679795D01*
G02X113935Y680074I673J-672D01*
G37*
G36*
G01X195715Y685712D02*
G03X195107Y685867I-365J-163D01*
G02X194196Y685559I-911J1193D01*
G02Y688563I0J1502D01*
G02X195567Y687675I0J-1502D01*
G03X196175Y687520I365J163D01*
G02X197086Y687828I911J-1193D01*
G02Y684824I0J-1502D01*
G02X195715Y685712I0J1502D01*
G37*
G36*
G01X197216Y697572D02*
G03Y697866I-136J147D01*
G02X196733Y698969I1018J1103D01*
G02X198235Y700471I1502J0D01*
G02X199222Y700101I0J-1501D01*
G03X199748I263J302D01*
G02X200735Y700471I987J-1131D01*
G02X202237Y698969I0J-1502D01*
G02X201867Y697982I-1501J0D01*
G03Y697456I302J-263D01*
G02X202237Y696469I-1131J-987D01*
G02X200735Y694967I-1502J0D01*
G02X199748Y695337I0J1501D01*
G03X199222I-263J-302D01*
G02X197248I-987J1131D01*
G03X196722I-263J-302D01*
G02X195735Y694967I-987J1131D01*
G02Y697971I0J1502D01*
G02X196838Y697488I0J-1501D01*
G03X197132I147J136D01*
G02X197216Y697572I1103J-1019D01*
G37*
G36*
G01X100568Y517596D02*
G02X100481Y518100I1416J504D01*
G02X101983Y516598I1502J0D01*
G02X101653Y516635I1J1502D01*
G03X101188Y516110I-88J-390D01*
G02X101275Y515606I-1416J-504D01*
G02X99773Y517108I-1502J0D01*
G02X100103Y517071I-1J-1502D01*
G03X100568Y517596I88J390D01*
G37*
G36*
G01X116703Y529383D02*
G03X117305Y529524I243J318D01*
G02X118652Y530362I1347J-664D01*
G02Y527358I0J-1502D01*
G02X117742Y527665I0J1502D01*
G03X117140Y527524I-243J-318D01*
G02X115793Y526686I-1347J664D01*
G02X114450Y527514I0J1503D01*
G03X113736I-357J-179D01*
G02X112393Y526686I-1343J675D01*
G02Y529690I0J1502D01*
G02X113736Y528862I0J-1503D01*
G03X114450I357J179D01*
G02X115793Y529690I1343J-675D01*
G02X116703Y529383I0J-1502D01*
G37*
G36*
G01X131926Y539129D02*
G02X131098Y540472I675J1343D01*
G02X134102I1502J0D01*
G02X133274Y539129I-1503J0D01*
G03Y538415I179J-357D01*
G02X134102Y537072I-675J-1343D01*
G02X131098I-1502J0D01*
G02X131926Y538415I1503J0D01*
G03Y539129I-179J357D01*
G37*
G36*
G01X203161Y570702D02*
G02X203108Y571097I1449J395D01*
G02X204610Y569595I1502J0D01*
G01X204609D01*
G02X204265Y569635I0J1502D01*
G03X203787Y569141I-92J-389D01*
G02X203840Y568746I-1449J-395D01*
G02X202338Y570248I-1502J0D01*
G01X202339D01*
G02X202683Y570208I0J-1502D01*
G03X203161Y570702I92J389D01*
G37*
G36*
G01Y604702D02*
G02X203108Y605097I1449J395D01*
G02X204610Y603595I1502J0D01*
G01X204609D01*
G02X204265Y603635I0J1502D01*
G03X203787Y603141I-92J-389D01*
G02X203840Y602746I-1449J-395D01*
G02X202338Y604248I-1502J0D01*
G01X202339D01*
G02X202683Y604208I0J-1502D01*
G03X203161Y604702I92J389D01*
G37*
G36*
G01X87802Y627572D02*
G02X86459Y626744I-1343J675D01*
G02Y629748I0J1502D01*
G02X87802Y628920I0J-1503D01*
G03X88516I357J179D01*
G02X89859Y629748I1343J-675D01*
G02Y626744I0J-1502D01*
G02X88516Y627572I0J1503D01*
G03X87802I-357J-179D01*
G37*
G36*
G01X203161Y638702D02*
G02X203108Y639097I1449J395D01*
G02X204610Y637595I1502J0D01*
G01X204609D01*
G02X204265Y637635I0J1502D01*
G03X203787Y637141I-92J-389D01*
G02X203840Y636746I-1449J-395D01*
G02X202338Y638248I-1502J0D01*
G01X202339D01*
G02X202683Y638208I0J-1502D01*
G03X203161Y638702I92J389D01*
G37*
G36*
G01X80894Y657659D02*
G02X80241Y657509I-654J1352D01*
G02X81743Y659011I0J1502D01*
G02X81736Y658863I-1502J-3D01*
G03X82308Y658463I398J-40D01*
G02X82961Y658613I654J-1352D01*
G02X81459Y657111I0J-1502D01*
G02X81466Y657259I1502J3D01*
G03X80894Y657659I-398J40D01*
G37*
G36*
G01X214292Y602522D02*
X214304Y602489D01*
G02X214393Y601981I-1413J-509D01*
G02X214304Y601473I-1502J1D01*
G01X214292Y601440D01*
Y583552D01*
G02X213882Y582562I-1401J0D01*
G01X212302Y580981D01*
Y572743D01*
X213882Y571162D01*
G02X214292Y570172I-991J-990D01*
G01Y567173D01*
X214304Y567140D01*
G02X214393Y566632I-1413J-509D01*
G02X212891Y565130I-1502J0D01*
G02X211430Y566286I0J1501D01*
G03X210904Y566569I-389J-93D01*
G02X210393Y566479I-512J1412D01*
G01X210391D01*
G02Y569483I0J1502D01*
G01X210392D01*
G02X211184Y569257I0J-1502D01*
G03X211490Y569426I106J170D01*
G01Y569590D01*
X209909Y571171D01*
G02X209498Y572162I991J992D01*
G01Y581562D01*
G02X209909Y582553I1402J-1D01*
G01X211490Y584134D01*
Y600212D01*
G03X210943Y600584I-400J0D01*
G02X210392Y600479I-552J1397D01*
G01X210391D01*
G02Y603483I0J1502D01*
G01X210392D01*
G02X210943Y603378I-1J-1502D01*
G03X211490Y603750I147J372D01*
G01Y605090D01*
X210209Y606371D01*
G02X209798Y607362I991J992D01*
G01Y616462D01*
G02X209846Y616823I1402J-3D01*
G03X209319Y617301I-387J103D01*
G02X208806Y617208I-514J1374D01*
G02X207339Y618675I0J1467D01*
G02X207457Y619251I1467J0D01*
G03X207296Y619750I-368J157D01*
G02Y622260I760J1255D01*
G03X207457Y622759I-207J342D01*
G02X207339Y623335I1349J576D01*
G02X207457Y623911I1467J0D01*
G03X207296Y624410I-368J157D01*
G02X206739Y625020I761J1254D01*
G03X206123Y625151I-359J-176D01*
G02X205162Y624803I-961J1153D01*
G02X204017Y625333I0J1502D01*
G03X203407I-305J-259D01*
G02X202262Y624803I-1145J972D01*
G02X200760Y626305I0J1502D01*
G02X202064Y627794I1502J0D01*
G03X202406Y628249I-53J396D01*
G02X202390Y628471I1486J219D01*
G02X202404Y628677I1502J1D01*
G03X202110Y629118I-396J54D01*
G02X200990Y630571I383J1453D01*
G02X202492Y632073I1502J0D01*
G02X203637Y631543I0J-1502D01*
G03X204247I305J259D01*
G02X206537I1145J-972D01*
G03X207147I305J259D01*
G02X208292Y632073I1145J-972D01*
G02X209794Y630571I0J-1502D01*
G02X208662Y629115I-1502J0D01*
G03X208367Y628653I98J-388D01*
G02X208394Y628371I-1475J-284D01*
G02X208211Y627653I-1502J0D01*
G03X208454Y627077I352J-191D01*
G02X209523Y625665I-398J-1412D01*
G02X209405Y625089I-1467J0D01*
G03X209566Y624590I368J-157D01*
G02Y622080I-760J-1255D01*
G03X209405Y621581I207J-342D01*
G02X209523Y621005I-1349J-576D01*
G02X209405Y620429I-1467J0D01*
G03X209566Y619930I368J-157D01*
G02X210273Y618675I-760J-1255D01*
G02X210264Y618515I-1467J2D01*
G03X210945Y618189I398J-44D01*
G01X211490Y618734D01*
Y634212D01*
G03X210943Y634584I-400J0D01*
G02X210392Y634479I-552J1397D01*
G01X210391D01*
G02Y637483I0J1502D01*
G01X210392D01*
G02X210989Y637359I-1J-1502D01*
G03X211548Y637725I159J367D01*
G01Y638644D01*
X211182Y639010D01*
X208900D01*
G02X208015Y639377I1J1252D01*
G01X204215Y643177D01*
G02X203848Y644062I885J886D01*
G01Y650244D01*
X197415Y656677D01*
G02X197048Y657562I885J886D01*
G01Y663744D01*
X194915Y665877D01*
G02X194548Y666762I885J886D01*
G01Y672062D01*
G02X194915Y672947I1252J-1D01*
G01X195715Y673747D01*
G02X196600Y674114I886J-885D01*
G01X198033D01*
X198057Y674119D01*
G02X198420Y674164I365J-1457D01*
G02X199922Y672662I0J-1502D01*
G02X199276Y671428I-1502J0D01*
G03X199292Y670760I228J-329D01*
G02X199997Y669487I-797J-1273D01*
G02X198495Y667985I-1502J0D01*
G02X197671Y668231I0J1503D01*
G03X197052Y667897I-219J-334D01*
G01Y667280D01*
X199185Y665147D01*
G02X199552Y664262I-885J-886D01*
G01Y658080D01*
X205985Y651647D01*
G02X206352Y650762I-885J-886D01*
G01Y644580D01*
X209418Y641514D01*
X211700D01*
G02X212585Y641147I-1J-1252D01*
G01X213685Y640047D01*
G02X214052Y639162I-885J-886D01*
G01Y636935D01*
G02X214393Y635983I-1161J-953D01*
G01Y635981D01*
G02X214304Y635473I-1502J1D01*
G01X214292Y635440D01*
Y618152D01*
G02X213882Y617162I-1401J0D01*
G01X212602Y615881D01*
Y607943D01*
X213882Y606662D01*
G02X214292Y605672I-991J-990D01*
G01Y602522D01*
G37*
G36*
G01X148795Y697773D02*
G03X148223Y697769I-284J-282D01*
G02X147141Y697309I-1082J1043D01*
G02Y700313I0J1502D01*
G02X148207Y699869I0J-1502D01*
G03X148779Y699873I284J282D01*
G02X149861Y700333I1082J-1043D01*
G02Y697329I0J-1502D01*
G02X148795Y697773I0J1502D01*
G37*
G36*
G01X148598Y705735D02*
G03X148054I-272J-293D01*
G02X147031Y705333I-1023J1101D01*
G02Y708337I0J1502D01*
G02X148054Y707935I0J-1503D01*
G03X148598I272J293D01*
G02X149621Y708337I1023J-1101D01*
G02Y705333I0J-1502D01*
G02X148598Y705735I0J1503D01*
G37*
G36*
G01X155619Y705778D02*
G03X155047Y705774I-284J-282D01*
G02X153965Y705314I-1082J1043D01*
G02Y708318I0J1502D01*
G02X155031Y707874I0J-1502D01*
G03X155603Y707878I284J282D01*
G02X156685Y708338I1082J-1043D01*
G02Y705334I0J-1502D01*
G02X155619Y705778I0J1502D01*
G37*
G36*
G01X148646Y720560D02*
G03X148102I-272J-293D01*
G02X147079Y720158I-1023J1101D01*
G02Y723162I0J1502D01*
G02X148102Y722760I0J-1503D01*
G03X148646I272J293D01*
G02X149669Y723162I1023J-1101D01*
G02Y720158I0J-1502D01*
G02X148646Y720560I0J1503D01*
G37*
G36*
G01X155446D02*
G03X154902I-272J-293D01*
G02X153879Y720158I-1023J1101D01*
G02Y723162I0J1502D01*
G02X154902Y722760I0J-1503D01*
G03X155446I272J293D01*
G02X156469Y723162I1023J-1101D01*
G02Y720158I0J-1502D01*
G02X155446Y720560I0J1503D01*
G37*
G36*
G01X268418Y739529D02*
G03X268836Y739987I23J399D01*
G02X268820Y740207I1486J219D01*
G02X270322Y738705I1502J0D01*
G02X270235Y738707I-9J1502D01*
G03X269817Y738249I-23J-399D01*
G02X269833Y738029I-1486J-219D01*
G02X268331Y739531I-1502J0D01*
G02X268418Y739529I9J-1502D01*
G37*
G36*
G01X355081Y855103D02*
X354279Y856493D01*
X354189Y856510D01*
G02X353128Y857789I240J1279D01*
G02X355730I1301J0D01*
G02X355656Y857357I-1301J1D01*
G01X355626Y857270D01*
X356428Y855880D01*
X356518Y855863D01*
G02X357579Y854584I-240J-1279D01*
G02X354977I-1301J0D01*
G02X355051Y855016I1301J-1D01*
G01X355081Y855103D01*
G37*
G36*
G01X362481D02*
X361679Y856493D01*
X361589Y856510D01*
G02X360528Y857789I240J1279D01*
G02X363130I1301J0D01*
G02X363056Y857357I-1301J1D01*
G01X363026Y857270D01*
X363828Y855880D01*
X363918Y855863D01*
G02X364979Y854584I-240J-1279D01*
G02X362377I-1301J0D01*
G02X362451Y855016I1301J-1D01*
G01X362481Y855103D01*
G37*
G36*
G01X369881D02*
X369079Y856493D01*
X368989Y856510D01*
G02X367928Y857789I240J1279D01*
G02X370530I1301J0D01*
G02X370456Y857357I-1301J1D01*
G01X370426Y857270D01*
X371228Y855880D01*
X371318Y855863D01*
G02X372379Y854584I-240J-1279D01*
G02X369777I-1301J0D01*
G02X369851Y855016I1301J-1D01*
G01X369881Y855103D01*
G37*
G36*
G01X377281D02*
X376479Y856493D01*
X376389Y856510D01*
G02X375328Y857789I240J1279D01*
G02X377930I1301J0D01*
G02X377856Y857357I-1301J1D01*
G01X377826Y857270D01*
X378628Y855880D01*
X378718Y855863D01*
G02X379779Y854584I-240J-1279D01*
G02X377177I-1301J0D01*
G02X377251Y855016I1301J-1D01*
G01X377281Y855103D01*
G37*
G36*
G01X384681D02*
X383879Y856493D01*
X383789Y856510D01*
G02X382728Y857789I240J1279D01*
G02X385330I1301J0D01*
G02X385256Y857357I-1301J1D01*
G01X385226Y857270D01*
X386028Y855880D01*
X386118Y855863D01*
G02X387179Y854584I-240J-1279D01*
G02X384577I-1301J0D01*
G02X384651Y855016I1301J-1D01*
G01X384681Y855103D01*
G37*
G36*
G01X392081D02*
X391279Y856493D01*
X391189Y856510D01*
G02X390128Y857789I240J1279D01*
G02X392730I1301J0D01*
G02X392656Y857357I-1301J1D01*
G01X392626Y857270D01*
X393428Y855880D01*
X393518Y855863D01*
G02X394579Y854584I-240J-1279D01*
G02X391977I-1301J0D01*
G02X392051Y855016I1301J-1D01*
G01X392081Y855103D01*
G37*
G36*
G01X350579Y859085D02*
X351381Y860474D01*
X351351Y860561D01*
G02X351277Y860993I1227J433D01*
G02X353879I1301J0D01*
G02X352818Y859714I-1301J0D01*
G01X352728Y859697D01*
X351926Y858308D01*
X351956Y858221D01*
G02X352030Y857789I-1227J-433D01*
G02X349428I-1301J0D01*
G02X350489Y859068I1301J0D01*
G01X350579Y859085D01*
G37*
G36*
G01X357979D02*
X358781Y860474D01*
X358751Y860561D01*
G02X358677Y860993I1227J433D01*
G02X361279I1301J0D01*
G02X360218Y859714I-1301J0D01*
G01X360128Y859697D01*
X359326Y858308D01*
X359356Y858221D01*
G02X359430Y857789I-1227J-433D01*
G02X356828I-1301J0D01*
G02X357889Y859068I1301J0D01*
G01X357979Y859085D01*
G37*
G36*
G01X365379D02*
X366181Y860474D01*
X366151Y860561D01*
G02X366077Y860993I1227J433D01*
G02X368679I1301J0D01*
G02X367618Y859714I-1301J0D01*
G01X367528Y859697D01*
X366726Y858308D01*
X366756Y858221D01*
G02X366830Y857789I-1227J-433D01*
G02X364228I-1301J0D01*
G02X365289Y859068I1301J0D01*
G01X365379Y859085D01*
G37*
G36*
G01X372779D02*
X373581Y860474D01*
X373551Y860561D01*
G02X373477Y860993I1227J433D01*
G02X376079I1301J0D01*
G02X375018Y859714I-1301J0D01*
G01X374928Y859697D01*
X374126Y858308D01*
X374156Y858221D01*
G02X374230Y857789I-1227J-433D01*
G02X371628I-1301J0D01*
G02X372689Y859068I1301J0D01*
G01X372779Y859085D01*
G37*
G36*
G01X380179D02*
X380981Y860474D01*
X380951Y860561D01*
G02X380877Y860993I1227J433D01*
G02X383479I1301J0D01*
G02X382418Y859714I-1301J0D01*
G01X382328Y859697D01*
X381526Y858308D01*
X381556Y858221D01*
G02X381630Y857789I-1227J-433D01*
G02X379028I-1301J0D01*
G02X380089Y859068I1301J0D01*
G01X380179Y859085D01*
G37*
G36*
G01X387579D02*
X388381Y860474D01*
X388351Y860561D01*
G02X388277Y860993I1227J433D01*
G02X390879I1301J0D01*
G02X389818Y859714I-1301J0D01*
G01X389728Y859697D01*
X388926Y858308D01*
X388956Y858221D01*
G02X389030Y857789I-1227J-433D01*
G02X386428I-1301J0D01*
G02X387489Y859068I1301J0D01*
G01X387579Y859085D01*
G37*
G36*
G01X392081Y867920D02*
X391279Y869310D01*
X391189Y869327D01*
G02X390128Y870606I240J1279D01*
G02X392730I1301J0D01*
G02X392656Y870174I-1301J1D01*
G01X392626Y870087D01*
X393428Y868697D01*
X393518Y868680D01*
G02X394579Y867401I-240J-1279D01*
G02X391977I-1301J0D01*
G02X392051Y867833I1301J-1D01*
G01X392081Y867920D01*
G37*
G36*
G01X394979Y871902D02*
X395781Y873291D01*
X395751Y873378D01*
G02X395677Y873810I1227J433D01*
G02X398279I1301J0D01*
G02X397218Y872531I-1301J0D01*
G01X397128Y872514D01*
X396326Y871125D01*
X396356Y871038D01*
G02X396430Y870606I-1227J-433D01*
G02X393828I-1301J0D01*
G02X394889Y871885I1301J0D01*
G01X394979Y871902D01*
G37*
G36*
G01X402379D02*
X403181Y873291D01*
X403151Y873378D01*
G02X403077Y873810I1227J433D01*
G02X405679I1301J0D01*
G02X404618Y872531I-1301J0D01*
G01X404528Y872514D01*
X403726Y871125D01*
X403756Y871038D01*
G02X403830Y870606I-1227J-433D01*
G02X401228I-1301J0D01*
G02X402289Y871885I1301J0D01*
G01X402379Y871902D01*
G37*
G36*
G01X406881Y880737D02*
X406079Y882127D01*
X405989Y882144D01*
G02X404928Y883423I240J1279D01*
G02X407530I1301J0D01*
G02X407456Y882991I-1301J1D01*
G01X407426Y882904D01*
X408227Y881515D01*
X408318Y881498D01*
G02X409379Y880219I-240J-1279D01*
G02X406777I-1301J0D01*
G02X406851Y880651I1301J-1D01*
G01X406881Y880737D01*
G37*
G36*
G01X414281D02*
X413479Y882127D01*
X413389Y882144D01*
G02X412328Y883423I240J1279D01*
G02X414930I1301J0D01*
G02X414856Y882991I-1301J1D01*
G01X414826Y882904D01*
X415627Y881515D01*
X415718Y881498D01*
G02X416779Y880219I-240J-1279D01*
G02X414177I-1301J0D01*
G02X414251Y880651I1301J-1D01*
G01X414281Y880737D01*
G37*
G36*
G01X421681D02*
X420879Y882127D01*
X420789Y882144D01*
G02X419728Y883423I240J1279D01*
G02X422330I1301J0D01*
G02X422256Y882991I-1301J1D01*
G01X422226Y882904D01*
X423027Y881515D01*
X423118Y881498D01*
G02X424179Y880219I-240J-1279D01*
G02X421577I-1301J0D01*
G02X421651Y880651I1301J-1D01*
G01X421681Y880737D01*
G37*
G36*
G01X429081D02*
X428279Y882127D01*
X428189Y882144D01*
G02X427128Y883423I240J1279D01*
G02X429730I1301J0D01*
G02X429656Y882991I-1301J1D01*
G01X429626Y882904D01*
X430427Y881515D01*
X430518Y881498D01*
G02X431579Y880219I-240J-1279D01*
G02X428977I-1301J0D01*
G02X429051Y880651I1301J-1D01*
G01X429081Y880737D01*
G37*
G36*
G01X402379Y884719D02*
X403181Y886108D01*
X403151Y886195D01*
G02X403077Y886627I1227J433D01*
G02X405679I1301J0D01*
G02X404618Y885348I-1301J0D01*
G01X404528Y885331D01*
X403726Y883942D01*
X403756Y883855D01*
G02X403830Y883423I-1227J-433D01*
G02X401228I-1301J0D01*
G02X402289Y884702I1301J0D01*
G01X402379Y884719D01*
G37*
G36*
G01X409779D02*
X410581Y886108D01*
X410551Y886195D01*
G02X410477Y886627I1227J433D01*
G02X413079I1301J0D01*
G02X412018Y885348I-1301J0D01*
G01X411928Y885331D01*
X411126Y883942D01*
X411156Y883855D01*
G02X411230Y883423I-1227J-433D01*
G02X408628I-1301J0D01*
G02X409689Y884702I1301J0D01*
G01X409779Y884719D01*
G37*
G36*
G01X417179D02*
X417981Y886108D01*
X417951Y886195D01*
G02X417877Y886627I1227J433D01*
G02X420479I1301J0D01*
G02X419418Y885348I-1301J0D01*
G01X419328Y885331D01*
X418526Y883942D01*
X418556Y883855D01*
G02X418630Y883423I-1227J-433D01*
G02X416028I-1301J0D01*
G02X417089Y884702I1301J0D01*
G01X417179Y884719D01*
G37*
G36*
G01X424579D02*
X425381Y886108D01*
X425351Y886195D01*
G02X425277Y886627I1227J433D01*
G02X427879I1301J0D01*
G02X426818Y885348I-1301J0D01*
G01X426728Y885331D01*
X425926Y883942D01*
X425956Y883855D01*
G02X426030Y883423I-1227J-433D01*
G02X423428I-1301J0D01*
G02X424489Y884702I1301J0D01*
G01X424579Y884719D01*
G37*
G36*
G01X431979D02*
X432781Y886108D01*
X432751Y886195D01*
G02X432677Y886627I1227J433D01*
G02X435279I1301J0D01*
G02X434218Y885348I-1301J0D01*
G01X434128Y885331D01*
X433326Y883942D01*
X433356Y883855D01*
G02X433430Y883423I-1227J-433D01*
G02X430828I-1301J0D01*
G02X431889Y884702I1301J0D01*
G01X431979Y884719D01*
G37*
G36*
G01X274965Y725846D02*
G02X274247Y725663I-718J1319D01*
G02Y728667I0J1502D01*
G02X275739Y727334I0J-1501D01*
G03X276328Y727028I398J45D01*
G02X277046Y727211I718J-1319D01*
G02X277536Y727129I0J-1502D01*
G03X278054Y727405I131J378D01*
G02X279507Y728527I1453J-380D01*
G02Y725523I0J-1502D01*
G02X279017Y725605I0J1502D01*
G03X278499Y725329I-131J-378D01*
G02X277046Y724207I-1453J380D01*
G02X275554Y725540I0J1501D01*
G03X274965Y725846I-398J-45D01*
G37*
G36*
G01X273777Y737652D02*
G02X273708Y738102I1433J450D01*
G02X275210Y739604I1502J0D01*
G02X276524Y738830I0J-1502D01*
G03X277220Y738824I350J194D01*
G02X278520Y739574I1300J-752D01*
G02X279577Y739139I0J-1502D01*
G03X280108Y739111I281J284D01*
G02X281046Y739440I938J-1173D01*
G02Y736436I0J-1502D01*
G02X279989Y736871I0J1502D01*
G03X279458Y736899I-281J-284D01*
G02X278737Y736586I-938J1173D01*
G03X278427Y736033I58J-396D01*
G02X278548Y735442I-1381J-591D01*
G02X275544I-1502J0D01*
G02X275669Y736042I1503J0D01*
G03X275283Y736602I-366J160D01*
G02X275210Y736600I-78J1500D01*
G02X274934Y736626I2J1502D01*
G03X274479Y736112I-74J-393D01*
G02X274548Y735662I-1433J-450D01*
G02X273046Y737164I-1502J0D01*
G02X273322Y737138I-2J-1502D01*
G03X273777Y737652I74J393D01*
G37*
G36*
G01X152850Y1350479D02*
G02X154904I1027J-1096D01*
G03X155450I273J292D01*
G02X156477Y1350885I1027J-1096D01*
G02X157979Y1349383I0J-1502D01*
G02X157609Y1348396I-1501J0D01*
G03Y1347870I302J-263D01*
G02Y1345896I-1131J-987D01*
G03Y1345370I302J-263D01*
G02Y1343396I-1131J-987D01*
G03Y1342870I302J-263D01*
G02X157979Y1341883I-1131J-987D01*
G02X157535Y1340817I-1502J0D01*
G03Y1340249I282J-284D01*
G02X157979Y1339183I-1058J-1066D01*
G02X157474Y1338059I-1503J0D01*
G03X157461Y1337473I265J-299D01*
G02X157919Y1336398I-1044J-1080D01*
G02X157920Y1336343I-1502J-55D01*
G02X157472Y1335272I-1504J0D01*
G03X157549Y1334880I379J-129D01*
G02X157919Y1333898I-1131J-987D01*
G02X157920Y1333843I-1502J-55D01*
G02X156417Y1332340I-1503J0D01*
G02X155267Y1332876I0J1502D01*
G03X154844Y1332797I-150J-371D01*
G02X152790I-1027J1096D01*
G03X152244I-273J-292D01*
G02X151217Y1332391I-1027J1096D01*
G02X149715Y1333893I0J1502D01*
G02X150085Y1334880I1501J0D01*
G03Y1335406I-302J263D01*
G02X149715Y1336393I1131J987D01*
G02X150220Y1337517I1503J0D01*
G03X150233Y1338103I-265J299D01*
G02X149775Y1339183I1044J1080D01*
G02X150219Y1340249I1502J0D01*
G03Y1340817I-282J284D01*
G02X149775Y1341883I1058J1066D01*
G02X150145Y1342870I1501J0D01*
G03Y1343396I-302J263D01*
G02Y1345370I1131J987D01*
G03Y1345896I-302J263D01*
G02Y1347870I1131J987D01*
G03Y1348396I-302J263D01*
G02X149775Y1349383I1131J987D01*
G02X151277Y1350885I1502J0D01*
G02X152304Y1350479I0J-1502D01*
G03X152850I273J292D01*
G37*
G36*
G01X183075Y1434426D02*
G02X184260Y1433847I0J-1502D01*
G03X184890I315J246D01*
G02X186075Y1434426I1185J-923D01*
G02X187577Y1432924I0J-1502D01*
G02X187207Y1431937I-1501J0D01*
G03Y1431411I302J-263D01*
G02Y1429437I-1131J-987D01*
G03Y1428911I302J-263D01*
G02Y1426937I-1131J-987D01*
G03Y1426411I302J-263D01*
G02X187577Y1425424I-1131J-987D01*
G02X187111Y1424336I-1503J0D01*
G03X187130Y1423740I276J-290D01*
G02X187667Y1422589I-965J-1151D01*
G02X187168Y1421471I-1502J0D01*
G03X187161Y1420881I267J-298D01*
G02X187637Y1419784I-1026J-1097D01*
G02X186135Y1418282I-1502J0D01*
G02X184950Y1418861I0J1502D01*
G03X184320I-315J-246D01*
G02X183135Y1418282I-1185J923D01*
G02X181908Y1418917I0J1503D01*
G03X181356Y1419017I-327J-230D01*
G02X180510Y1418756I-846J1241D01*
G02X179325Y1419335I0J1502D01*
G03X178695I-315J-246D01*
G02X177510Y1418756I-1185J923D01*
G02X176008Y1420258I0J1502D01*
G02X176597Y1421450I1501J0D01*
G03Y1422086I-243J318D01*
G02X176008Y1423278I912J1192D01*
G02X177510Y1424780I1502J0D01*
G02X178695Y1424201I0J-1502D01*
G03X179325I315J246D01*
G02X180510Y1424780I1185J-923D01*
G02X181064Y1424674I0J-1501D01*
G03X181603Y1425126I147J372D01*
G02X181573Y1425424I1472J299D01*
G02X181943Y1426411I1501J0D01*
G03Y1426937I-302J263D01*
G02Y1428911I1131J987D01*
G03Y1429437I-302J263D01*
G02Y1431411I1131J987D01*
G03Y1431937I-302J263D01*
G02X181573Y1432924I1131J987D01*
G02X183075Y1434426I1502J0D01*
G37*
G36*
G01X172920Y1403894D02*
G03Y1404504I-259J305D01*
G02X172390Y1405649I972J1145D01*
G02X173892Y1407151I1502J0D01*
G02X175394Y1405649I0J-1502D01*
G02X175388Y1405518I-1502J3D01*
G03X175907Y1405102I398J-35D01*
G02X176357Y1405171I450J-1433D01*
G01X176358D01*
X176359D01*
G02X176564Y1405157I0J-1502D01*
G03X177005Y1405451I54J396D01*
G02X178458Y1406571I1453J-383D01*
G02X179960Y1405069I0J-1502D01*
G02X179430Y1403924I-1502J0D01*
G03Y1403314I259J-305D01*
G02Y1401024I-972J-1145D01*
G03Y1400414I259J-305D01*
G02X179960Y1399269I-972J-1145D01*
G02X178458Y1397767I-1502J0D01*
G02X177002Y1398899I0J1502D01*
G03X176540Y1399194I-388J-98D01*
G02X176258Y1399167I-284J1475D01*
G02X175240Y1399565I0J1501D01*
G03X174601Y1399428I-271J-294D01*
G02X173252Y1398538I-1349J577D01*
G02X172676Y1398656I0J1467D01*
G03X172177Y1398495I-157J-368D01*
G02X169667I-1255J760D01*
G03X169168Y1398656I-342J-207D01*
G02X168592Y1398538I-576J1349D01*
G02X168016Y1398656I0J1467D01*
G03X167517Y1398495I-157J-368D01*
G02X166262Y1397788I-1255J760D01*
G02Y1400722I0J1467D01*
G02X166838Y1400604I0J-1467D01*
G03X167337Y1400765I157J368D01*
G02X169847I1255J-760D01*
G03X170346Y1400604I342J207D01*
G02X170922Y1400722I576J-1349D01*
G02X171498Y1400604I0J-1467D01*
G03X171997Y1400765I157J368D01*
G02X172542Y1401289I1255J-760D01*
G03X172673Y1401872I-194J350D01*
G02X172390Y1402749I1219J877D01*
G02X172920Y1403894I1502J0D01*
G37*
G36*
G01X210550Y1350479D02*
G02X212604I1027J-1096D01*
G03X213150I273J292D01*
G02X214177Y1350885I1027J-1096D01*
G02X215679Y1349383I0J-1502D01*
G02X215309Y1348396I-1501J0D01*
G03Y1347870I302J-263D01*
G02Y1345896I-1131J-987D01*
G03Y1345370I302J-263D01*
G02Y1343396I-1131J-987D01*
G03Y1342870I302J-263D01*
G02X215679Y1341883I-1131J-987D01*
G02X215278Y1340861I-1503J0D01*
G03X215284Y1340310I293J-272D01*
G02X215709Y1339263I-1077J-1047D01*
G02X215176Y1338116I-1501J0D01*
G03X215170Y1337510I258J-306D01*
G02X215679Y1336383I-993J-1127D01*
G02X215273Y1335356I-1502J0D01*
G03Y1334810I292J-273D01*
G02X215679Y1333783I-1096J-1027D01*
G02X214177Y1332281I-1502J0D01*
G02X213150Y1332687I0J1502D01*
G03X212604I-273J-292D01*
G02X210550I-1027J1096D01*
G03X210004I-273J-292D01*
G02X209832Y1332548I-1028J1096D01*
G03X209879Y1331863I228J-328D01*
G02X211849Y1328652I-1632J-3211D01*
G02X204645I-3602J0D01*
G02X207575Y1332191I3602J0D01*
G03X207811Y1332836I-74J393D01*
G02X207475Y1333783I1167J947D01*
G02X207881Y1334810I1502J0D01*
G03Y1335356I-292J273D01*
G02X207475Y1336383I1096J1027D01*
G02X208008Y1337530I1501J0D01*
G03X208014Y1338136I-258J306D01*
G02X207505Y1339263I993J1127D01*
G02X207906Y1340285I1503J0D01*
G03X207900Y1340836I-293J272D01*
G02X207475Y1341883I1077J1047D01*
G02X207845Y1342870I1501J0D01*
G03Y1343396I-302J263D01*
G02Y1345370I1131J987D01*
G03Y1345896I-302J263D01*
G02Y1347870I1131J987D01*
G03Y1348396I-302J263D01*
G02X207475Y1349383I1131J987D01*
G02X208977Y1350885I1502J0D01*
G02X210004Y1350479I0J-1502D01*
G03X210550I273J292D01*
G37*
G36*
G01X217469Y1456227D02*
G02X218812Y1455399I0J-1503D01*
G03X219526I357J179D01*
G02X220869Y1456227I1343J-675D01*
G02X222371Y1454725I0J-1502D01*
G02X221135Y1453247I-1502J0D01*
G01X220970Y1453217D01*
Y1449502D01*
G02X220677Y1448794I-1002J0D01*
G01X216228Y1444345D01*
Y1420345D01*
G02X215935Y1419637I-1002J0D01*
G01X212268Y1415970D01*
G02X211560Y1415676I-709J708D01*
G01X192183D01*
X191710Y1415203D01*
Y1411798D01*
X192782Y1410725D01*
X192924Y1410855D01*
G02X193941Y1411252I1017J-1104D01*
G02X195443Y1409750I0J-1502D01*
G02X194991Y1408676I-1502J0D01*
G03Y1408103I279J-286D01*
G02X195443Y1407029I-1050J-1074D01*
G02X193941Y1405527I-1502J0D01*
G02X192548Y1406468I0J1502D01*
G01X192497Y1406594D01*
X192317D01*
G02X191609Y1406887I0J1002D01*
G01X188459Y1410037D01*
G02X188166Y1410745I709J708D01*
G01Y1416335D01*
G02X188459Y1417043I1002J0D01*
G01X190343Y1418927D01*
G02X191051Y1419220I708J-709D01*
G01X210506D01*
X212726Y1421440D01*
Y1445421D01*
G02X213019Y1446129I1002J0D01*
G01X217426Y1450537D01*
Y1453213D01*
X217255Y1453238D01*
G02X215967Y1454725I214J1487D01*
G02X217469Y1456227I1502J0D01*
G37*
G36*
G01X158388Y1451963D02*
G02X159096Y1452256I708J-709D01*
G01X172221D01*
X172252Y1452419D01*
G02X173727Y1453636I1475J-285D01*
G02X175229Y1452134I0J-1502D01*
G02X174401Y1450791I-1503J0D01*
G03Y1450077I179J-357D01*
G02X175229Y1448734I-675J-1343D01*
G02X173727Y1447232I-1502J0D01*
G02X172240Y1448522I0J1502D01*
G01X172215Y1448694D01*
X160145D01*
X151270Y1439818D01*
Y1412310D01*
X153763Y1409816D01*
X154411D01*
X154461Y1409943D01*
G02X155858Y1410892I1397J-554D01*
G02X157360Y1409390I0J-1502D01*
G02X156908Y1408316I-1502J0D01*
G03Y1407743I279J-286D01*
G02X157360Y1406669I-1050J-1074D01*
G02X155858Y1405167I-1502J0D01*
G02X154444Y1406161I0J1503D01*
G01X154397Y1406294D01*
X152257D01*
G02X151549Y1406587I0J1002D01*
G01X148009Y1410127D01*
G02X147716Y1410835I709J708D01*
G01Y1440876D01*
G02X148009Y1441584I1002J0D01*
G01X158388Y1451963D01*
G37*
G36*
G01X155030Y1439256D02*
G02X156017Y1438886I0J-1501D01*
G03X156543I263J302D01*
G02X157530Y1439256I987J-1131D01*
G02X158715Y1438677I0J-1502D01*
G03X159345I315J246D01*
G02X160530Y1439256I1185J-923D01*
G02X162032Y1437754I0J-1502D01*
G02X161615Y1436716I-1502J1D01*
G03Y1436162I289J-277D01*
G02X162032Y1435124I-1085J-1039D01*
G02X161453Y1433939I-1502J0D01*
G03Y1433309I246J-315D01*
G02Y1430939I-923J-1185D01*
G03Y1430309I246J-315D01*
G02X162032Y1429124I-923J-1185D01*
G02X161662Y1428137I-1501J0D01*
G03Y1427611I302J-263D01*
G02Y1425637I-1131J-987D01*
G03Y1425111I302J-263D01*
G02X162032Y1424124I-1131J-987D01*
G02X161584Y1423054I-1502J0D01*
G03X161575Y1422492I280J-286D01*
G02X161992Y1421454I-1085J-1039D01*
G02X160490Y1419952I-1502J0D01*
G02X159305Y1420531I0J1502D01*
G03X158675I-315J-246D01*
G02X157490Y1419952I-1185J923D01*
G02X156503Y1420322I0J1501D01*
G03X155977I-263J-302D01*
G02X154990Y1419952I-987J1131D01*
G02X153488Y1421454I0J1502D01*
G02X153936Y1422524I1502J0D01*
G03X153945Y1423086I-280J286D01*
G02X153528Y1424124I1085J1039D01*
G02X153898Y1425111I1501J0D01*
G03Y1425637I-302J263D01*
G02Y1427611I1131J987D01*
G03Y1428137I-302J263D01*
G02X153528Y1429124I1131J987D01*
G02X154107Y1430309I1502J0D01*
G03Y1430939I-246J315D01*
G02Y1433309I923J1185D01*
G03Y1433939I-246J315D01*
G02X153528Y1435124I923J1185D01*
G02X153945Y1436162I1502J-1D01*
G03Y1436716I-289J277D01*
G02X153528Y1437754I1085J1039D01*
G02X155030Y1439256I1502J0D01*
G37*
G36*
G01X199662Y1407938D02*
G03X199726Y1408552I-221J333D01*
G02X199637Y1408650I1066J1058D01*
G01X199309Y1408622D01*
G02X198001Y1407859I-1308J740D01*
G02Y1410863I0J1502D01*
G02X199017Y1410467I0J-1501D01*
G03X199605Y1410519I270J295D01*
G02X200797Y1411107I1192J-914D01*
G02X202299Y1409605I0J-1502D01*
G02X201627Y1408353I-1502J0D01*
G03X201563Y1407739I221J-333D01*
G02X201994Y1406686I-1071J-1053D01*
G02X198990I-1502J0D01*
G02X199662Y1407938I1502J0D01*
G37*
G36*
G01X160755Y1406594D02*
G02X162160Y1408093I1502J0D01*
G03X162527Y1408570I-25J399D01*
G02X162498Y1408862I1473J294D01*
G02X164000Y1410364I1502J0D01*
G02X165502Y1408862I0J-1502D01*
G02X164097Y1407363I-1502J0D01*
G03X163730Y1406886I25J-399D01*
G02X163759Y1406594I-1473J-294D01*
G02X162257Y1405092I-1502J0D01*
G02X160755Y1406594I0J1502D01*
G37*
G36*
G01X210533Y1402899D02*
G02X211063Y1404044I1502J0D01*
G03Y1404654I-259J305D01*
G02X210533Y1405799I972J1145D01*
G02X212035Y1407301I1502J0D01*
G02X213524Y1405997I0J-1502D01*
G03X213979Y1405655I396J53D01*
G02X214201Y1405671I219J-1486D01*
G01X214202D01*
G02X214730Y1405575I0J-1502D01*
G03X215225Y1405763I141J374D01*
G02X216554Y1406566I1329J-698D01*
G02X218056Y1405064I0J-1502D01*
G02X217526Y1403919I-1502J0D01*
G03Y1403309I259J-305D01*
G02Y1401019I-972J-1145D01*
G03Y1400409I259J-305D01*
G02X218056Y1399264I-972J-1145D01*
G02X216554Y1397762I-1502J0D01*
G02X215052Y1399263I0J1502D01*
G01Y1399264D01*
G02X215054Y1399331I1502J-11D01*
G03X214538Y1399732I-400J18D01*
G02X214101Y1399667I-437J1436D01*
G02X213383Y1399850I0J1502D01*
G03X212807Y1399607I-191J-352D01*
G02X211395Y1398538I-1412J398D01*
G02X210819Y1398656I0J1467D01*
G03X210320Y1398495I-157J-368D01*
G02X207810I-1255J760D01*
G03X207311Y1398656I-342J-207D01*
G02X206735Y1398538I-576J1349D01*
G02X206159Y1398656I0J1467D01*
G03X205660Y1398495I-157J-368D01*
G02X204405Y1397788I-1255J760D01*
G02Y1400722I0J1467D01*
G02X204981Y1400604I0J-1467D01*
G03X205480Y1400765I157J368D01*
G02X207990I1255J-760D01*
G03X208489Y1400604I342J207D01*
G02X209065Y1400722I576J-1349D01*
G02X209641Y1400604I0J-1467D01*
G03X210140Y1400765I157J368D01*
G02X210750Y1401322I1254J-761D01*
G03X210881Y1401938I-176J359D01*
G02X210533Y1402899I1153J961D01*
G37*
G36*
G01X148066Y1395146D02*
G02X148453Y1396152I1502J0D01*
G03Y1396688I-296J268D01*
G02X148066Y1397694I1115J1006D01*
G01Y1397695D01*
G02X151070I1502J0D01*
G01Y1397694D01*
G02X150683Y1396688I-1502J0D01*
G03Y1396152I296J-268D01*
G02X151070Y1395146I-1115J-1006D01*
G01Y1395145D01*
G02X148066I-1502J0D01*
G01Y1395146D01*
G37*
G36*
G01X186209Y1395170D02*
G02X186579Y1396157I1501J0D01*
G03Y1396683I-302J263D01*
G02X186209Y1397670I1131J987D01*
G02X189213I1502J0D01*
G02X188843Y1396683I-1501J0D01*
G03Y1396157I302J-263D01*
G02X189213Y1395170I-1131J-987D01*
G02X186209I-1502J0D01*
G37*
G36*
G01X189377Y1350885D02*
G02X190404Y1350479I0J-1502D01*
G03X190950I273J292D01*
G02X193004I1027J-1096D01*
G03X193550I273J292D01*
G02X194577Y1350885I1027J-1096D01*
G02X196079Y1349383I0J-1502D01*
G02X195709Y1348396I-1501J0D01*
G03Y1347870I302J-263D01*
G02Y1345896I-1131J-987D01*
G03Y1345370I302J-263D01*
G02Y1343396I-1131J-987D01*
G03Y1342870I302J-263D01*
G02X196079Y1341883I-1131J-987D01*
G02X195654Y1340836I-1502J0D01*
G03X195648Y1340285I287J-279D01*
G02X196049Y1339263I-1102J-1022D01*
G02X195540Y1338136I-1502J0D01*
G03X195546Y1337530I264J-300D01*
G02X196079Y1336383I-968J-1147D01*
G02X195673Y1335356I-1502J0D01*
G03Y1334810I292J-273D01*
G02X196079Y1333783I-1096J-1027D01*
G02X194577Y1332281I-1502J0D01*
G02X193550Y1332687I0J1502D01*
G03X193004I-273J-292D01*
G02X190950I-1027J1096D01*
G03X190404I-273J-292D01*
G02X189377Y1332281I-1027J1096D01*
G02X187875Y1333783I0J1502D01*
G02X188281Y1334810I1502J0D01*
G03Y1335356I-292J273D01*
G02X187875Y1336383I1096J1027D01*
G02X188384Y1337510I1502J0D01*
G03X188378Y1338116I-264J300D01*
G02X187845Y1339263I968J1147D01*
G02X188270Y1340310I1502J0D01*
G03X188276Y1340861I-287J279D01*
G02X187875Y1341883I1102J1022D01*
G02X188245Y1342870I1501J0D01*
G03Y1343396I-302J263D01*
G02Y1345370I1131J987D01*
G03Y1345896I-302J263D01*
G02Y1347870I1131J987D01*
G03Y1348396I-302J263D01*
G02X187875Y1349383I1131J987D01*
G02X189377Y1350885I1502J0D01*
G37*
G36*
G01X170877D02*
G02X171904Y1350479I0J-1502D01*
G03X172450I273J292D01*
G02X174504I1027J-1096D01*
G03X175050I273J292D01*
G02X176077Y1350885I1027J-1096D01*
G02X177579Y1349383I0J-1502D01*
G02X177209Y1348396I-1501J0D01*
G03Y1347870I302J-263D01*
G02Y1345896I-1131J-987D01*
G03Y1345370I302J-263D01*
G02Y1343396I-1131J-987D01*
G03Y1342870I302J-263D01*
G02X177579Y1341883I-1131J-987D01*
G02X177166Y1340849I-1501J0D01*
G03X177173Y1340292I290J-275D01*
G02X177609Y1339234I-1066J-1058D01*
G01Y1339233D01*
G02X177090Y1338097I-1503J0D01*
G03X177084Y1337498I262J-302D01*
G02X177579Y1336383I-1008J-1115D01*
G02X177173Y1335356I-1502J0D01*
G03Y1334810I292J-273D01*
G02X177579Y1333783I-1096J-1027D01*
G02X176077Y1332281I-1502J0D01*
G02X175050Y1332687I0J1502D01*
G03X174504I-273J-292D01*
G02X172450I-1027J1096D01*
G03X171904I-273J-292D01*
G02X170877Y1332281I-1027J1096D01*
G02X169375Y1333783I0J1502D01*
G02X169781Y1334810I1502J0D01*
G03Y1335356I-292J273D01*
G02X169375Y1336383I1096J1027D01*
G02X169894Y1337519I1503J0D01*
G03X169900Y1338118I-262J302D01*
G02X169405Y1339233I1008J1115D01*
G02X169818Y1340267I1501J0D01*
G03X169811Y1340824I-290J275D01*
G02X169375Y1341882I1066J1058D01*
G01Y1341883D01*
G02X169745Y1342870I1501J0D01*
G03Y1343396I-302J263D01*
G02Y1345370I1131J987D01*
G03Y1345896I-302J263D01*
G02Y1347870I1131J987D01*
G03Y1348396I-302J263D01*
G02X169375Y1349383I1131J987D01*
G02X170877Y1350885I1502J0D01*
G37*
G36*
G01X313685Y70048D02*
G03Y70658I-259J305D01*
G02X313155Y71803I972J1145D01*
G02X316159I1502J0D01*
G02X315629Y70658I-1502J0D01*
G03Y70048I259J-305D01*
G02X316159Y68903I-972J-1145D01*
G02X313155I-1502J0D01*
G02X313685Y70048I1502J0D01*
G37*
G36*
G01X321696Y76450D02*
G03X321131Y76674I-378J-130D01*
G02X320430Y76500I-702J1328D01*
G02Y79504I0J1502D01*
G02X321851Y78490I0J-1503D01*
G03X322416Y78266I378J130D01*
G02X323117Y78440I702J-1328D01*
G02Y75436I0J-1502D01*
G02X321696Y76450I0J1503D01*
G37*
G36*
G01X279761Y108330D02*
G03Y108876I-292J273D01*
G02X279355Y109903I1096J1027D01*
G02X282359I1502J0D01*
G02X281953Y108876I-1502J0D01*
G03Y108330I292J-273D01*
G02X282359Y107303I-1096J-1027D01*
G02X279355I-1502J0D01*
G02X279761Y108330I1502J0D01*
G37*
G36*
G01X260889Y109526D02*
G03Y110080I-288J277D01*
G02X260497Y111053I1010J972D01*
G02X263301I1402J0D01*
G02X262909Y110080I-1402J-1D01*
G03Y109526I288J-277D01*
G02X263301Y108553I-1010J-972D01*
G02X260497I-1402J0D01*
G02X260889Y109526I1402J1D01*
G37*
G36*
G01X264432D02*
G03Y110080I-288J277D01*
G02X264040Y111053I1010J972D01*
G02X266844I1402J0D01*
G02X266452Y110080I-1402J-1D01*
G03Y109526I288J-277D01*
G02X266844Y108553I-1010J-972D01*
G02X264040I-1402J0D01*
G02X264432Y109526I1402J1D01*
G37*
G36*
G01X267975D02*
G03Y110080I-288J277D01*
G02X267583Y111053I1010J972D01*
G02X270387I1402J0D01*
G02X269995Y110080I-1402J-1D01*
G03Y109526I288J-277D01*
G02X270387Y108553I-1010J-972D01*
G02X267583I-1402J0D01*
G02X267975Y109526I1402J1D01*
G37*
G36*
G01X271519D02*
G03Y110080I-288J277D01*
G02X271127Y111053I1010J972D01*
G02X273931I1402J0D01*
G02X273539Y110080I-1402J-1D01*
G03Y109526I288J-277D01*
G02X273931Y108553I-1010J-972D01*
G02X271127I-1402J0D01*
G02X271519Y109526I1402J1D01*
G37*
G36*
G01X300166Y111109D02*
G03Y111697I-270J294D01*
G02X299681Y112803I1017J1105D01*
G02X302685I1502J0D01*
G02X302200Y111697I-1502J-1D01*
G03Y111109I270J-294D01*
G02X302685Y110003I-1017J-1105D01*
G02X302155Y108858I-1502J0D01*
G03Y108248I259J-305D01*
G02X302685Y107103I-972J-1145D01*
G02X299681I-1502J0D01*
G02X300211Y108248I1502J0D01*
G03Y108858I-259J305D01*
G02X299681Y110003I972J1145D01*
G02X300166Y111109I1502J1D01*
G37*
G36*
G01X310040D02*
G03Y111697I-270J294D01*
G02X309555Y112803I1017J1105D01*
G02X312559I1502J0D01*
G02X312074Y111697I-1502J-1D01*
G03Y111109I270J-294D01*
G02X312559Y110003I-1017J-1105D01*
G02X312029Y108858I-1502J0D01*
G03Y108248I259J-305D01*
G02X312559Y107103I-972J-1145D01*
G02X309555I-1502J0D01*
G02X310085Y108248I1502J0D01*
G03Y108858I-259J305D01*
G02X309555Y110003I972J1145D01*
G02X310040Y111109I1502J1D01*
G37*
G36*
G01X284672Y114680D02*
G03X284042I-315J-246D01*
G02X282857Y114101I-1185J923D01*
G02Y117105I0J1502D01*
G02X284042Y116526I0J-1502D01*
G03X284672I315J246D01*
G02X285857Y117105I1185J-923D01*
G02Y114101I0J-1502D01*
G02X284672Y114680I0J1502D01*
G37*
G36*
G01X322136Y83010D02*
G02X321373Y84318I740J1308D01*
G02X324377I1502J0D01*
G02X323805Y83138I-1503J0D01*
G03X323856Y82476I247J-314D01*
G02X324619Y81168I-740J-1308D01*
G02X321615I-1502J0D01*
G02X322187Y82348I1503J0D01*
G03X322136Y83010I-247J314D01*
G37*
G36*
G01X314456Y88480D02*
G02X313357Y88001I-1100J1023D01*
G02Y91005I0J1502D01*
G02X314632Y90297I0J-1502D01*
G03X315265Y90235I340J211D01*
G02X316364Y90714I1100J-1023D01*
G02Y87710I0J-1502D01*
G02X315089Y88418I0J1502D01*
G03X314456Y88480I-340J-211D01*
G37*
G36*
G01X286621Y104191D02*
G02X285357Y103501I-1264J813D01*
G02Y106505I0J1502D01*
G02X286621Y105815I0J-1503D01*
G03X287293I336J216D01*
G02X288557Y106505I1264J-813D01*
G02Y103501I0J-1502D01*
G02X287293Y104191I0J1503D01*
G03X286621I-336J-216D01*
G37*
G36*
G01X247955Y70378D02*
G02X247720Y70360I-232J1484D01*
G02X249222Y71862I0J1502D01*
G02X249195Y71577I-1502J-1D01*
G03X249650Y71107I393J-75D01*
G02X249885Y71125I232J-1484D01*
G02X248383Y69623I0J-1502D01*
G02X248410Y69908I1502J1D01*
G03X247955Y70378I-393J75D01*
G37*
G36*
G01X358954Y688777D02*
G02X358137Y690114I685J1337D01*
G02X361141I1502J0D01*
G02X360347Y688790I-1501J0D01*
G03X360354Y688081I189J-353D01*
G02X361171Y686744I-685J-1337D01*
G02X358167I-1502J0D01*
G02X358961Y688068I1501J0D01*
G03X358954Y688777I-189J353D01*
G37*
G36*
G01X362427Y696005D02*
G02X361599Y697348I675J1343D01*
G02X364603I1502J0D01*
G02X363775Y696005I-1503J0D01*
G03Y695291I179J-357D01*
G02X364603Y693948I-675J-1343D01*
G02X361599I-1502J0D01*
G02X362427Y695291I1503J0D01*
G03Y696005I-179J357D01*
G37*
G36*
G01X348056Y733755D02*
G02X347228Y735098I675J1343D01*
G02X350232I1502J0D01*
G02X349404Y733755I-1503J0D01*
G03Y733041I179J-357D01*
G02X350232Y731698I-675J-1343D01*
G02X349334Y730323I-1502J0D01*
G03X349188Y729700I161J-366D01*
G02X349539Y728735I-1151J-965D01*
G02X346535I-1502J0D01*
G02X347433Y730110I1502J0D01*
G03X347579Y730733I-161J366D01*
G02X347228Y731698I1151J965D01*
G02X348056Y733041I1503J0D01*
G03Y733755I-179J357D01*
G37*
G36*
G01X358665Y734742D02*
G02X357400Y736225I237J1483D01*
G02X360404I1502J0D01*
G02X359951Y735150I-1502J0D01*
G03X360167Y734468I279J-287D01*
G02X361432Y732985I-237J-1483D01*
G02X358428I-1502J0D01*
G02X358881Y734060I1502J0D01*
G03X358665Y734742I-279J287D01*
G37*
G36*
G01X414973Y943057D02*
G03X415513I270J294D01*
G02X416393Y943399I879J-959D01*
G02X417273Y943057I1J-1301D01*
G03X417813I270J294D01*
G02X418693Y943399I879J-959D01*
G02Y940797I0J-1301D01*
G02X417813Y941139I-1J1301D01*
G03X417273I-270J-294D01*
G02X416393Y940797I-879J959D01*
G02X415513Y941139I-1J1301D01*
G03X414973I-270J-294D01*
G02X414093Y940797I-879J959D01*
G02Y943399I0J1301D01*
G02X414973Y943057I1J-1301D01*
G37*
G36*
G01X425916Y948079D02*
G03Y948619I-294J270D01*
G02X425574Y949499I959J879D01*
G02X428176I1301J0D01*
G02X427834Y948619I-1301J-1D01*
G03Y948079I294J-270D01*
G02X428176Y947199I-959J-879D01*
G02X425574I-1301J0D01*
G02X425916Y948079I1301J1D01*
G37*
G36*
G01X453464Y950019D02*
G03Y950559I-294J270D01*
G02X453122Y951439I959J879D01*
G02X455724I1301J0D01*
G02X455382Y950559I-1301J-1D01*
G03Y950019I294J-270D01*
G02X455724Y949139I-959J-879D01*
G02X453122I-1301J0D01*
G02X453464Y950019I1301J1D01*
G37*
G36*
G01X465355Y955617D02*
G03X464791I-282J-284D01*
G02X463874Y955239I-917J923D01*
G02Y957841I0J1301D01*
G02X464791Y957463I0J-1301D01*
G03X465355I282J284D01*
G02X466272Y957841I917J-923D01*
G02Y955239I0J-1301D01*
G02X465355Y955617I0J1301D01*
G37*
G36*
G01X425946Y964515D02*
G03Y965055I-294J270D01*
G02X425604Y965935I959J879D01*
G02X428206I1301J0D01*
G02X427864Y965055I-1301J-1D01*
G03Y964515I294J-270D01*
G02X428206Y963635I-959J-879D01*
G02X425604I-1301J0D01*
G02X425946Y964515I1301J1D01*
G37*
G36*
G01X453434Y964709D02*
G03Y965249I-294J270D01*
G02X453092Y966129I959J879D01*
G02X455694I1301J0D01*
G02X455352Y965249I-1301J-1D01*
G03Y964709I294J-270D01*
G02X455694Y963829I-959J-879D01*
G02X453092I-1301J0D01*
G02X453434Y964709I1301J1D01*
G37*
G36*
G01X425946Y978916D02*
G03Y979456I-294J270D01*
G02X425604Y980336I959J879D01*
G02X428206I1301J0D01*
G02X427864Y979456I-1301J-1D01*
G03Y978916I294J-270D01*
G02X428206Y978036I-959J-879D01*
G02X425604I-1301J0D01*
G02X425946Y978916I1301J1D01*
G37*
G36*
G01X453304Y979789D02*
G03Y980329I-294J270D01*
G02X452962Y981209I959J879D01*
G02X455564I1301J0D01*
G02X455222Y980329I-1301J-1D01*
G03Y979789I294J-270D01*
G02X455564Y978909I-959J-879D01*
G02X452962I-1301J0D01*
G02X453304Y979789I1301J1D01*
G37*
G36*
G01X416661Y984654D02*
G03X416099I-281J-284D01*
G02X415185Y984279I-914J926D01*
G02Y986881I0J1301D01*
G02X416099Y986506I0J-1301D01*
G03X416661I281J284D01*
G02X417575Y986881I914J-926D01*
G02Y984279I0J-1301D01*
G02X416661Y984654I0J1301D01*
G37*
G36*
G01X465355Y984657D02*
G03X464791I-282J-284D01*
G02X463874Y984279I-917J923D01*
G02Y986881I0J1301D01*
G02X464791Y986503I0J-1301D01*
G03X465355I282J284D01*
G02X466272Y986881I917J-923D01*
G02Y984279I0J-1301D01*
G02X465355Y984657I0J1301D01*
G37*
G36*
G01X425946Y993302D02*
G03Y993842I-294J270D01*
G02X425604Y994722I959J879D01*
G02X428206I1301J0D01*
G02X427864Y993842I-1301J-1D01*
G03Y993302I294J-270D01*
G02X428206Y992422I-959J-879D01*
G02X425604I-1301J0D01*
G02X425946Y993302I1301J1D01*
G37*
G36*
G01X453504Y993879D02*
G03Y994419I-294J270D01*
G02X453162Y995299I959J879D01*
G02X455764I1301J0D01*
G02X455422Y994419I-1301J-1D01*
G03Y993879I294J-270D01*
G02X455764Y992999I-959J-879D01*
G02X453162I-1301J0D01*
G02X453504Y993879I1301J1D01*
G37*
G36*
G01X416661Y999134D02*
G03X416099I-281J-284D01*
G02X415185Y998759I-914J926D01*
G02Y1001361I0J1301D01*
G02X416099Y1000986I0J-1301D01*
G03X416661I281J284D01*
G02X417575Y1001361I914J-926D01*
G02Y998759I0J-1301D01*
G02X416661Y999134I0J1301D01*
G37*
G36*
G01X465355Y999137D02*
G03X464791I-282J-284D01*
G02X463874Y998759I-917J923D01*
G02Y1001361I0J1301D01*
G02X464791Y1000983I0J-1301D01*
G03X465355I282J284D01*
G02X466272Y1001361I917J-923D01*
G02Y998759I0J-1301D01*
G02X465355Y999137I0J1301D01*
G37*
G36*
G01X425946Y1007755D02*
G03Y1008295I-294J270D01*
G02X425604Y1009175I959J879D01*
G02X428206I1301J0D01*
G02X427864Y1008295I-1301J-1D01*
G03Y1007755I294J-270D01*
G02X428206Y1006875I-959J-879D01*
G02X425604I-1301J0D01*
G02X425946Y1007755I1301J1D01*
G37*
G36*
G01X453484Y1007989D02*
G03Y1008529I-294J270D01*
G02X453142Y1009409I959J879D01*
G02X455744I1301J0D01*
G02X455402Y1008529I-1301J-1D01*
G03Y1007989I294J-270D01*
G02X455744Y1007109I-959J-879D01*
G02X453142I-1301J0D01*
G02X453484Y1007989I1301J1D01*
G37*
G36*
G01X416661Y1013614D02*
G03X416099I-281J-284D01*
G02X415185Y1013239I-914J926D01*
G02Y1015841I0J1301D01*
G02X416099Y1015466I0J-1301D01*
G03X416661I281J284D01*
G02X417575Y1015841I914J-926D01*
G02Y1013239I0J-1301D01*
G02X416661Y1013614I0J1301D01*
G37*
G36*
G01X425946Y1020543D02*
G03Y1021083I-294J270D01*
G02X425604Y1021963I959J879D01*
G02X428206I1301J0D01*
G02X427864Y1021083I-1301J-1D01*
G03Y1020543I294J-270D01*
G02X428206Y1019663I-959J-879D01*
G02X425604I-1301J0D01*
G02X425946Y1020543I1301J1D01*
G37*
G36*
G01X453475Y1020766D02*
G03Y1021306I-294J270D01*
G02X453133Y1022186I959J879D01*
G02X455735I1301J0D01*
G02X455393Y1021306I-1301J-1D01*
G03Y1020766I294J-270D01*
G02X455735Y1019886I-959J-879D01*
G02X453133I-1301J0D01*
G02X453475Y1020766I1301J1D01*
G37*
G36*
G01X417917Y1029737D02*
G03X418505I294J272D01*
G02X420417I956J-881D01*
G03X421005I294J272D01*
G02X421961Y1030156I956J-881D01*
G02Y1027554I0J-1301D01*
G02X421005Y1027973I0J1300D01*
G03X420417I-294J-272D01*
G02X418505I-956J881D01*
G03X417917I-294J-272D01*
G02X416005I-956J881D01*
G03X415417I-294J-272D01*
G02X413505I-956J881D01*
G03X412917I-294J-272D01*
G02X411961Y1027554I-956J881D01*
G02Y1030156I0J1301D01*
G02X412917Y1029737I0J-1300D01*
G03X413505I294J272D01*
G02X415417I956J-881D01*
G03X416005I294J272D01*
G02X417917I956J-881D01*
G37*
G36*
G01X461636D02*
G03X462224I294J272D01*
G02X464136I956J-881D01*
G03X464724I294J272D01*
G02X465680Y1030156I956J-881D01*
G02Y1027554I0J-1301D01*
G02X464724Y1027973I0J1300D01*
G03X464136I-294J-272D01*
G02X462224I-956J881D01*
G03X461636I-294J-272D01*
G02X459724I-956J881D01*
G03X459136I-294J-272D01*
G02X458180Y1027554I-956J881D01*
G02Y1030156I0J1301D01*
G02X459136Y1029737I0J-1300D01*
G03X459724I294J272D01*
G02X461636I956J-881D01*
G37*
G36*
G01X407366Y1032851D02*
G03Y1033391I-294J270D01*
G02X407024Y1034271I959J879D01*
G02X409626I1301J0D01*
G02X409284Y1033391I-1301J-1D01*
G03Y1032851I294J-270D01*
G02X409626Y1031971I-959J-879D01*
G02X407024I-1301J0D01*
G02X407366Y1032851I1301J1D01*
G37*
G36*
G01X473963Y1138087D02*
X473123Y1139676D01*
X473028Y1139693D01*
G02X471960Y1140973I233J1280D01*
G02X474562I1301J0D01*
G02X474450Y1140444I-1301J-1D01*
G01X474410Y1140355D01*
X475250Y1138766D01*
X475345Y1138749D01*
G02X476413Y1137469I-233J-1280D01*
G02X473811I-1301J0D01*
G02X473923Y1137998I1301J1D01*
G01X473963Y1138087D01*
G37*
G36*
G01X458183Y1154502D02*
G03X458709I263J302D01*
G02X460683I987J-1131D01*
G03X461209I263J302D01*
G02X462196Y1154872I987J-1131D01*
G02Y1151868I0J-1502D01*
G02X461209Y1152238I0J1501D01*
G03X460683I-263J-302D01*
G02X458709I-987J1131D01*
G03X458183I-263J-302D01*
G02X457196Y1151868I-987J1131D01*
G02Y1154872I0J1502D01*
G02X458183Y1154502I0J-1501D01*
G37*
G36*
G01Y1162702D02*
G03X458709I263J302D01*
G02X460683I987J-1131D01*
G03X461209I263J302D01*
G02X462196Y1163072I987J-1131D01*
G02Y1160068I0J-1502D01*
G02X461209Y1160438I0J1501D01*
G03X460683I-263J-302D01*
G02X458709I-987J1131D01*
G03X458183I-263J-302D01*
G02X457196Y1160068I-987J1131D01*
G02Y1163072I0J1502D01*
G02X458183Y1162702I0J-1501D01*
G37*
G36*
G01Y1171202D02*
G03X458709I263J302D01*
G02X460683I987J-1131D01*
G03X461209I263J302D01*
G02X462196Y1171572I987J-1131D01*
G02Y1168568I0J-1502D01*
G02X461209Y1168938I0J1501D01*
G03X460683I-263J-302D01*
G02X458709I-987J1131D01*
G03X458183I-263J-302D01*
G02X457196Y1168568I-987J1131D01*
G02Y1171572I0J1502D01*
G02X458183Y1171202I0J-1501D01*
G37*
G36*
G01X461851Y1038028D02*
G03X462391I270J294D01*
G02X463271Y1038370I879J-959D01*
G02Y1035768I0J-1301D01*
G02X462391Y1036110I-1J1301D01*
G03X461851I-270J-294D01*
G02X460971Y1035768I-879J959D01*
G02X460091Y1036110I-1J1301D01*
G03X459551I-270J-294D01*
G02X459127Y1035850I-880J959D01*
G03X458955Y1035225I140J-375D01*
G02X459243Y1034409I-1012J-816D01*
G02X458824Y1033453I-1300J0D01*
G03Y1032865I272J-294D01*
G02X459243Y1031909I-881J-956D01*
G02X456641I-1301J0D01*
G02X457060Y1032865I1300J0D01*
G03Y1033453I-272J294D01*
G02X456641Y1034409I881J956D01*
G02X457486Y1035628I1302J0D01*
G03X457658Y1036253I-140J375D01*
G02X457370Y1037069I1012J816D01*
G02X458671Y1038370I1301J0D01*
G02X459551Y1038028I1J-1301D01*
G03X460091I270J294D01*
G02X460971Y1038370I879J-959D01*
G02X461851Y1038028I1J-1301D01*
G37*
G36*
G01X727830Y1430633D02*
G02X728124Y1429925I-708J-709D01*
G01Y1413939D01*
G02X727830Y1413231I-1002J1D01*
G01X722778Y1408179D01*
G02X722070Y1407886I-708J709D01*
G01X716881D01*
G02X715859Y1407388I-1120J1001D01*
G03X715492Y1406911I25J-399D01*
G02X715521Y1406619I-1473J-294D01*
G02X712517I-1502J0D01*
G02X713922Y1408118I1502J0D01*
G03X714289Y1408595I-25J399D01*
G02X714260Y1408887I1473J294D01*
G02X715762Y1410389I1502J0D01*
G02X716881Y1409888I-1J-1502D01*
G01X721655D01*
X726120Y1414354D01*
Y1429510D01*
X722030Y1433601D01*
X707852Y1439474D01*
X639394D01*
X618061Y1418141D01*
G02X617353Y1417848I-708J709D01*
G01X529765D01*
G02X529057Y1418141I0J1002D01*
G01X513063Y1434134D01*
X478035D01*
G02X477327Y1434428I1J1002D01*
G01X468186Y1443568D01*
X445510D01*
X438801Y1436860D01*
Y1436776D01*
G02X435797Y1436774I-1502J-2D01*
G02X437301Y1438276I1502J0D01*
G01X437385D01*
X444387Y1445278D01*
G02X445095Y1445572I709J-708D01*
G01X468601D01*
G02X469309Y1445278I-1J-1002D01*
G01X478450Y1436138D01*
X513478D01*
G02X514186Y1435844I-1J-1002D01*
G01X530180Y1419850D01*
X616938D01*
X638271Y1441183D01*
G02X638979Y1441476I708J-709D01*
G01X708052D01*
G02X708434Y1441400I-1J-1001D01*
G01X722980Y1435375D01*
G02X723305Y1435158I-383J-925D01*
G01X727830Y1430633D01*
G37*
G36*
G01X528741Y1416376D02*
X619760D01*
X624741Y1421357D01*
G02X625449Y1421650I708J-709D01*
G01X675235D01*
G02X675943Y1421357I0J-1002D01*
G01X680829Y1416471D01*
G02X681122Y1415763I-709J-708D01*
G01Y1410159D01*
G02X680829Y1409451I-1002J0D01*
G01X679557Y1408179D01*
G02X678849Y1407886I-708J709D01*
G01X678741D01*
X678683Y1407827D01*
G02X677716Y1407388I-1064J1060D01*
G03X677349Y1406911I25J-399D01*
G02X677378Y1406619I-1473J-294D01*
G02X674374I-1502J0D01*
G02X675779Y1408118I1502J0D01*
G03X676146Y1408595I-25J399D01*
G02X676117Y1408887I1473J294D01*
G02X677619Y1410389I1502J0D01*
G02X678584Y1410038I0J-1502D01*
G01X679120Y1410574D01*
Y1415348D01*
X674820Y1419648D01*
X625864D01*
X620883Y1414667D01*
G02X620175Y1414374I-708J709D01*
G01X528326D01*
G02X527618Y1414667I0J1002D01*
G01X511624Y1430660D01*
X469670D01*
G02X468962Y1430954I1J1002D01*
G01X464107Y1435808D01*
X449805D01*
X446361Y1432365D01*
G02X446225Y1432251I-709J707D01*
G03X446210Y1431606I229J-328D01*
G02X446796Y1430415I-917J-1191D01*
G02X443792I-1502J0D01*
G02X444517Y1431700I1501J0D01*
G01X444613Y1431759D01*
Y1432072D01*
X444187D01*
X439877Y1427762D01*
X439952Y1427630D01*
G02X440147Y1426890I-1307J-740D01*
G02X437143I-1502J0D01*
G02X437646Y1428011I1501J0D01*
G02X437937Y1428654I999J-65D01*
G01X443064Y1433781D01*
G02X443772Y1434074I708J-709D01*
G01X445238D01*
X448682Y1437518D01*
G02X449390Y1437812I709J-708D01*
G01X464522D01*
G02X465230Y1437518I-1J-1002D01*
G01X470085Y1432664D01*
X512039D01*
G02X512747Y1432370I-1J-1002D01*
G01X528741Y1416376D01*
G37*
G36*
G01X674478Y1410505D02*
G02X674979Y1409386I-1001J-1120D01*
G02X671975I-1502J0D01*
G02X672476Y1410505I1502J-1D01*
G01Y1415019D01*
X670847Y1416648D01*
X654109D01*
X649128Y1411667D01*
G02X648420Y1411374I-708J709D01*
G01X532235D01*
X521911Y1401050D01*
G02X521203Y1400756I-709J708D01*
G01X497656D01*
X493568Y1396669D01*
G02X492860Y1396376I-708J709D01*
G01X482944D01*
G02X482236Y1396669I0J1002D01*
G01X475976Y1402928D01*
X468622D01*
G02X467914Y1403222I1J1002D01*
G01X463405Y1407730D01*
X458885D01*
X457238Y1406084D01*
G02X456530Y1405790I-709J708D01*
G01X454970D01*
G02X454262Y1406084I1J1002D01*
G01X452832Y1407514D01*
G02X452538Y1408222I708J709D01*
G01Y1411159D01*
X448548Y1415150D01*
X446729D01*
X446673Y1415041D01*
G02X445339Y1414229I-1334J690D01*
G02Y1417233I0J1502D01*
G02X445795Y1417162I0J-1502D01*
G01X445825Y1417152D01*
X448963D01*
G02X449671Y1416859I0J-1002D01*
G01X454248Y1412282D01*
G02X454542Y1411574I-708J-709D01*
G01Y1408637D01*
X455385Y1407794D01*
X456115D01*
X457762Y1409440D01*
G02X458470Y1409734I709J-708D01*
G01X463820D01*
G02X464528Y1409440I-1J-1002D01*
G01X469037Y1404932D01*
X476391D01*
G02X477099Y1404638I-1J-1002D01*
G01X483359Y1398378D01*
X492445D01*
X496533Y1402466D01*
G02X497241Y1402760I709J-708D01*
G01X520788D01*
X531112Y1413083D01*
G02X531820Y1413376I708J-709D01*
G01X648005D01*
X652986Y1418357D01*
G02X653694Y1418650I708J-709D01*
G01X671262D01*
G02X671970Y1418357I0J-1002D01*
G01X674185Y1416142D01*
G02X674478Y1415434I-709J-708D01*
G01Y1410505D01*
G37*
G36*
G01X458647Y1394352D02*
G03Y1395066I-179J357D01*
G02X457819Y1396409I675J1343D01*
G02X459321Y1397911I1502J0D01*
G02X460805Y1396639I0J-1502D01*
G01X460832Y1396470D01*
X462339D01*
G02X463047Y1396176I-1J-1002D01*
G01X465337Y1393886D01*
G02X465630Y1393178I-709J-708D01*
G01Y1388668D01*
G02X465337Y1387960I-1002J0D01*
G01X463031Y1385654D01*
G02X462323Y1385360I-709J708D01*
G01X453215D01*
X436404Y1368550D01*
G02X435696Y1368256I-709J708D01*
G01X390334D01*
X383737Y1361660D01*
G02X383029Y1361366I-709J708D01*
G01X343277D01*
G02X342569Y1361660I1J1002D01*
G01X327691Y1376538D01*
X304317D01*
X304296Y1376361D01*
G02X302805Y1375039I-1491J180D01*
G02X301303Y1376541I0J1502D01*
G02X302131Y1377884I1503J0D01*
G03Y1378598I-179J357D01*
G02X301303Y1379941I675J1343D01*
G02X302805Y1381443I1502J0D01*
G02X304284Y1380205I0J-1502D01*
G01X304313Y1380040D01*
X328728D01*
G02X329436Y1379747I0J-1002D01*
G01X344314Y1364870D01*
X381992D01*
X388589Y1371466D01*
G02X389297Y1371760I709J-708D01*
G01X434659D01*
X451470Y1388570D01*
G02X452178Y1388864I709J-708D01*
G01X461286D01*
X462128Y1389705D01*
Y1392141D01*
X461302Y1392966D01*
X460832D01*
X460808Y1392795D01*
G02X459321Y1391507I-1487J214D01*
G02X457819Y1393009I0J1502D01*
G02X458647Y1394352I1503J0D01*
G37*
G36*
G01X468442Y1416962D02*
G02X467377Y1418400I438J1438D01*
G02X470383I1503J0D01*
G02X470341Y1418047I-1503J0D01*
G01Y1417895D01*
X471943Y1416293D01*
X475305D01*
X480642Y1410956D01*
X480876D01*
G02X481997Y1411458I1121J-1001D01*
G02Y1408452I0J-1503D01*
G02X480876Y1408954I0J1503D01*
G01X479812D01*
X474475Y1414291D01*
X471113D01*
X468442Y1416962D01*
G37*
G36*
G01X507041Y1447164D02*
G03Y1447794I-246J315D01*
G02X506462Y1448979I923J1185D01*
G02X509466I1502J0D01*
G02X508887Y1447794I-1502J0D01*
G03Y1447164I246J-315D01*
G02X509466Y1445979I-923J-1185D01*
G02X506462I-1502J0D01*
G02X507041Y1447164I1502J0D01*
G37*
G36*
G01X368887Y1418310D02*
G03X369521Y1418314I315J246D01*
G02X370717Y1418907I1196J-910D01*
G02X371902Y1418328I0J-1502D01*
G03X372530Y1418324I316J246D01*
G02X373703Y1418888I1173J-938D01*
G02X374936Y1418244I0J-1502D01*
G03X375592I328J229D01*
G02X376825Y1418888I1233J-858D01*
G02X378327Y1417386I0J-1502D01*
G02X377748Y1416201I-1502J0D01*
G03Y1415571I246J-315D01*
G02X378010Y1415309I-923J-1185D01*
G03X378640I315J246D01*
G02X379825Y1415888I1185J-923D01*
G02X381327Y1414386I0J-1502D01*
G02X380748Y1413201I-1502J0D01*
G03Y1412571I246J-315D01*
G02Y1410201I-923J-1185D01*
G03Y1409571I246J-315D01*
G02Y1407201I-923J-1185D01*
G03Y1406571I246J-315D01*
G02Y1404201I-923J-1185D01*
G03Y1403571I246J-315D01*
G02Y1401201I-923J-1185D01*
G03Y1400571I246J-315D01*
G02X381327Y1399386I-923J-1185D01*
G02X379825Y1397884I-1502J0D01*
G02X378640Y1398463I0J1502D01*
G03X378010I-315J-246D01*
G02X376825Y1397884I-1185J923D01*
G02X375592Y1398528I0J1502D01*
G03X374936I-328J-229D01*
G02X373703Y1397884I-1233J858D01*
G02X372518Y1398463I0J1502D01*
G03X371888I-315J-246D01*
G02X369518I-1185J923D01*
G03X368888I-315J-246D01*
G02X366518I-1185J923D01*
G03X365888I-315J-246D01*
G02X363518I-1185J923D01*
G03X362888I-315J-246D01*
G02X361703Y1397884I-1185J923D01*
G02X360538Y1398438I0J1502D01*
G03X359909Y1398428I-311J-252D01*
G02X358713Y1397834I-1196J907D01*
G02X357528Y1398413I0J1502D01*
G03X356898I-315J-246D01*
G02X354528I-1185J923D01*
G03X353898I-315J-246D01*
G02X352713Y1397834I-1185J923D01*
G02X351423Y1398567I0J1502D01*
G03X350776Y1398623I-344J-205D01*
G02X349636Y1398099I-1140J978D01*
G02X348134Y1399601I0J1502D01*
G02X348534Y1400621I1502J-1D01*
G03X348508Y1401190I-294J272D01*
G02X348011Y1402306I1004J1116D01*
G02X348560Y1403467I1502J0D01*
G03X348550Y1404094I-254J310D01*
G02X347961Y1405286I912J1192D01*
G02X348551Y1406480I1503J0D01*
G03X348522Y1407136I-243J318D01*
G02X347821Y1408406I800J1270D01*
G02X348311Y1409516I1502J0D01*
G03X348269Y1410140I-270J295D01*
G02X347621Y1411376I855J1236D01*
G02X348170Y1412537I1502J0D01*
G03X348160Y1413164I-254J310D01*
G02X348009Y1413295I907J1198D01*
G03X347453Y1413305I-283J-282D01*
G02X346426Y1412899I-1027J1096D01*
G02X344924Y1414401I0J1502D01*
G02X345391Y1415489I1501J0D01*
G03X345355Y1416099I-276J290D01*
G02X344754Y1417301I901J1202D01*
G02X346256Y1418803I1502J0D01*
G02X347320Y1418362I1J-1502D01*
G03X347876Y1418352I283J282D01*
G02X348903Y1418758I1027J-1096D01*
G02X350200Y1418013I0J-1501D01*
G03X350900Y1418029I346J201D01*
G02X352231Y1418834I1331J-698D01*
G02X353437Y1418227I0J-1502D01*
G03X354088Y1418238I322J238D01*
G02X355325Y1418888I1237J-852D01*
G02X356659Y1418077I0J-1503D01*
G03X357369I355J184D01*
G02X358703Y1418888I1334J-692D01*
G02X359888Y1418309I0J-1502D01*
G03X360518I315J246D01*
G02X362888I1185J-923D01*
G03X363518I315J246D01*
G02X365888I1185J-923D01*
G03X366518I315J246D01*
G02X367703Y1418888I1185J-923D01*
G02X368887Y1418310I0J-1502D01*
G37*
G36*
G01X373203Y1330440D02*
G02X372595Y1331647I894J1207D01*
G02X375599I1502J0D01*
G02X374991Y1330440I-1502J0D01*
G03Y1329798I239J-321D01*
G02X375599Y1328591I-894J-1207D01*
G02X372595I-1502J0D01*
G02X373203Y1329798I1502J0D01*
G03Y1330440I-239J321D01*
G37*
G36*
G01X405331D02*
G02X404723Y1331647I894J1207D01*
G02X407727I1502J0D01*
G02X407119Y1330440I-1502J0D01*
G03Y1329798I239J-321D01*
G02X407727Y1328591I-894J-1207D01*
G02X404723I-1502J0D01*
G02X405331Y1329798I1502J0D01*
G03Y1330440I-239J321D01*
G37*
G36*
G01X437459D02*
G02X436851Y1331647I894J1207D01*
G02X439855I1502J0D01*
G02X439247Y1330440I-1502J0D01*
G03Y1329798I239J-321D01*
G02X439855Y1328591I-894J-1207D01*
G02X436851I-1502J0D01*
G02X437459Y1329798I1502J0D01*
G03Y1330440I-239J321D01*
G37*
G36*
G01X469587D02*
G02X468979Y1331647I894J1207D01*
G02X471983I1502J0D01*
G02X471375Y1330440I-1502J0D01*
G03Y1329798I239J-321D01*
G02X471983Y1328591I-894J-1207D01*
G02X468979I-1502J0D01*
G02X469587Y1329798I1502J0D01*
G03Y1330440I-239J321D01*
G37*
G36*
G01X341075Y1343866D02*
G02X340467Y1345073I894J1207D01*
G02X343471I1502J0D01*
G02X342863Y1343866I-1502J0D01*
G03Y1343224I239J-321D01*
G02X343471Y1342017I-894J-1207D01*
G02X340467I-1502J0D01*
G02X341075Y1343224I1502J0D01*
G03Y1343866I-239J321D01*
G37*
G36*
G01X501715D02*
G02X501107Y1345073I894J1207D01*
G02X504111I1502J0D01*
G02X503503Y1343866I-1502J0D01*
G03Y1343224I239J-321D01*
G02X504111Y1342017I-894J-1207D01*
G02X501107I-1502J0D01*
G02X501715Y1343224I1502J0D01*
G03Y1343866I-239J321D01*
G37*
G36*
G01X726591Y1350028D02*
G03X727117I263J302D01*
G02X728104Y1350398I987J-1131D01*
G02X729606Y1348896I0J-1502D01*
G02X729236Y1347909I-1501J0D01*
G03Y1347383I302J-263D01*
G02Y1345409I-1131J-987D01*
G03Y1344883I302J-263D01*
G02Y1342909I-1131J-987D01*
G03Y1342383I302J-263D01*
G02Y1340409I-1131J-987D01*
G03Y1339883I302J-263D01*
G02Y1337909I-1131J-987D01*
G03Y1337383I302J-263D01*
G02Y1335409I-1131J-987D01*
G03Y1334883I302J-263D01*
G02X729606Y1333896I-1131J-987D01*
G02X728104Y1332394I-1502J0D01*
G02X727117Y1332764I0J1501D01*
G03X726591I-263J-302D01*
G02X725604Y1332394I-987J1131D01*
G02X724597Y1332781I-1J1502D01*
G03X724061I-268J-296D01*
G02X723670Y1332526I-1006J1115D01*
G03X723638Y1331813I164J-365D01*
G02X725468Y1328677I-1772J-3136D01*
G02X718264I-3602J0D01*
G02X721626Y1332271I3602J0D01*
G03X721906Y1332928I-26J399D01*
G02X721552Y1333896I1148J968D01*
G02X721922Y1334883I1501J0D01*
G03Y1335409I-302J263D01*
G02Y1337383I1131J987D01*
G03Y1337909I-302J263D01*
G02Y1339883I1131J987D01*
G03Y1340409I-302J263D01*
G02Y1342383I1131J987D01*
G03Y1342909I-302J263D01*
G02Y1344883I1131J987D01*
G03Y1345409I-302J263D01*
G02Y1347383I1131J987D01*
G03Y1347909I-302J263D01*
G02X721552Y1348896I1131J987D01*
G02X723054Y1350398I1502J0D01*
G02X724061Y1350011I1J-1502D01*
G03X724597I268J296D01*
G02X725604Y1350398I1006J-1115D01*
G02X726591Y1350028I0J-1501D01*
G37*
G36*
G01X308947Y1366664D02*
G02X308339Y1367871I894J1207D01*
G02X311343I1502J0D01*
G02X310735Y1366664I-1502J0D01*
G03Y1366022I239J-321D01*
G02X311343Y1364815I-894J-1207D01*
G02X308339I-1502J0D01*
G02X308947Y1366022I1502J0D01*
G03Y1366664I-239J321D01*
G37*
G36*
G01X533843D02*
G02X533235Y1367871I894J1207D01*
G02X536239I1502J0D01*
G02X535631Y1366664I-1502J0D01*
G03Y1366022I239J-321D01*
G02X536239Y1364815I-894J-1207D01*
G02X533235I-1502J0D01*
G02X533843Y1366022I1502J0D01*
G03Y1366664I-239J321D01*
G37*
G36*
G01X372629Y1377398D02*
G02X372030Y1378598I903J1200D01*
G02X375034I1502J0D01*
G02X374451Y1377410I-1502J0D01*
G03X374455Y1376773I244J-317D01*
G02X375054Y1375573I-903J-1200D01*
G02X373552Y1374071I-1502J0D01*
G02X372367Y1374650I0J1502D01*
G03X371737I-315J-246D01*
G02X370552Y1374071I-1185J923D01*
G02X369433Y1374571I0J1502D01*
G03X368822Y1374554I-298J-266D01*
G02X367647Y1373988I-1175J937D01*
G02X366462Y1374567I0J1502D01*
G03X365832I-315J-246D01*
G02X363462I-1185J923D01*
G03X362832I-315J-246D01*
G02X360462I-1185J923D01*
G03X359832I-315J-246D01*
G02X358647Y1373988I-1185J923D01*
G02X357145Y1375490I0J1502D01*
G02X357724Y1376675I1502J0D01*
G03Y1377305I-246J315D01*
G02X357145Y1378490I923J1185D01*
G02X360149I1502J0D01*
G02X359570Y1377305I-1502J0D01*
G03Y1376675I246J-315D01*
G02X359832Y1376413I-923J-1185D01*
G03X360462I315J246D01*
G02X362832I1185J-923D01*
G03X363462I315J246D01*
G02X365832I1185J-923D01*
G03X366462I315J246D01*
G02X367647Y1376992I1185J-923D01*
G02X368766Y1376492I0J-1502D01*
G03X369377Y1376509I298J266D01*
G02X370552Y1377075I1175J-937D01*
G02X371737Y1376496I0J-1502D01*
G03X372367I315J246D01*
G02X372633Y1376761I1185J-923D01*
G03X372629Y1377398I-244J317D01*
G37*
G36*
G01X353035Y1382331D02*
G03X353665I315J246D01*
G02X354850Y1382910I1185J-923D01*
G02X356352Y1381408I0J-1502D01*
G02X355773Y1380223I-1502J0D01*
G03Y1379593I246J-315D01*
G02Y1377223I-923J-1185D01*
G03Y1376593I246J-315D01*
G02X356352Y1375408I-923J-1185D01*
G02X354850Y1373906I-1502J0D01*
G02X353665Y1374485I0J1502D01*
G03X353035I-315J-246D01*
G02X351850Y1373906I-1185J923D01*
G02X351296Y1374012I0J1501D01*
G03X350752Y1373593I-147J-372D01*
G02X350762Y1373418I-1492J-173D01*
G02X350761Y1373366I-1502J3D01*
G03X351065Y1373189I200J-6D01*
G02X351850Y1373410I784J-1281D01*
G02X353035Y1372831I0J-1502D01*
G03X353665I315J246D01*
G02X354850Y1373410I1185J-923D01*
G02Y1370406I0J-1502D01*
G02X353665Y1370985I0J1502D01*
G03X353035I-315J-246D01*
G02X351850Y1370406I-1185J923D01*
G02X350362Y1371706I0J1502D01*
G03X349817Y1372023I-396J-54D01*
G02X349260Y1371916I-557J1396D01*
G02Y1374920I0J1502D01*
G02X349814Y1374814I0J-1501D01*
G03X350358Y1375233I147J372D01*
G02X350348Y1375408I1492J173D01*
G02X350349Y1375460I1502J-3D01*
G03X350045Y1375637I-200J6D01*
G02X349260Y1375416I-784J1281D01*
G02X347758Y1376918I0J1502D01*
G02X348337Y1378103I1502J0D01*
G03Y1378733I-246J315D01*
G02X347758Y1379918I923J1185D01*
G02X349260Y1381420I1502J0D01*
G02X349819Y1381312I0J-1501D01*
G03X350364Y1381625I149J371D01*
G02X351850Y1382910I1486J-217D01*
G02X353035Y1382331I0J-1502D01*
G37*
G36*
G01X409221Y1408946D02*
G02X408968Y1408925I-250J1481D01*
G02X410470Y1410427I0J1502D01*
G02X410438Y1410120I-1502J1D01*
G03X410897Y1409644I391J-82D01*
G02X411150Y1409665I250J-1481D01*
G02X409648Y1408163I0J-1502D01*
G02X409680Y1408470I1502J-1D01*
G03X409221Y1408946I-391J82D01*
G37*
G36*
G01X653866Y1426262D02*
G02X653038Y1427605I675J1343D01*
G02X656042I1502J0D01*
G02X655214Y1426262I-1503J0D01*
G03Y1425548I179J-357D01*
G02X656042Y1424205I-675J-1343D01*
G02X653038I-1502J0D01*
G02X653866Y1425548I1503J0D01*
G03Y1426262I-179J357D01*
G37*
G36*
G01X697879Y1431372D02*
G03X698509I315J246D01*
G02X699694Y1431951I1185J-923D01*
G02X701196Y1430449I0J-1502D01*
G02X700826Y1429462I-1501J0D01*
G03Y1428936I302J-263D01*
G02Y1426962I-1131J-987D01*
G03Y1426436I302J-263D01*
G02X701196Y1425449I-1131J-987D01*
G02X700730Y1424361I-1503J0D01*
G03X700749Y1423765I276J-290D01*
G02X701286Y1422614I-965J-1151D01*
G02X700787Y1421496I-1502J0D01*
G03X700780Y1420906I267J-298D01*
G02X701256Y1419809I-1026J-1097D01*
G02X699754Y1418307I-1502J0D01*
G02X698569Y1418886I0J1502D01*
G03X697939I-315J-246D01*
G02X696754Y1418307I-1185J923D01*
G02X695527Y1418942I0J1503D01*
G03X694975Y1419042I-327J-230D01*
G02X694129Y1418781I-846J1241D01*
G02X692944Y1419360I0J1502D01*
G03X692314I-315J-246D01*
G02X691129Y1418781I-1185J923D01*
G02X689627Y1420283I0J1502D01*
G02X690216Y1421475I1501J0D01*
G03Y1422111I-243J318D01*
G02X689627Y1423303I912J1192D01*
G02X691129Y1424805I1502J0D01*
G02X692314Y1424226I0J-1502D01*
G03X692944I315J246D01*
G02X694129Y1424805I1185J-923D01*
G02X694683Y1424699I0J-1501D01*
G03X695222Y1425151I147J372D01*
G02X695192Y1425449I1472J299D01*
G02X695562Y1426436I1501J0D01*
G03Y1426962I-302J263D01*
G02Y1428936I1131J987D01*
G03Y1429462I-302J263D01*
G02X695192Y1430449I1131J987D01*
G02X696694Y1431951I1502J0D01*
G02X697879Y1431372I0J-1502D01*
G37*
G36*
G01X672334Y1435072D02*
G03X672964I315J246D01*
G02X674149Y1435651I1185J-923D01*
G02X675587Y1434584I0J-1502D01*
G03X676253Y1434418I383J116D01*
G02X677319Y1434861I1065J-1059D01*
G02X678821Y1433359I0J-1502D01*
G02X678451Y1432372I-1501J0D01*
G03Y1431846I302J-263D01*
G02Y1429872I-1131J-987D01*
G03Y1429346I302J-263D01*
G02X678821Y1428359I-1131J-987D01*
G02X677319Y1426857I-1502J0D01*
G02X675992Y1427655I0J1502D01*
G03X675326Y1427716I-353J-188D01*
G02X675281Y1427662I-1176J934D01*
G03Y1427136I302J-263D01*
G02X675651Y1426149I-1131J-987D01*
G02X674149Y1424647I-1502J0D01*
G02X672964Y1425226I0J1502D01*
G03X672334I-315J-246D01*
G02X671149Y1424647I-1185J923D01*
G02X670162Y1425017I0J1501D01*
G03X669636I-263J-302D01*
G02X668649Y1424647I-987J1131D01*
G02X667147Y1426149I0J1502D01*
G02X667517Y1427136I1501J0D01*
G03Y1427662I-302J263D01*
G02Y1429636I1131J987D01*
G03Y1430162I-302J263D01*
G02X667147Y1431149I1131J987D01*
G02X667726Y1432334I1502J0D01*
G03Y1432964I-246J315D01*
G02X667147Y1434149I923J1185D01*
G02X668649Y1435651I1502J0D01*
G02X669636Y1435281I0J-1501D01*
G03X670162I263J302D01*
G02X671149Y1435651I987J-1131D01*
G02X672334Y1435072I0J-1502D01*
G37*
G36*
G01X392115Y1434470D02*
G02X390777Y1433650I-1338J682D01*
G02Y1436654I0J1502D01*
G02X392037Y1435969I0J-1501D01*
G03X392729Y1436005I336J218D01*
G02X394067Y1436825I1338J-682D01*
G02Y1433821I0J-1502D01*
G02X392807Y1434506I0J1501D01*
G03X392115Y1434470I-336J-218D01*
G37*
G36*
G01X414942Y1441234D02*
G02X413599Y1440406I-1343J675D01*
G02Y1443410I0J1502D01*
G02X414942Y1442582I0J-1503D01*
G03X415656I357J179D01*
G02X416999Y1443410I1343J-675D01*
G02Y1440406I0J-1502D01*
G02X415656Y1441234I0J1503D01*
G03X414942I-357J-179D01*
G37*
G36*
G01X425489Y1442737D02*
G02X424146Y1441909I-1343J675D01*
G02Y1444913I0J1502D01*
G02X425489Y1444085I0J-1503D01*
G03X426203I357J179D01*
G02X427546Y1444913I1343J-675D01*
G02Y1441909I0J-1502D01*
G02X426203Y1442737I0J1503D01*
G03X425489I-357J-179D01*
G37*
G36*
G01X680976Y1432234D02*
G03Y1432864I-246J315D01*
G02X680397Y1434049I923J1185D01*
G02X683401I1502J0D01*
G02X682822Y1432864I-1502J0D01*
G03Y1432234I246J-315D01*
G02X683401Y1431049I-923J-1185D01*
G02X683031Y1430062I-1501J0D01*
G03Y1429536I302J-263D01*
G02Y1427562I-1131J-987D01*
G03Y1427036I302J-263D01*
G02X683401Y1426049I-1131J-987D01*
G02X680397I-1502J0D01*
G02X680767Y1427036I1501J0D01*
G03Y1427562I-302J263D01*
G02Y1429536I1131J987D01*
G03Y1430062I-302J263D01*
G02X680397Y1431049I1131J987D01*
G02X680976Y1432234I1502J0D01*
G37*
G36*
G01X706680Y1407865D02*
G03Y1408489I-251J312D01*
G02X706118Y1409660I939J1171D01*
G02X709122I1502J0D01*
G02X708560Y1408489I-1501J0D01*
G03Y1407865I251J-312D01*
G02X709122Y1406694I-939J-1171D01*
G02X706118I-1502J0D01*
G02X706680Y1407865I1501J0D01*
G37*
G36*
G01X668427Y1407768D02*
G03Y1408341I-279J286D01*
G02X667975Y1409415I1050J1074D01*
G02X670979I1502J0D01*
G02X670527Y1408341I-1502J0D01*
G03Y1407768I279J-286D01*
G02X670979Y1406694I-1050J-1074D01*
G02X667975I-1502J0D01*
G02X668427Y1407768I1502J0D01*
G37*
G36*
G01X724682Y1404069D02*
G03Y1404679I-259J305D01*
G02X724152Y1405824I972J1145D01*
G02X725654Y1407326I1502J0D01*
G02X727143Y1406022I0J-1502D01*
G03X727598Y1405680I396J53D01*
G02X727820Y1405696I219J-1486D01*
G02X728026Y1405682I1J-1502D01*
G03X728467Y1405976I54J396D01*
G02X729920Y1407096I1453J-383D01*
G02X731422Y1405594I0J-1502D01*
G02X730892Y1404449I-1502J0D01*
G03Y1403839I259J-305D01*
G02Y1401549I-972J-1145D01*
G03Y1400939I259J-305D01*
G02X731422Y1399794I-972J-1145D01*
G02X729920Y1398292I-1502J0D01*
G02X728464Y1399424I0J1502D01*
G03X728002Y1399719I-388J-98D01*
G02X727720Y1399692I-284J1475D01*
G02X727002Y1399875I0J1502D01*
G03X726426Y1399632I-191J-352D01*
G02X725014Y1398563I-1412J398D01*
G02X724438Y1398681I0J1467D01*
G03X723939Y1398520I-157J-368D01*
G02X721429I-1255J760D01*
G03X720930Y1398681I-342J-207D01*
G02X720354Y1398563I-576J1349D01*
G02X719778Y1398681I0J1467D01*
G03X719279Y1398520I-157J-368D01*
G02X718024Y1397813I-1255J760D01*
G02Y1400747I0J1467D01*
G02X718600Y1400629I0J-1467D01*
G03X719099Y1400790I157J368D01*
G02X721609I1255J-760D01*
G03X722108Y1400629I342J207D01*
G02X722684Y1400747I576J-1349D01*
G02X723260Y1400629I0J-1467D01*
G03X723759Y1400790I157J368D01*
G02X724369Y1401347I1254J-761D01*
G03X724500Y1401963I-176J359D01*
G02X724152Y1402924I1153J961D01*
G02X724682Y1404069I1502J0D01*
G37*
G36*
G01X686539D02*
G03Y1404679I-259J305D01*
G02X686009Y1405824I972J1145D01*
G02X687511Y1407326I1502J0D01*
G02X689000Y1406022I0J-1502D01*
G03X689455Y1405680I396J53D01*
G02X689677Y1405696I219J-1486D01*
G02X689883Y1405682I1J-1502D01*
G03X690324Y1405976I54J396D01*
G02X691777Y1407096I1453J-383D01*
G02X693279Y1405594I0J-1502D01*
G02X692749Y1404449I-1502J0D01*
G03Y1403839I259J-305D01*
G02Y1401549I-972J-1145D01*
G03Y1400939I259J-305D01*
G02X693279Y1399794I-972J-1145D01*
G02X691777Y1398292I-1502J0D01*
G02X690321Y1399424I0J1502D01*
G03X689859Y1399719I-388J-98D01*
G02X689577Y1399692I-284J1475D01*
G02X688859Y1399875I0J1502D01*
G03X688283Y1399632I-191J-352D01*
G02X686871Y1398563I-1412J398D01*
G02X686295Y1398681I0J1467D01*
G03X685796Y1398520I-157J-368D01*
G02X683286I-1255J760D01*
G03X682787Y1398681I-342J-207D01*
G02X682211Y1398563I-576J1349D01*
G02X681635Y1398681I0J1467D01*
G03X681136Y1398520I-157J-368D01*
G02X679881Y1397813I-1255J760D01*
G02Y1400747I0J1467D01*
G02X680457Y1400629I0J-1467D01*
G03X680956Y1400790I157J368D01*
G02X683466I1255J-760D01*
G03X683965Y1400629I342J207D01*
G02X684541Y1400747I576J-1349D01*
G02X685117Y1400629I0J-1467D01*
G03X685616Y1400790I157J368D01*
G02X686226Y1401347I1254J-761D01*
G03X686357Y1401963I-176J359D01*
G02X686009Y1402924I1153J961D01*
G02X686539Y1404069I1502J0D01*
G37*
G36*
G01X662072Y1396177D02*
G03Y1396713I-296J268D01*
G02X661685Y1397720I1115J1006D01*
G02X664689I1502J0D01*
G02X664302Y1396713I-1502J-1D01*
G03Y1396177I296J-268D01*
G02X664689Y1395170I-1115J-1006D01*
G02X661685I-1502J0D01*
G02X662072Y1396177I1502J1D01*
G37*
G36*
G01X700198Y1396182D02*
G03Y1396708I-302J263D01*
G02X699828Y1397695I1131J987D01*
G02X702832I1502J0D01*
G02X702462Y1396708I-1501J0D01*
G03Y1396182I302J-263D01*
G02X702832Y1395195I-1131J-987D01*
G02X699828I-1502J0D01*
G02X700198Y1396182I1501J0D01*
G37*
G36*
G01X376102Y1379675D02*
G03Y1380305I-246J315D01*
G02X375523Y1381490I923J1185D01*
G02X377025Y1382992I1502J0D01*
G02X378210Y1382413I0J-1502D01*
G03X378840I315J246D01*
G02X380025Y1382992I1185J-923D01*
G02X381527Y1381490I0J-1502D01*
G02X380948Y1380305I-1502J0D01*
G03Y1379675I246J-315D01*
G02Y1377305I-923J-1185D01*
G03Y1376675I246J-315D01*
G02X381527Y1375490I-923J-1185D01*
G02X380025Y1373988I-1502J0D01*
G02X378840Y1374567I0J1502D01*
G03X378210I-315J-246D01*
G02X377025Y1373988I-1185J923D01*
G02X375523Y1375490I0J1502D01*
G02X376102Y1376675I1502J0D01*
G03Y1377305I-246J315D01*
G02Y1379675I923J1185D01*
G37*
G36*
G01X368766Y1372992D02*
G03X369377Y1373009I298J266D01*
G02X370552Y1373575I1175J-937D01*
G02X371737Y1372996I0J-1502D01*
G03X372367I315J246D01*
G02X373552Y1373575I1185J-923D01*
G02Y1370571I0J-1502D01*
G02X372367Y1371150I0J1502D01*
G03X371737I-315J-246D01*
G02X370552Y1370571I-1185J923D01*
G02X369433Y1371071I0J1502D01*
G03X368822Y1371054I-298J-266D01*
G02X367647Y1370488I-1175J937D01*
G02X366462Y1371067I0J1502D01*
G03X365832I-315J-246D01*
G02X363462I-1185J923D01*
G03X362832I-315J-246D01*
G02X360462I-1185J923D01*
G03X359832I-315J-246D01*
G02X358647Y1370488I-1185J923D01*
G02Y1373492I0J1502D01*
G02X359832Y1372913I0J-1502D01*
G03X360462I315J246D01*
G02X362832I1185J-923D01*
G03X363462I315J246D01*
G02X365832I1185J-923D01*
G03X366462I315J246D01*
G02X367647Y1373492I1185J-923D01*
G02X368766Y1372992I0J-1502D01*
G37*
G36*
G01X378840Y1371067D02*
G03X378210I-315J-246D01*
G02X377025Y1370488I-1185J923D01*
G02Y1373492I0J1502D01*
G02X378210Y1372913I0J-1502D01*
G03X378840I315J246D01*
G02X380025Y1373492I1185J-923D01*
G02Y1370488I0J-1502D01*
G02X378840Y1371067I0J1502D01*
G37*
G36*
G01X541209Y1366063D02*
G03X541518Y1366580I-71J394D01*
G02X541445Y1367043I1429J463D01*
G02X544449I1502J0D01*
G02X543213Y1365565I-1502J0D01*
G03X542904Y1365048I71J-394D01*
G02X542977Y1364585I-1429J-463D01*
G02X541475Y1363083I-1502J0D01*
G02X540071Y1364053I0J1501D01*
G03X539495Y1364256I-374J-142D01*
G02X538737Y1364051I-758J1297D01*
G02Y1367055I0J1502D01*
G02X540141Y1366085I0J-1501D01*
G03X540717Y1365882I374J142D01*
G02X541209Y1366063I757J-1298D01*
G37*
G36*
G01X316313D02*
G03X316622Y1366580I-71J394D01*
G02X316549Y1367043I1429J463D01*
G02X319553I1502J0D01*
G02X318317Y1365565I-1502J0D01*
G03X318008Y1365048I71J-394D01*
G02X318081Y1364585I-1429J-463D01*
G02X316579Y1363083I-1502J0D01*
G02X315175Y1364053I0J1501D01*
G03X314599Y1364256I-374J-142D01*
G02X313841Y1364051I-758J1297D01*
G02Y1367055I0J1502D01*
G02X315245Y1366085I0J-1501D01*
G03X315821Y1365882I374J142D01*
G02X316313Y1366063I757J-1298D01*
G37*
G36*
G01X551799Y1362190D02*
G03Y1362800I-259J305D01*
G02X551269Y1363945I972J1145D01*
G02X552771Y1365447I1502J0D01*
G02X554260Y1364143I0J-1502D01*
G03X554715Y1363801I396J53D01*
G02X554937Y1363817I219J-1486D01*
G02X555143Y1363803I1J-1502D01*
G03X555584Y1364097I54J396D01*
G02X557037Y1365217I1453J-383D01*
G02X558539Y1363715I0J-1502D01*
G02X558009Y1362570I-1502J0D01*
G03Y1361960I259J-305D01*
G02Y1359670I-972J-1145D01*
G03Y1359060I259J-305D01*
G02X558539Y1357915I-972J-1145D01*
G02X557037Y1356413I-1502J0D01*
G02X555581Y1357545I0J1502D01*
G03X555119Y1357840I-388J-98D01*
G02X554837Y1357813I-284J1475D01*
G02X554119Y1357996I0J1502D01*
G03X553543Y1357753I-191J-352D01*
G02X552131Y1356684I-1412J398D01*
G02X551555Y1356802I0J1467D01*
G03X551056Y1356641I-157J-368D01*
G02X548546I-1255J760D01*
G03X548047Y1356802I-342J-207D01*
G02X547471Y1356684I-576J1349D01*
G02X546895Y1356802I0J1467D01*
G03X546396Y1356641I-157J-368D01*
G02X545141Y1355934I-1255J760D01*
G02Y1358868I0J1467D01*
G02X545717Y1358750I0J-1467D01*
G03X546216Y1358911I157J368D01*
G02X548726I1255J-760D01*
G03X549225Y1358750I342J207D01*
G02X549801Y1358868I576J-1349D01*
G02X550377Y1358750I0J-1467D01*
G03X550876Y1358911I157J368D01*
G02X551486Y1359468I1254J-761D01*
G03X551617Y1360084I-176J359D01*
G02X551269Y1361045I1153J961D01*
G02X551799Y1362190I1502J0D01*
G37*
G36*
G01X326903D02*
G03Y1362800I-259J305D01*
G02X326373Y1363945I972J1145D01*
G02X327875Y1365447I1502J0D01*
G02X329364Y1364143I0J-1502D01*
G03X329819Y1363801I396J53D01*
G02X330041Y1363817I219J-1486D01*
G02X330581Y1363717I1J-1502D01*
G03X331093Y1363933I144J373D01*
G02X332475Y1364847I1382J-588D01*
G02X333977Y1363345I0J-1502D01*
G02X333447Y1362200I-1502J0D01*
G03Y1361590I259J-305D01*
G02X333977Y1360445I-972J-1145D01*
G02X333607Y1359458I-1501J0D01*
G03Y1358932I302J-263D01*
G02X333977Y1357945I-1131J-987D01*
G02X332475Y1356443I-1502J0D01*
G02X331008Y1357623I0J1502D01*
G03X330475Y1357911I-391J-86D01*
G02X329941Y1357813I-534J1404D01*
G02X329223Y1357996I0J1502D01*
G03X328647Y1357753I-191J-352D01*
G02X327235Y1356684I-1412J398D01*
G02X326659Y1356802I0J1467D01*
G03X326160Y1356641I-157J-368D01*
G02X323650I-1255J760D01*
G03X323151Y1356802I-342J-207D01*
G02X322575Y1356684I-576J1349D01*
G02X321999Y1356802I0J1467D01*
G03X321500Y1356641I-157J-368D01*
G02X320245Y1355934I-1255J760D01*
G02Y1358868I0J1467D01*
G02X320821Y1358750I0J-1467D01*
G03X321320Y1358911I157J368D01*
G02X323830I1255J-760D01*
G03X324329Y1358750I342J207D01*
G02X324905Y1358868I576J-1349D01*
G02X325481Y1358750I0J-1467D01*
G03X325980Y1358911I157J368D01*
G02X326590Y1359468I1254J-761D01*
G03X326721Y1360084I-176J359D01*
G02X326373Y1361045I1153J961D01*
G02X326903Y1362190I1502J0D01*
G37*
G36*
G01X302604Y1354318D02*
G03Y1354851I-298J266D01*
G02X302221Y1355853I1119J1002D01*
G02X305225I1502J0D01*
G02X304842Y1354851I-1502J0D01*
G03Y1354318I298J-267D01*
G02X305225Y1353316I-1119J-1002D01*
G02X302221I-1502J0D01*
G02X302604Y1354318I1502J0D01*
G37*
G36*
G01X527315Y1354303D02*
G03Y1354829I-302J263D01*
G02X526945Y1355816I1131J987D01*
G02X529949I1502J0D01*
G02X529579Y1354829I-1501J0D01*
G03Y1354303I302J-263D01*
G02X529949Y1353316I-1131J-987D01*
G02X526945I-1502J0D01*
G02X527315Y1354303I1501J0D01*
G37*
G36*
G01X704074Y1350028D02*
G03X704600I263J302D01*
G02X705587Y1350398I987J-1131D01*
G02X706594Y1350011I1J-1502D01*
G03X707130I268J296D01*
G02X708137Y1350398I1006J-1115D01*
G02X709639Y1348896I0J-1502D01*
G02X709269Y1347909I-1501J0D01*
G03Y1347383I302J-263D01*
G02Y1345409I-1131J-987D01*
G03Y1344883I302J-263D01*
G02Y1342909I-1131J-987D01*
G03Y1342383I302J-263D01*
G02Y1340409I-1131J-987D01*
G03Y1339883I302J-263D01*
G02Y1337909I-1131J-987D01*
G03Y1337383I302J-263D01*
G02Y1335409I-1131J-987D01*
G03Y1334883I302J-263D01*
G02X709639Y1333896I-1131J-987D01*
G02X708137Y1332394I-1502J0D01*
G02X707130Y1332781I-1J1502D01*
G03X706594I-268J-296D01*
G02X705587Y1332394I-1006J1115D01*
G02X704600Y1332764I0J1501D01*
G03X704074I-263J-302D01*
G02X703087Y1332394I-987J1131D01*
G02X701585Y1333896I0J1502D01*
G02X701955Y1334883I1501J0D01*
G03Y1335409I-302J263D01*
G02Y1337383I1131J987D01*
G03Y1337909I-302J263D01*
G02Y1339883I1131J987D01*
G03Y1340409I-302J263D01*
G02Y1342383I1131J987D01*
G03Y1342909I-302J263D01*
G02Y1344883I1131J987D01*
G03Y1345409I-302J263D01*
G02Y1347383I1131J987D01*
G03Y1347909I-302J263D01*
G02X701585Y1348896I1131J987D01*
G02X703087Y1350398I1502J0D01*
G02X704074Y1350028I0J-1501D01*
G37*
G36*
G01X685562Y1350011D02*
G03X686098I268J296D01*
G02X687105Y1350398I1006J-1115D01*
G02X688092Y1350028I0J-1501D01*
G03X688618I263J302D01*
G02X689605Y1350398I987J-1131D01*
G02X691107Y1348896I0J-1502D01*
G02X690737Y1347909I-1501J0D01*
G03Y1347383I302J-263D01*
G02Y1345409I-1131J-987D01*
G03Y1344883I302J-263D01*
G02Y1342909I-1131J-987D01*
G03Y1342383I302J-263D01*
G02Y1340409I-1131J-987D01*
G03Y1339883I302J-263D01*
G02Y1337909I-1131J-987D01*
G03Y1337383I302J-263D01*
G02Y1335409I-1131J-987D01*
G03Y1334883I302J-263D01*
G02X691107Y1333896I-1131J-987D01*
G02X689605Y1332394I-1502J0D01*
G02X688618Y1332764I0J1501D01*
G03X688092I-263J-302D01*
G02X687105Y1332394I-987J1131D01*
G02X686098Y1332781I-1J1502D01*
G03X685562I-268J-296D01*
G02X684555Y1332394I-1006J1115D01*
G02X683053Y1333896I0J1502D01*
G02X683423Y1334883I1501J0D01*
G03Y1335409I-302J263D01*
G02Y1337383I1131J987D01*
G03Y1337909I-302J263D01*
G02Y1339883I1131J987D01*
G03Y1340409I-302J263D01*
G02Y1342383I1131J987D01*
G03Y1342909I-302J263D01*
G02Y1344883I1131J987D01*
G03Y1345409I-302J263D01*
G02Y1347383I1131J987D01*
G03Y1347909I-302J263D01*
G02X683053Y1348896I1131J987D01*
G02X684555Y1350398I1502J0D01*
G02X685562Y1350011I1J-1502D01*
G37*
G36*
G01X665974Y1350028D02*
G03X666500I263J302D01*
G02X667487Y1350398I987J-1131D01*
G02X668494Y1350011I1J-1502D01*
G03X669030I268J296D01*
G02X670037Y1350398I1006J-1115D01*
G02X671539Y1348896I0J-1502D01*
G02X671169Y1347909I-1501J0D01*
G03Y1347383I302J-263D01*
G02Y1345409I-1131J-987D01*
G03Y1344883I302J-263D01*
G02Y1342909I-1131J-987D01*
G03Y1342383I302J-263D01*
G02Y1340409I-1131J-987D01*
G03Y1339883I302J-263D01*
G02Y1337909I-1131J-987D01*
G03Y1337383I302J-263D01*
G02Y1335409I-1131J-987D01*
G03Y1334883I302J-263D01*
G02X671539Y1333896I-1131J-987D01*
G02X670037Y1332394I-1502J0D01*
G02X669030Y1332781I-1J1502D01*
G03X668494I-268J-296D01*
G02X667487Y1332394I-1006J1115D01*
G02X666500Y1332764I0J1501D01*
G03X665974I-263J-302D01*
G02X664987Y1332394I-987J1131D01*
G02X663485Y1333896I0J1502D01*
G02X663855Y1334883I1501J0D01*
G03Y1335409I-302J263D01*
G02Y1337383I1131J987D01*
G03Y1337909I-302J263D01*
G02Y1339883I1131J987D01*
G03Y1340409I-302J263D01*
G02Y1342383I1131J987D01*
G03Y1342909I-302J263D01*
G02Y1344883I1131J987D01*
G03Y1345409I-302J263D01*
G02Y1347383I1131J987D01*
G03Y1347909I-302J263D01*
G02X663485Y1348896I1131J987D01*
G02X664987Y1350398I1502J0D01*
G02X665974Y1350028I0J-1501D01*
G37*
G36*
G01X509081Y1343265D02*
G03X509390Y1343782I-71J394D01*
G02X509317Y1344245I1429J463D01*
G02X512321I1502J0D01*
G02X511085Y1342767I-1502J0D01*
G03X510776Y1342250I71J-394D01*
G02X510849Y1341787I-1429J-463D01*
G02X509347Y1340285I-1502J0D01*
G02X507943Y1341255I0J1501D01*
G03X507367Y1341458I-374J-142D01*
G02X506609Y1341253I-758J1297D01*
G02Y1344257I0J1502D01*
G02X508013Y1343287I0J-1501D01*
G03X508589Y1343084I374J142D01*
G02X509081Y1343265I757J-1298D01*
G37*
G36*
G01X348441D02*
G03X348750Y1343782I-71J394D01*
G02X348677Y1344245I1429J463D01*
G02X351681I1502J0D01*
G02X350445Y1342767I-1502J0D01*
G03X350136Y1342250I71J-394D01*
G02X350209Y1341787I-1429J-463D01*
G02X348707Y1340285I-1502J0D01*
G02X347303Y1341255I0J1501D01*
G03X346727Y1341458I-374J-142D01*
G02X345969Y1341253I-758J1297D01*
G02Y1344257I0J1502D01*
G02X347373Y1343287I0J-1501D01*
G03X347949Y1343084I374J142D01*
G02X348441Y1343265I757J-1298D01*
G37*
G36*
G01X520861Y1342633D02*
G03X521318Y1343008I58J396D01*
G02X522818Y1344432I1500J-78D01*
G02X524283Y1343263I0J-1502D01*
G03X524719Y1342954I390J88D01*
G02X524892Y1342964I173J-1491D01*
G02Y1339960I0J-1502D01*
G02X524748Y1339967I1J1502D01*
G03X524310Y1339558I-38J-398D01*
G02X524311Y1339517I-1501J-57D01*
G02X522809Y1338015I-1502J0D01*
G02X522524Y1338042I-1J1502D01*
G03X522069Y1337775I-75J-393D01*
G02X521284Y1336889I-1426J472D01*
G03X521144Y1336275I171J-362D01*
G02X521241Y1336140I-1141J-922D01*
G03X521832Y1336045I338J214D01*
G02X522783Y1336384I951J-1163D01*
G02X523082Y1336354I0J-1502D01*
G03X523550Y1336649I80J392D01*
G02X525008Y1337789I1458J-362D01*
G02Y1334785I0J-1502D01*
G02X524709Y1334815I0J1502D01*
G03X524241Y1334520I-80J-392D01*
G02X522783Y1333380I-1458J362D01*
G02X521502Y1334098I0J1502D01*
G03X520913Y1334202I-341J-209D01*
G02X520003Y1333886I-910J1152D01*
G02X519427Y1334004I0J1467D01*
G03X518928Y1333843I-157J-368D01*
G02X516418I-1255J760D01*
G03X515919Y1334004I-342J-207D01*
G02X515343Y1333886I-576J1349D01*
G02X514767Y1334004I0J1467D01*
G03X514268Y1333843I-157J-368D01*
G02X513013Y1333136I-1255J760D01*
G02Y1336070I0J1467D01*
G02X513589Y1335952I0J-1467D01*
G03X514088Y1336113I157J368D01*
G02X516598I1255J-760D01*
G03X517097Y1335952I342J207D01*
G02X517673Y1336070I576J-1349D01*
G02X518249Y1335952I0J-1467D01*
G03X518748Y1336113I157J368D01*
G02X519358Y1336670I1254J-761D01*
G03X519489Y1337286I-176J359D01*
G02X519141Y1338247I1153J961D01*
G02X519671Y1339392I1502J0D01*
G03Y1340002I-259J305D01*
G02X519141Y1341147I972J1145D01*
G02X520643Y1342649I1502J0D01*
G02X520861Y1342633I-1J-1502D01*
G37*
G36*
G01X359031Y1339392D02*
G03Y1340002I-259J305D01*
G02X358501Y1341147I972J1145D01*
G02X360003Y1342649I1502J0D01*
G02X361474Y1341453I0J-1503D01*
G03X361924Y1341138I392J81D01*
G02X362147Y1341155I225J-1485D01*
G02X362475Y1341119I1J-1502D01*
G03X362937Y1341371I87J390D01*
G02X364347Y1342355I1410J-518D01*
G02X365849Y1340853I0J-1502D01*
G02X365316Y1339706I-1501J0D01*
G03X365300Y1339109I258J-306D01*
G02X365771Y1338017I-1030J-1092D01*
G02X365049Y1336733I-1503J0D01*
G03X365008Y1336079I208J-341D01*
G02X365575Y1334903I-936J-1176D01*
G02X364073Y1333401I-1502J0D01*
G02X362584Y1334704I0J1502D01*
G03X362179Y1335051I-396J-53D01*
G01X362147D01*
G02X361382Y1335260I-1J1502D01*
G03X360789Y1335010I-204J-344D01*
G02X359363Y1333886I-1426J343D01*
G02X358787Y1334004I0J1467D01*
G03X358288Y1333843I-157J-368D01*
G02X355778I-1255J760D01*
G03X355279Y1334004I-342J-207D01*
G02X354703Y1333886I-576J1349D01*
G02X354127Y1334004I0J1467D01*
G03X353628Y1333843I-157J-368D01*
G02X352373Y1333136I-1255J760D01*
G02Y1336070I0J1467D01*
G02X352949Y1335952I0J-1467D01*
G03X353448Y1336113I157J368D01*
G02X355958I1255J-760D01*
G03X356457Y1335952I342J207D01*
G02X357033Y1336070I576J-1349D01*
G02X357609Y1335952I0J-1467D01*
G03X358108Y1336113I157J368D01*
G02X358718Y1336670I1254J-761D01*
G03X358849Y1337286I-176J359D01*
G02X358501Y1338247I1153J961D01*
G02X359031Y1339392I1502J0D01*
G37*
G36*
G01X334467Y1331405D02*
G03X334318Y1332001I-323J236D01*
G02X333471Y1333353I656J1352D01*
G02X336475I1502J0D01*
G02X336185Y1332466I-1501J0D01*
G03X336334Y1331870I323J-236D01*
G02X337181Y1330518I-656J-1352D01*
G02X334177I-1502J0D01*
G02X334467Y1331405I1501J0D01*
G37*
G36*
G01X495204Y1331500D02*
G03Y1332036I-296J268D01*
G02X494817Y1333043I1115J1006D01*
G02X497821I1502J0D01*
G02X497434Y1332036I-1502J-1D01*
G03Y1331500I296J-268D01*
G02X497821Y1330493I-1115J-1006D01*
G02X494817I-1502J0D01*
G02X495204Y1331500I1502J1D01*
G37*
G36*
G01X476953Y1329839D02*
G03X477262Y1330356I-71J394D01*
G02X477189Y1330819I1429J463D01*
G02X480193I1502J0D01*
G02X478957Y1329341I-1502J0D01*
G03X478648Y1328824I71J-394D01*
G02X478721Y1328361I-1429J-463D01*
G02X477219Y1326859I-1502J0D01*
G02X475815Y1327829I0J1501D01*
G03X475239Y1328032I-374J-142D01*
G02X474481Y1327827I-758J1297D01*
G02Y1330831I0J1502D01*
G02X475885Y1329861I0J-1501D01*
G03X476461Y1329658I374J142D01*
G02X476953Y1329839I757J-1298D01*
G37*
G36*
G01X444825D02*
G03X445134Y1330356I-71J394D01*
G02X445061Y1330819I1429J463D01*
G02X448065I1502J0D01*
G02X446829Y1329341I-1502J0D01*
G03X446520Y1328824I71J-394D01*
G02X446593Y1328361I-1429J-463D01*
G02X445091Y1326859I-1502J0D01*
G02X443687Y1327829I0J1501D01*
G03X443111Y1328032I-374J-142D01*
G02X442353Y1327827I-758J1297D01*
G02Y1330831I0J1502D01*
G02X443757Y1329861I0J-1501D01*
G03X444333Y1329658I374J142D01*
G02X444825Y1329839I757J-1298D01*
G37*
G36*
G01X412697D02*
G03X413006Y1330356I-71J394D01*
G02X412933Y1330819I1429J463D01*
G02X415937I1502J0D01*
G02X414701Y1329341I-1502J0D01*
G03X414392Y1328824I71J-394D01*
G02X414465Y1328361I-1429J-463D01*
G02X412963Y1326859I-1502J0D01*
G02X411559Y1327829I0J1501D01*
G03X410983Y1328032I-374J-142D01*
G02X410225Y1327827I-758J1297D01*
G02Y1330831I0J1502D01*
G02X411629Y1329861I0J-1501D01*
G03X412205Y1329658I374J142D01*
G02X412697Y1329839I757J-1298D01*
G37*
G36*
G01X380569D02*
G03X380878Y1330356I-71J394D01*
G02X380805Y1330819I1429J463D01*
G02X383809I1502J0D01*
G02X382573Y1329341I-1502J0D01*
G03X382264Y1328824I71J-394D01*
G02X382337Y1328361I-1429J-463D01*
G02X380835Y1326859I-1502J0D01*
G02X379431Y1327829I0J1501D01*
G03X378855Y1328032I-374J-142D01*
G02X378097Y1327827I-758J1297D01*
G02Y1330831I0J1502D01*
G02X379501Y1329861I0J-1501D01*
G03X380077Y1329658I374J142D01*
G02X380569Y1329839I757J-1298D01*
G37*
G36*
G01X487567Y1326917D02*
G03Y1327527I-259J305D01*
G02X487037Y1328672I972J1145D01*
G02X488539Y1330174I1502J0D01*
G02X490031Y1328842I0J-1502D01*
G03X490502Y1328494I398J45D01*
G02X490778Y1328520I278J-1476D01*
G02X490984Y1328506I1J-1502D01*
G03X491425Y1328800I54J396D01*
G02X492878Y1329920I1453J-383D01*
G02X494380Y1328418I0J-1502D01*
G02X493850Y1327273I-1502J0D01*
G03Y1326663I259J-305D01*
G02Y1324373I-972J-1145D01*
G03Y1323763I259J-305D01*
G02X494380Y1322618I-972J-1145D01*
G02X492878Y1321116I-1502J0D01*
G02X491422Y1322248I0J1502D01*
G03X490960Y1322543I-388J-98D01*
G02X490678Y1322516I-284J1475D01*
G02X489180Y1323913I0J1502D01*
G03X488730Y1324282I-399J-28D01*
G02X488539Y1324270I-189J1490D01*
G02X487037Y1325772I0J1502D01*
G02X487567Y1326917I1502J0D01*
G37*
G36*
G01X455415Y1325966D02*
G03Y1326576I-259J305D01*
G02X454885Y1327721I972J1145D01*
G02X456387Y1329223I1502J0D01*
G02X457876Y1327919I0J-1502D01*
G03X458331Y1327577I396J53D01*
G02X458553Y1327593I219J-1486D01*
G02X458759Y1327579I1J-1502D01*
G03X459200Y1327873I54J396D01*
G02X460653Y1328993I1453J-383D01*
G02X462155Y1327491I0J-1502D01*
G02X461625Y1326346I-1502J0D01*
G03Y1325736I259J-305D01*
G02Y1323446I-972J-1145D01*
G03Y1322836I259J-305D01*
G02X462155Y1321691I-972J-1145D01*
G02X460653Y1320189I-1502J0D01*
G02X459197Y1321321I0J1502D01*
G03X458735Y1321616I-388J-98D01*
G02X458453Y1321589I-284J1475D01*
G02X457735Y1321772I0J1502D01*
G03X457159Y1321529I-191J-352D01*
G02X455747Y1320460I-1412J398D01*
G02X455171Y1320578I0J1467D01*
G03X454672Y1320417I-157J-368D01*
G02X452162I-1255J760D01*
G03X451663Y1320578I-342J-207D01*
G02X451087Y1320460I-576J1349D01*
G02X450511Y1320578I0J1467D01*
G03X450012Y1320417I-157J-368D01*
G02X448757Y1319710I-1255J760D01*
G02Y1322644I0J1467D01*
G02X449333Y1322526I0J-1467D01*
G03X449832Y1322687I157J368D01*
G02X452342I1255J-760D01*
G03X452841Y1322526I342J207D01*
G02X453417Y1322644I576J-1349D01*
G02X453993Y1322526I0J-1467D01*
G03X454492Y1322687I157J368D01*
G02X455102Y1323244I1254J-761D01*
G03X455233Y1323860I-176J359D01*
G02X454885Y1324821I1153J961D01*
G02X455415Y1325966I1502J0D01*
G37*
G36*
G01X423287D02*
G03Y1326576I-259J305D01*
G02X422757Y1327721I972J1145D01*
G02X424259Y1329223I1502J0D01*
G02X425748Y1327919I0J-1502D01*
G03X426203Y1327577I396J53D01*
G02X426425Y1327593I219J-1486D01*
G02X426631Y1327579I1J-1502D01*
G03X427072Y1327873I54J396D01*
G02X428525Y1328993I1453J-383D01*
G02X430027Y1327491I0J-1502D01*
G02X429497Y1326346I-1502J0D01*
G03Y1325736I259J-305D01*
G02Y1323446I-972J-1145D01*
G03Y1322836I259J-305D01*
G02X430027Y1321691I-972J-1145D01*
G02X428525Y1320189I-1502J0D01*
G02X427069Y1321321I0J1502D01*
G03X426607Y1321616I-388J-98D01*
G02X426325Y1321589I-284J1475D01*
G02X425607Y1321772I0J1502D01*
G03X425031Y1321529I-191J-352D01*
G02X423619Y1320460I-1412J398D01*
G02X423043Y1320578I0J1467D01*
G03X422544Y1320417I-157J-368D01*
G02X420034I-1255J760D01*
G03X419535Y1320578I-342J-207D01*
G02X418959Y1320460I-576J1349D01*
G02X418383Y1320578I0J1467D01*
G03X417884Y1320417I-157J-368D01*
G02X416629Y1319710I-1255J760D01*
G02Y1322644I0J1467D01*
G02X417205Y1322526I0J-1467D01*
G03X417704Y1322687I157J368D01*
G02X420214I1255J-760D01*
G03X420713Y1322526I342J207D01*
G02X421289Y1322644I576J-1349D01*
G02X421865Y1322526I0J-1467D01*
G03X422364Y1322687I157J368D01*
G02X422974Y1323244I1254J-761D01*
G03X423105Y1323860I-176J359D01*
G02X422757Y1324821I1153J961D01*
G02X423287Y1325966I1502J0D01*
G37*
G36*
G01X391159D02*
G03Y1326576I-259J305D01*
G02X390629Y1327721I972J1145D01*
G02X392131Y1329223I1502J0D01*
G02X393620Y1327919I0J-1502D01*
G03X394075Y1327577I396J53D01*
G02X394297Y1327593I219J-1486D01*
G02X394503Y1327579I1J-1502D01*
G03X394944Y1327873I54J396D01*
G02X396397Y1328993I1453J-383D01*
G02X397899Y1327491I0J-1502D01*
G02X397369Y1326346I-1502J0D01*
G03Y1325736I259J-305D01*
G02Y1323446I-972J-1145D01*
G03Y1322836I259J-305D01*
G02X397899Y1321691I-972J-1145D01*
G02X396397Y1320189I-1502J0D01*
G02X394941Y1321321I0J1502D01*
G03X394479Y1321616I-388J-98D01*
G02X394197Y1321589I-284J1475D01*
G02X393479Y1321772I0J1502D01*
G03X392903Y1321529I-191J-352D01*
G02X391491Y1320460I-1412J398D01*
G02X390915Y1320578I0J1467D01*
G03X390416Y1320417I-157J-368D01*
G02X387906I-1255J760D01*
G03X387407Y1320578I-342J-207D01*
G02X386831Y1320460I-576J1349D01*
G02X386255Y1320578I0J1467D01*
G03X385756Y1320417I-157J-368D01*
G02X384501Y1319710I-1255J760D01*
G02Y1322644I0J1467D01*
G02X385077Y1322526I0J-1467D01*
G03X385576Y1322687I157J368D01*
G02X388086I1255J-760D01*
G03X388585Y1322526I342J207D01*
G02X389161Y1322644I576J-1349D01*
G02X389737Y1322526I0J-1467D01*
G03X390236Y1322687I157J368D01*
G02X390846Y1323244I1254J-761D01*
G03X390977Y1323860I-176J359D01*
G02X390629Y1324821I1153J961D01*
G02X391159Y1325966I1502J0D01*
G37*
G36*
G01X484470Y1322687D02*
G03X484969Y1322526I342J207D01*
G02X485545Y1322644I576J-1349D01*
G02X486121Y1322526I0J-1467D01*
G03X486620Y1322687I157J368D01*
G02X487875Y1323394I1255J-760D01*
G02Y1320460I0J-1467D01*
G02X487299Y1320578I0J1467D01*
G03X486800Y1320417I-157J-368D01*
G02X484290I-1255J760D01*
G03X483791Y1320578I-342J-207D01*
G02X483215Y1320460I-576J1349D01*
G02X482639Y1320578I0J1467D01*
G03X482140Y1320417I-157J-368D01*
G02X480885Y1319710I-1255J760D01*
G02Y1322644I0J1467D01*
G02X481461Y1322526I0J-1467D01*
G03X481960Y1322687I157J368D01*
G02X484470I1255J-760D01*
G37*
G36*
G01X463059Y1318079D02*
G03Y1318605I-302J263D01*
G02X462689Y1319592I1131J987D01*
G02X465693I1502J0D01*
G02X465323Y1318605I-1501J0D01*
G03Y1318079I302J-263D01*
G02X465693Y1317092I-1131J-987D01*
G02X462689I-1502J0D01*
G02X463059Y1318079I1501J0D01*
G37*
G36*
G01X430931D02*
G03Y1318605I-302J263D01*
G02X430561Y1319592I1131J987D01*
G02X433565I1502J0D01*
G02X433195Y1318605I-1501J0D01*
G03Y1318079I302J-263D01*
G02X433565Y1317092I-1131J-987D01*
G02X430561I-1502J0D01*
G02X430931Y1318079I1501J0D01*
G37*
G36*
G01X398803D02*
G03Y1318605I-302J263D01*
G02X398433Y1319592I1131J987D01*
G02X401437I1502J0D01*
G02X401067Y1318605I-1501J0D01*
G03Y1318079I302J-263D01*
G02X401437Y1317092I-1131J-987D01*
G02X398433I-1502J0D01*
G02X398803Y1318079I1501J0D01*
G37*
G36*
G01X366609Y1318130D02*
G03X366632Y1318656I-289J276D01*
G02X366305Y1319592I1176J936D01*
G02X369309I1502J0D01*
G02X368892Y1318554I-1502J1D01*
G03X368869Y1318028I289J-276D01*
G02X369196Y1317092I-1176J-936D01*
G02X366192I-1502J0D01*
G02X366609Y1318130I1502J-1D01*
G37*
G36*
G01X406881Y855103D02*
X406079Y856493D01*
X405989Y856510D01*
G02X404928Y857789I240J1279D01*
G02X407530I1301J0D01*
G02X407456Y857357I-1301J1D01*
G01X407426Y857270D01*
X408228Y855880D01*
X408318Y855863D01*
G02X409379Y854584I-240J-1279D01*
G02X406777I-1301J0D01*
G02X406851Y855016I1301J-1D01*
G01X406881Y855103D01*
G37*
G36*
G01X414281D02*
X413479Y856493D01*
X413389Y856510D01*
G02X412328Y857789I240J1279D01*
G02X414930I1301J0D01*
G02X414856Y857357I-1301J1D01*
G01X414826Y857270D01*
X415628Y855880D01*
X415718Y855863D01*
G02X416779Y854584I-240J-1279D01*
G02X414177I-1301J0D01*
G02X414251Y855016I1301J-1D01*
G01X414281Y855103D01*
G37*
G36*
G01X421681D02*
X420879Y856493D01*
X420789Y856510D01*
G02X419728Y857789I240J1279D01*
G02X422330I1301J0D01*
G02X422256Y857357I-1301J1D01*
G01X422226Y857270D01*
X423028Y855880D01*
X423118Y855863D01*
G02X424179Y854584I-240J-1279D01*
G02X421577I-1301J0D01*
G02X421651Y855016I1301J-1D01*
G01X421681Y855103D01*
G37*
G36*
G01X429081D02*
X428279Y856493D01*
X428189Y856510D01*
G02X427128Y857789I240J1279D01*
G02X429730I1301J0D01*
G02X429656Y857357I-1301J1D01*
G01X429626Y857270D01*
X430428Y855880D01*
X430518Y855863D01*
G02X431579Y854584I-240J-1279D01*
G02X428977I-1301J0D01*
G02X429051Y855016I1301J-1D01*
G01X429081Y855103D01*
G37*
G36*
G01X402379Y859085D02*
X403181Y860474D01*
X403151Y860561D01*
G02X403077Y860993I1227J433D01*
G02X405679I1301J0D01*
G02X404618Y859714I-1301J0D01*
G01X404528Y859697D01*
X403726Y858308D01*
X403756Y858221D01*
G02X403830Y857789I-1227J-433D01*
G02X401228I-1301J0D01*
G02X402289Y859068I1301J0D01*
G01X402379Y859085D01*
G37*
G36*
G01X409779D02*
X410581Y860474D01*
X410551Y860561D01*
G02X410477Y860993I1227J433D01*
G02X413079I1301J0D01*
G02X412018Y859714I-1301J0D01*
G01X411928Y859697D01*
X411126Y858308D01*
X411156Y858221D01*
G02X411230Y857789I-1227J-433D01*
G02X408628I-1301J0D01*
G02X409689Y859068I1301J0D01*
G01X409779Y859085D01*
G37*
G36*
G01X417179D02*
X417981Y860474D01*
X417951Y860561D01*
G02X417877Y860993I1227J433D01*
G02X420479I1301J0D01*
G02X419418Y859714I-1301J0D01*
G01X419328Y859697D01*
X418526Y858308D01*
X418556Y858221D01*
G02X418630Y857789I-1227J-433D01*
G02X416028I-1301J0D01*
G02X417089Y859068I1301J0D01*
G01X417179Y859085D01*
G37*
G36*
G01X424579D02*
X425381Y860474D01*
X425351Y860561D01*
G02X425277Y860993I1227J433D01*
G02X427879I1301J0D01*
G02X426818Y859714I-1301J0D01*
G01X426728Y859697D01*
X425926Y858308D01*
X425956Y858221D01*
G02X426030Y857789I-1227J-433D01*
G02X423428I-1301J0D01*
G02X424489Y859068I1301J0D01*
G01X424579Y859085D01*
G37*
G36*
G01X431981D02*
X432782Y860474D01*
X432752Y860561D01*
G02X432678Y860993I1227J433D01*
G02X435280I1301J0D01*
G02X434219Y859714I-1301J0D01*
G01X434129Y859697D01*
X433326Y858307D01*
X433356Y858220D01*
G02X433430Y857789I-1227J-432D01*
G02X430828I-1301J0D01*
G02X431890Y859068I1301J0D01*
G01X431981Y859085D01*
G37*
G36*
G01X415330Y868697D02*
X416132Y870087D01*
X416102Y870174D01*
G02X416028Y870606I1227J433D01*
G02X418630I1301J0D01*
G02X417569Y869327I-1301J0D01*
G01X417479Y869310D01*
X416675Y867918D01*
X416706Y867832D01*
G02X416779Y867401I-1228J-430D01*
G02X414177I-1301J0D01*
G02X415239Y868680I1301J0D01*
G01X415330Y868697D01*
G37*
G36*
G01X422730D02*
X423532Y870087D01*
X423502Y870174D01*
G02X423428Y870606I1227J433D01*
G02X426030I1301J0D01*
G02X424969Y869327I-1301J0D01*
G01X424879Y869310D01*
X424075Y867918D01*
X424106Y867832D01*
G02X424179Y867401I-1228J-430D01*
G02X421577I-1301J0D01*
G02X422639Y868680I1301J0D01*
G01X422730Y868697D01*
G37*
G36*
G01X430130D02*
X430932Y870087D01*
X430902Y870174D01*
G02X430828Y870606I1227J433D01*
G02X433430I1301J0D01*
G02X432369Y869327I-1301J0D01*
G01X432279Y869310D01*
X431475Y867918D01*
X431506Y867832D01*
G02X431579Y867401I-1228J-430D01*
G02X428977I-1301J0D01*
G02X430039Y868680I1301J0D01*
G01X430130Y868697D01*
G37*
G36*
G01X403902Y987301D02*
G03Y987841I-294J270D01*
G02X403560Y988721I959J879D01*
G02X406162I1301J0D01*
G02X405820Y987841I-1301J-1D01*
G03Y987301I294J-270D01*
G02X406162Y986421I-959J-879D01*
G02X403560I-1301J0D01*
G02X403902Y987301I1301J1D01*
G37*
G36*
G01X404142Y993851D02*
G03Y994391I-294J270D01*
G02X403800Y995271I959J879D01*
G02X406402I1301J0D01*
G02X406060Y994391I-1301J-1D01*
G03Y993851I294J-270D01*
G02X406402Y992971I-959J-879D01*
G02X403800I-1301J0D01*
G02X404142Y993851I1301J1D01*
G37*
G36*
G01X403454Y1007298D02*
G03X403986Y1007547I151J370D01*
G02X405227Y1008457I1241J-391D01*
G02X406528Y1007156I0J-1301D01*
G02X406184Y1006275I-1300J0D01*
G03X406185Y1005732I294J-271D01*
G02X406532Y1004848I-954J-885D01*
G02X405231Y1003547I-1301J0D01*
G02X403957Y1004584I0J1301D01*
G03X403424Y1004877I-392J-81D01*
G02X402962Y1004792I-463J1216D01*
G02Y1007394I0J1301D01*
G02X403454Y1007298I1J-1301D01*
G37*
G36*
G01X403281Y965673D02*
G02X402529Y965434I-752J1062D01*
G02Y968036I0J1301D01*
G02X403760Y967155I0J-1301D01*
G03X404370Y966958I379J129D01*
G02X405122Y967197I752J-1062D01*
G02X406423Y965896I0J-1301D01*
G02X406081Y965016I-1301J-1D01*
G03Y964476I294J-270D01*
G02X406423Y963596I-959J-879D01*
G02X403821I-1301J0D01*
G02X404163Y964476I1301J1D01*
G03Y965016I-294J270D01*
G02X403891Y965476I960J878D01*
G03X403281Y965673I-379J-129D01*
G37*
G36*
G01X444930Y855880D02*
X445732Y857270D01*
X445702Y857357D01*
G02X445628Y857789I1227J433D01*
G02X448230I1301J0D01*
G02X447169Y856510I-1301J0D01*
G01X447079Y856493D01*
X446275Y855101D01*
X446306Y855015D01*
G02X446379Y854584I-1228J-430D01*
G02X443777I-1301J0D01*
G02X444839Y855863I1301J0D01*
G01X444930Y855880D01*
G37*
G36*
G01X452330D02*
X453132Y857270D01*
X453102Y857357D01*
G02X453028Y857789I1227J433D01*
G02X455630I1301J0D01*
G02X454569Y856510I-1301J0D01*
G01X454479Y856493D01*
X453675Y855101D01*
X453706Y855015D01*
G02X453779Y854584I-1228J-430D01*
G02X451177I-1301J0D01*
G02X452239Y855863I1301J0D01*
G01X452330Y855880D01*
G37*
G36*
G01X459730D02*
X460532Y857270D01*
X460502Y857357D01*
G02X460428Y857789I1227J433D01*
G02X463030I1301J0D01*
G02X461969Y856510I-1301J0D01*
G01X461879Y856493D01*
X461075Y855101D01*
X461106Y855015D01*
G02X461179Y854584I-1228J-430D01*
G02X458577I-1301J0D01*
G02X459639Y855863I1301J0D01*
G01X459730Y855880D01*
G37*
G36*
G01X467130D02*
X467932Y857270D01*
X467902Y857357D01*
G02X467828Y857789I1227J433D01*
G02X470430I1301J0D01*
G02X469369Y856510I-1301J0D01*
G01X469279Y856493D01*
X468475Y855101D01*
X468506Y855015D01*
G02X468579Y854584I-1228J-430D01*
G02X465977I-1301J0D01*
G02X467039Y855863I1301J0D01*
G01X467130Y855880D01*
G37*
G36*
G01X474530D02*
X475332Y857270D01*
X475302Y857357D01*
G02X475228Y857789I1227J433D01*
G02X477830I1301J0D01*
G02X476769Y856510I-1301J0D01*
G01X476679Y856493D01*
X475875Y855101D01*
X475906Y855015D01*
G02X475979Y854584I-1228J-430D01*
G02X473377I-1301J0D01*
G02X474439Y855863I1301J0D01*
G01X474530Y855880D01*
G37*
G36*
G01X481930D02*
X482732Y857270D01*
X482702Y857357D01*
G02X482628Y857789I1227J433D01*
G02X485230I1301J0D01*
G02X484169Y856510I-1301J0D01*
G01X484079Y856493D01*
X483275Y855101D01*
X483306Y855015D01*
G02X483379Y854584I-1228J-430D01*
G02X480777I-1301J0D01*
G02X481839Y855863I1301J0D01*
G01X481930Y855880D01*
G37*
G36*
G01X489330D02*
X490132Y857270D01*
X490102Y857357D01*
G02X490028Y857789I1227J433D01*
G02X492630I1301J0D01*
G02X491569Y856510I-1301J0D01*
G01X491479Y856493D01*
X490675Y855101D01*
X490706Y855015D01*
G02X490779Y854584I-1228J-430D01*
G02X488177I-1301J0D01*
G02X489239Y855863I1301J0D01*
G01X489330Y855880D01*
G37*
G36*
G01X496730D02*
X497532Y857270D01*
X497502Y857357D01*
G02X497428Y857789I1227J433D01*
G02X500030I1301J0D01*
G02X498969Y856510I-1301J0D01*
G01X498879Y856493D01*
X498075Y855101D01*
X498106Y855015D01*
G02X498179Y854584I-1228J-430D01*
G02X495577I-1301J0D01*
G02X496639Y855863I1301J0D01*
G01X496730Y855880D01*
G37*
G36*
G01X504130D02*
X504932Y857270D01*
X504902Y857357D01*
G02X504828Y857789I1227J433D01*
G02X507430I1301J0D01*
G02X506369Y856510I-1301J0D01*
G01X506279Y856493D01*
X505475Y855101D01*
X505506Y855015D01*
G02X505579Y854584I-1228J-430D01*
G02X502977I-1301J0D01*
G02X504039Y855863I1301J0D01*
G01X504130Y855880D01*
G37*
G36*
G01X511530D02*
X512332Y857270D01*
X512302Y857357D01*
G02X512228Y857789I1227J433D01*
G02X514830I1301J0D01*
G02X513769Y856510I-1301J0D01*
G01X513679Y856493D01*
X512875Y855101D01*
X512906Y855015D01*
G02X512979Y854584I-1228J-430D01*
G02X510377I-1301J0D01*
G02X511439Y855863I1301J0D01*
G01X511530Y855880D01*
G37*
G36*
G01X518930D02*
X519732Y857270D01*
X519702Y857357D01*
G02X519628Y857789I1227J433D01*
G02X522230I1301J0D01*
G02X521169Y856510I-1301J0D01*
G01X521079Y856493D01*
X520275Y855101D01*
X520306Y855015D01*
G02X520379Y854584I-1228J-430D01*
G02X517777I-1301J0D01*
G02X518839Y855863I1301J0D01*
G01X518930Y855880D01*
G37*
G36*
G01X442031Y858305D02*
X441228Y859697D01*
X441138Y859714D01*
G02X440077Y860993I240J1279D01*
G02X442679I1301J0D01*
G02X442605Y860561I-1301J1D01*
G01X442575Y860474D01*
X443376Y859085D01*
X443467Y859068D01*
G02X444530Y857789I-238J-1279D01*
G02X441928I-1301J0D01*
G02X442001Y858219I1301J0D01*
G01X442031Y858305D01*
G37*
G36*
G01X449432Y858306D02*
X448629Y859697D01*
X448539Y859714D01*
G02X447478Y860993I240J1279D01*
G02X450080I1301J0D01*
G02X450006Y860561I-1301J1D01*
G01X449976Y860474D01*
X450777Y859085D01*
X450868Y859068D01*
G02X451930Y857789I-239J-1279D01*
G02X449328I-1301J0D01*
G02X449401Y858220I1301J1D01*
G01X449432Y858306D01*
G37*
G36*
G01X456831Y858305D02*
X456028Y859697D01*
X455938Y859714D01*
G02X454877Y860993I240J1279D01*
G02X457479I1301J0D01*
G02X457405Y860561I-1301J1D01*
G01X457375Y860474D01*
X458176Y859085D01*
X458267Y859068D01*
G02X459330Y857789I-238J-1279D01*
G02X456728I-1301J0D01*
G02X456801Y858219I1301J0D01*
G01X456831Y858305D01*
G37*
G36*
G01X464231D02*
X463428Y859697D01*
X463338Y859714D01*
G02X462277Y860993I240J1279D01*
G02X464879I1301J0D01*
G02X464805Y860561I-1301J1D01*
G01X464775Y860474D01*
X465576Y859085D01*
X465667Y859068D01*
G02X466730Y857789I-238J-1279D01*
G02X464128I-1301J0D01*
G02X464201Y858219I1301J0D01*
G01X464231Y858305D01*
G37*
G36*
G01X471631D02*
X470828Y859697D01*
X470738Y859714D01*
G02X469677Y860993I240J1279D01*
G02X472279I1301J0D01*
G02X472205Y860561I-1301J1D01*
G01X472175Y860474D01*
X472976Y859085D01*
X473067Y859068D01*
G02X474130Y857789I-238J-1279D01*
G02X471528I-1301J0D01*
G02X471601Y858219I1301J0D01*
G01X471631Y858305D01*
G37*
G36*
G01X479031D02*
X478228Y859697D01*
X478138Y859714D01*
G02X477077Y860993I240J1279D01*
G02X479679I1301J0D01*
G02X479605Y860561I-1301J1D01*
G01X479575Y860474D01*
X480376Y859085D01*
X480467Y859068D01*
G02X481530Y857789I-238J-1279D01*
G02X478928I-1301J0D01*
G02X479001Y858219I1301J0D01*
G01X479031Y858305D01*
G37*
G36*
G01X486431D02*
X485628Y859697D01*
X485538Y859714D01*
G02X484477Y860993I240J1279D01*
G02X487079I1301J0D01*
G02X487005Y860561I-1301J1D01*
G01X486975Y860474D01*
X487776Y859085D01*
X487867Y859068D01*
G02X488930Y857789I-238J-1279D01*
G02X486328I-1301J0D01*
G02X486401Y858219I1301J0D01*
G01X486431Y858305D01*
G37*
G36*
G01X493831D02*
X493028Y859697D01*
X492938Y859714D01*
G02X491877Y860993I240J1279D01*
G02X494479I1301J0D01*
G02X494405Y860561I-1301J1D01*
G01X494375Y860474D01*
X495176Y859085D01*
X495267Y859068D01*
G02X496330Y857789I-238J-1279D01*
G02X493728I-1301J0D01*
G02X493801Y858219I1301J0D01*
G01X493831Y858305D01*
G37*
G36*
G01X501231D02*
X500428Y859697D01*
X500338Y859714D01*
G02X499277Y860993I240J1279D01*
G02X501879I1301J0D01*
G02X501805Y860561I-1301J1D01*
G01X501775Y860474D01*
X502576Y859085D01*
X502667Y859068D01*
G02X503730Y857789I-238J-1279D01*
G02X501128I-1301J0D01*
G02X501201Y858219I1301J0D01*
G01X501231Y858305D01*
G37*
G36*
G01X508631D02*
X507828Y859697D01*
X507738Y859714D01*
G02X506677Y860993I240J1279D01*
G02X509279I1301J0D01*
G02X509205Y860561I-1301J1D01*
G01X509175Y860474D01*
X509976Y859085D01*
X510067Y859068D01*
G02X511130Y857789I-238J-1279D01*
G02X508528I-1301J0D01*
G02X508601Y858219I1301J0D01*
G01X508631Y858305D01*
G37*
G36*
G01X516031D02*
X515228Y859697D01*
X515138Y859714D01*
G02X514077Y860993I240J1279D01*
G02X516679I1301J0D01*
G02X516605Y860561I-1301J1D01*
G01X516575Y860474D01*
X517376Y859085D01*
X517467Y859068D01*
G02X518530Y857789I-238J-1279D01*
G02X515928I-1301J0D01*
G02X516001Y858219I1301J0D01*
G01X516031Y858305D01*
G37*
G36*
G01X523431D02*
X522628Y859697D01*
X522538Y859714D01*
G02X521477Y860993I240J1279D01*
G02X524079I1301J0D01*
G02X524005Y860561I-1301J1D01*
G01X523975Y860474D01*
X524776Y859085D01*
X524867Y859068D01*
G02X525930Y857789I-238J-1279D01*
G02X523328I-1301J0D01*
G02X523401Y858219I1301J0D01*
G01X523431Y858305D01*
G37*
G36*
G01X444930Y868697D02*
X445732Y870087D01*
X445702Y870174D01*
G02X445628Y870606I1227J433D01*
G02X448230I1301J0D01*
G02X447169Y869327I-1301J0D01*
G01X447079Y869310D01*
X446275Y867918D01*
X446306Y867832D01*
G02X446379Y867401I-1228J-430D01*
G02X443777I-1301J0D01*
G02X444839Y868680I1301J0D01*
G01X444930Y868697D01*
G37*
G36*
G01X452330D02*
X453132Y870087D01*
X453102Y870174D01*
G02X453028Y870606I1227J433D01*
G02X455630I1301J0D01*
G02X454569Y869327I-1301J0D01*
G01X454479Y869310D01*
X453675Y867918D01*
X453706Y867832D01*
G02X453779Y867401I-1228J-430D01*
G02X451177I-1301J0D01*
G02X452239Y868680I1301J0D01*
G01X452330Y868697D01*
G37*
G36*
G01X459730D02*
X460532Y870087D01*
X460502Y870174D01*
G02X460428Y870606I1227J433D01*
G02X463030I1301J0D01*
G02X461969Y869327I-1301J0D01*
G01X461879Y869310D01*
X461075Y867918D01*
X461106Y867832D01*
G02X461179Y867401I-1228J-430D01*
G02X458577I-1301J0D01*
G02X459639Y868680I1301J0D01*
G01X459730Y868697D01*
G37*
G36*
G01X467130D02*
X467932Y870087D01*
X467902Y870174D01*
G02X467828Y870606I1227J433D01*
G02X470430I1301J0D01*
G02X469369Y869327I-1301J0D01*
G01X469279Y869310D01*
X468475Y867918D01*
X468506Y867832D01*
G02X468579Y867401I-1228J-430D01*
G02X465977I-1301J0D01*
G02X467039Y868680I1301J0D01*
G01X467130Y868697D01*
G37*
G36*
G01X474530D02*
X475332Y870087D01*
X475302Y870174D01*
G02X475228Y870606I1227J433D01*
G02X477830I1301J0D01*
G02X476769Y869327I-1301J0D01*
G01X476679Y869310D01*
X475875Y867918D01*
X475906Y867832D01*
G02X475979Y867401I-1228J-430D01*
G02X473377I-1301J0D01*
G02X474439Y868680I1301J0D01*
G01X474530Y868697D01*
G37*
G36*
G01X481930D02*
X482732Y870087D01*
X482702Y870174D01*
G02X482628Y870606I1227J433D01*
G02X485230I1301J0D01*
G02X484169Y869327I-1301J0D01*
G01X484079Y869310D01*
X483275Y867918D01*
X483306Y867832D01*
G02X483379Y867401I-1228J-430D01*
G02X480777I-1301J0D01*
G02X481839Y868680I1301J0D01*
G01X481930Y868697D01*
G37*
G36*
G01X489330D02*
X490132Y870087D01*
X490102Y870174D01*
G02X490028Y870606I1227J433D01*
G02X492630I1301J0D01*
G02X491569Y869327I-1301J0D01*
G01X491479Y869310D01*
X490675Y867918D01*
X490706Y867832D01*
G02X490779Y867401I-1228J-430D01*
G02X488177I-1301J0D01*
G02X489239Y868680I1301J0D01*
G01X489330Y868697D01*
G37*
G36*
G01X496730D02*
X497532Y870087D01*
X497502Y870174D01*
G02X497428Y870606I1227J433D01*
G02X500030I1301J0D01*
G02X498969Y869327I-1301J0D01*
G01X498879Y869310D01*
X498075Y867918D01*
X498106Y867832D01*
G02X498179Y867401I-1228J-430D01*
G02X495577I-1301J0D01*
G02X496639Y868680I1301J0D01*
G01X496730Y868697D01*
G37*
G36*
G01X504130D02*
X504932Y870087D01*
X504902Y870174D01*
G02X504828Y870606I1227J433D01*
G02X507430I1301J0D01*
G02X506369Y869327I-1301J0D01*
G01X506279Y869310D01*
X505475Y867918D01*
X505506Y867832D01*
G02X505579Y867401I-1228J-430D01*
G02X502977I-1301J0D01*
G02X504039Y868680I1301J0D01*
G01X504130Y868697D01*
G37*
G36*
G01X511530D02*
X512332Y870087D01*
X512302Y870174D01*
G02X512228Y870606I1227J433D01*
G02X514830I1301J0D01*
G02X513769Y869327I-1301J0D01*
G01X513679Y869310D01*
X512875Y867918D01*
X512906Y867832D01*
G02X512979Y867401I-1228J-430D01*
G02X510377I-1301J0D01*
G02X511439Y868680I1301J0D01*
G01X511530Y868697D01*
G37*
G36*
G01X518930D02*
X519732Y870087D01*
X519702Y870174D01*
G02X519628Y870606I1227J433D01*
G02X522230I1301J0D01*
G02X521169Y869327I-1301J0D01*
G01X521079Y869310D01*
X520275Y867918D01*
X520306Y867832D01*
G02X520379Y867401I-1228J-430D01*
G02X517777I-1301J0D01*
G02X518839Y868680I1301J0D01*
G01X518930Y868697D01*
G37*
G36*
G01X442031Y871122D02*
X441228Y872514D01*
X441138Y872531D01*
G02X440077Y873810I240J1279D01*
G02X442679I1301J0D01*
G02X442605Y873378I-1301J1D01*
G01X442575Y873291D01*
X443376Y871902D01*
X443467Y871885D01*
G02X444530Y870606I-238J-1279D01*
G02X441928I-1301J0D01*
G02X442001Y871036I1301J0D01*
G01X442031Y871122D01*
G37*
G36*
G01X449432Y871123D02*
X448629Y872514D01*
X448539Y872531D01*
G02X447478Y873810I240J1279D01*
G02X450080I1301J0D01*
G02X450006Y873378I-1301J1D01*
G01X449976Y873291D01*
X450777Y871902D01*
X450868Y871885D01*
G02X451930Y870606I-239J-1279D01*
G02X449328I-1301J0D01*
G02X449401Y871037I1301J1D01*
G01X449432Y871123D01*
G37*
G36*
G01X456831Y871122D02*
X456028Y872514D01*
X455938Y872531D01*
G02X454877Y873810I240J1279D01*
G02X457479I1301J0D01*
G02X457405Y873378I-1301J1D01*
G01X457375Y873291D01*
X458176Y871902D01*
X458267Y871885D01*
G02X459330Y870606I-238J-1279D01*
G02X456728I-1301J0D01*
G02X456801Y871036I1301J0D01*
G01X456831Y871122D01*
G37*
G36*
G01X464231D02*
X463428Y872514D01*
X463338Y872531D01*
G02X462277Y873810I240J1279D01*
G02X464879I1301J0D01*
G02X464805Y873378I-1301J1D01*
G01X464775Y873291D01*
X465576Y871902D01*
X465667Y871885D01*
G02X466730Y870606I-238J-1279D01*
G02X464128I-1301J0D01*
G02X464201Y871036I1301J0D01*
G01X464231Y871122D01*
G37*
G36*
G01X479031D02*
X478228Y872514D01*
X478138Y872531D01*
G02X477077Y873810I240J1279D01*
G02X479679I1301J0D01*
G02X479605Y873378I-1301J1D01*
G01X479575Y873291D01*
X480376Y871902D01*
X480467Y871885D01*
G02X481530Y870606I-238J-1279D01*
G02X478928I-1301J0D01*
G02X479001Y871036I1301J0D01*
G01X479031Y871122D01*
G37*
G36*
G01X486431D02*
X485628Y872514D01*
X485538Y872531D01*
G02X484477Y873810I240J1279D01*
G02X487079I1301J0D01*
G02X487005Y873378I-1301J1D01*
G01X486975Y873291D01*
X487776Y871902D01*
X487867Y871885D01*
G02X488930Y870606I-238J-1279D01*
G02X486328I-1301J0D01*
G02X486401Y871036I1301J0D01*
G01X486431Y871122D01*
G37*
G36*
G01X493831D02*
X493028Y872514D01*
X492938Y872531D01*
G02X491877Y873810I240J1279D01*
G02X494479I1301J0D01*
G02X494405Y873378I-1301J1D01*
G01X494375Y873291D01*
X495176Y871902D01*
X495267Y871885D01*
G02X496330Y870606I-238J-1279D01*
G02X493728I-1301J0D01*
G02X493801Y871036I1301J0D01*
G01X493831Y871122D01*
G37*
G36*
G01X501231D02*
X500428Y872514D01*
X500338Y872531D01*
G02X499277Y873810I240J1279D01*
G02X501879I1301J0D01*
G02X501805Y873378I-1301J1D01*
G01X501775Y873291D01*
X502576Y871902D01*
X502667Y871885D01*
G02X503730Y870606I-238J-1279D01*
G02X501128I-1301J0D01*
G02X501201Y871036I1301J0D01*
G01X501231Y871122D01*
G37*
G36*
G01X508631D02*
X507828Y872514D01*
X507738Y872531D01*
G02X506677Y873810I240J1279D01*
G02X509279I1301J0D01*
G02X509205Y873378I-1301J1D01*
G01X509175Y873291D01*
X509976Y871902D01*
X510067Y871885D01*
G02X511130Y870606I-238J-1279D01*
G02X508528I-1301J0D01*
G02X508601Y871036I1301J0D01*
G01X508631Y871122D01*
G37*
G36*
G01X516031D02*
X515228Y872514D01*
X515138Y872531D01*
G02X514077Y873810I240J1279D01*
G02X516679I1301J0D01*
G02X516605Y873378I-1301J1D01*
G01X516575Y873291D01*
X517376Y871902D01*
X517467Y871885D01*
G02X518530Y870606I-238J-1279D01*
G02X515928I-1301J0D01*
G02X516001Y871036I1301J0D01*
G01X516031Y871122D01*
G37*
G36*
G01X523431D02*
X522629Y872514D01*
X522538Y872531D01*
G02X521477Y873810I240J1279D01*
G02X524079I1301J0D01*
G02X524005Y873378I-1301J1D01*
G01X523975Y873291D01*
X524776Y871902D01*
X524867Y871885D01*
G02X525930Y870606I-238J-1279D01*
G02X523328I-1301J0D01*
G02X523401Y871035I1301J-1D01*
G01X523431Y871122D01*
G37*
G36*
G01X443881Y880737D02*
X443079Y882127D01*
X442989Y882144D01*
G02X441928Y883423I240J1279D01*
G02X444530I1301J0D01*
G02X444456Y882991I-1301J1D01*
G01X444426Y882904D01*
X445227Y881515D01*
X445318Y881498D01*
G02X446379Y880219I-240J-1279D01*
G02X443777I-1301J0D01*
G02X443851Y880651I1301J-1D01*
G01X443881Y880737D01*
G37*
G36*
G01X451282Y880736D02*
X450479Y882127D01*
X450389Y882144D01*
G02X449328Y883423I240J1279D01*
G02X451930I1301J0D01*
G02X451856Y882991I-1301J1D01*
G01X451826Y882904D01*
X452627Y881515D01*
X452718Y881498D01*
G02X453780Y880219I-239J-1279D01*
G02X451178I-1301J0D01*
G02X451251Y880650I1301J1D01*
G01X451282Y880736D01*
G37*
G36*
G01X458681Y880737D02*
X457879Y882127D01*
X457789Y882144D01*
G02X456728Y883423I240J1279D01*
G02X459330I1301J0D01*
G02X459256Y882991I-1301J1D01*
G01X459226Y882904D01*
X460027Y881515D01*
X460118Y881498D01*
G02X461179Y880219I-240J-1279D01*
G02X458577I-1301J0D01*
G02X458651Y880651I1301J-1D01*
G01X458681Y880737D01*
G37*
G36*
G01X466081D02*
X465279Y882127D01*
X465189Y882144D01*
G02X464128Y883423I240J1279D01*
G02X466730I1301J0D01*
G02X466656Y882991I-1301J1D01*
G01X466626Y882904D01*
X467427Y881515D01*
X467518Y881498D01*
G02X468579Y880219I-240J-1279D01*
G02X465977I-1301J0D01*
G02X466051Y880651I1301J-1D01*
G01X466081Y880737D01*
G37*
G36*
G01X473481D02*
X472679Y882127D01*
X472589Y882144D01*
G02X471528Y883423I240J1279D01*
G02X474130I1301J0D01*
G02X474056Y882991I-1301J1D01*
G01X474026Y882904D01*
X474827Y881515D01*
X474918Y881498D01*
G02X475979Y880219I-240J-1279D01*
G02X473377I-1301J0D01*
G02X473451Y880651I1301J-1D01*
G01X473481Y880737D01*
G37*
G36*
G01X480881D02*
X480079Y882127D01*
X479989Y882144D01*
G02X478928Y883423I240J1279D01*
G02X481530I1301J0D01*
G02X481456Y882991I-1301J1D01*
G01X481426Y882904D01*
X482227Y881515D01*
X482318Y881498D01*
G02X483379Y880219I-240J-1279D01*
G02X480777I-1301J0D01*
G02X480851Y880651I1301J-1D01*
G01X480881Y880737D01*
G37*
G36*
G01X488281D02*
X487479Y882127D01*
X487389Y882144D01*
G02X486328Y883423I240J1279D01*
G02X488930I1301J0D01*
G02X488856Y882991I-1301J1D01*
G01X488826Y882904D01*
X489627Y881515D01*
X489718Y881498D01*
G02X490779Y880219I-240J-1279D01*
G02X488177I-1301J0D01*
G02X488251Y880651I1301J-1D01*
G01X488281Y880737D01*
G37*
G36*
G01X495681D02*
X494879Y882127D01*
X494789Y882144D01*
G02X493728Y883423I240J1279D01*
G02X496330I1301J0D01*
G02X496256Y882991I-1301J1D01*
G01X496226Y882904D01*
X497027Y881515D01*
X497118Y881498D01*
G02X498179Y880219I-240J-1279D01*
G02X495577I-1301J0D01*
G02X495651Y880651I1301J-1D01*
G01X495681Y880737D01*
G37*
G36*
G01X503081D02*
X502279Y882127D01*
X502189Y882144D01*
G02X501128Y883423I240J1279D01*
G02X503730I1301J0D01*
G02X503656Y882991I-1301J1D01*
G01X503626Y882904D01*
X504427Y881515D01*
X504518Y881498D01*
G02X505579Y880219I-240J-1279D01*
G02X502977I-1301J0D01*
G02X503051Y880651I1301J-1D01*
G01X503081Y880737D01*
G37*
G36*
G01X510481D02*
X509679Y882127D01*
X509589Y882144D01*
G02X508528Y883423I240J1279D01*
G02X511130I1301J0D01*
G02X511056Y882991I-1301J1D01*
G01X511026Y882904D01*
X511827Y881515D01*
X511918Y881498D01*
G02X512979Y880219I-240J-1279D01*
G02X510377I-1301J0D01*
G02X510451Y880651I1301J-1D01*
G01X510481Y880737D01*
G37*
G36*
G01X517881D02*
X517080Y882127D01*
X516989Y882144D01*
G02X515928Y883423I240J1279D01*
G02X518530I1301J0D01*
G02X518456Y882991I-1301J1D01*
G01X518426Y882904D01*
X519227Y881515D01*
X519318Y881498D01*
G02X520379Y880219I-240J-1279D01*
G02X517777I-1301J0D01*
G02X517851Y880650I1301J-1D01*
G01X517881Y880737D01*
G37*
G36*
G01X525282Y880736D02*
X524480Y882127D01*
X524389Y882144D01*
G02X523328Y883423I240J1279D01*
G02X525930I1301J0D01*
G02X525856Y882991I-1301J1D01*
G01X525826Y882904D01*
X526627Y881515D01*
X526718Y881498D01*
G02X527780Y880219I-239J-1279D01*
G02X525178I-1301J0D01*
G02X525251Y880650I1301J1D01*
G01X525282Y880736D01*
G37*
G36*
G01X446779Y884719D02*
X447581Y886108D01*
X447551Y886195D01*
G02X447477Y886627I1227J433D01*
G02X450079I1301J0D01*
G02X449018Y885348I-1301J0D01*
G01X448928Y885331D01*
X448126Y883942D01*
X448156Y883855D01*
G02X448230Y883423I-1227J-433D01*
G02X445628I-1301J0D01*
G02X446689Y884702I1301J0D01*
G01X446779Y884719D01*
G37*
G36*
G01X454179D02*
X454981Y886108D01*
X454951Y886195D01*
G02X454877Y886627I1227J433D01*
G02X457479I1301J0D01*
G02X456418Y885348I-1301J0D01*
G01X456328Y885331D01*
X455526Y883942D01*
X455556Y883855D01*
G02X455630Y883423I-1227J-433D01*
G02X453028I-1301J0D01*
G02X454089Y884702I1301J0D01*
G01X454179Y884719D01*
G37*
G36*
G01X461579D02*
X462381Y886108D01*
X462351Y886195D01*
G02X462277Y886627I1227J433D01*
G02X464879I1301J0D01*
G02X463818Y885348I-1301J0D01*
G01X463728Y885331D01*
X462926Y883942D01*
X462956Y883855D01*
G02X463030Y883423I-1227J-433D01*
G02X460428I-1301J0D01*
G02X461489Y884702I1301J0D01*
G01X461579Y884719D01*
G37*
G36*
G01X468979D02*
X469781Y886108D01*
X469751Y886195D01*
G02X469677Y886627I1227J433D01*
G02X472279I1301J0D01*
G02X471218Y885348I-1301J0D01*
G01X471128Y885331D01*
X470326Y883942D01*
X470356Y883855D01*
G02X470430Y883423I-1227J-433D01*
G02X467828I-1301J0D01*
G02X468889Y884702I1301J0D01*
G01X468979Y884719D01*
G37*
G36*
G01X476379D02*
X477181Y886108D01*
X477151Y886195D01*
G02X477077Y886627I1227J433D01*
G02X479679I1301J0D01*
G02X478618Y885348I-1301J0D01*
G01X478528Y885331D01*
X477726Y883942D01*
X477756Y883855D01*
G02X477830Y883423I-1227J-433D01*
G02X475228I-1301J0D01*
G02X476289Y884702I1301J0D01*
G01X476379Y884719D01*
G37*
G36*
G01X483779D02*
X484581Y886108D01*
X484551Y886195D01*
G02X484477Y886627I1227J433D01*
G02X487079I1301J0D01*
G02X486018Y885348I-1301J0D01*
G01X485928Y885331D01*
X485126Y883942D01*
X485156Y883855D01*
G02X485230Y883423I-1227J-433D01*
G02X482628I-1301J0D01*
G02X483689Y884702I1301J0D01*
G01X483779Y884719D01*
G37*
G36*
G01X491179D02*
X491981Y886108D01*
X491951Y886195D01*
G02X491877Y886627I1227J433D01*
G02X494479I1301J0D01*
G02X493418Y885348I-1301J0D01*
G01X493328Y885331D01*
X492526Y883942D01*
X492556Y883855D01*
G02X492630Y883423I-1227J-433D01*
G02X490028I-1301J0D01*
G02X491089Y884702I1301J0D01*
G01X491179Y884719D01*
G37*
G36*
G01X498579D02*
X499381Y886108D01*
X499351Y886195D01*
G02X499277Y886627I1227J433D01*
G02X501879I1301J0D01*
G02X500818Y885348I-1301J0D01*
G01X500728Y885331D01*
X499926Y883942D01*
X499956Y883855D01*
G02X500030Y883423I-1227J-433D01*
G02X497428I-1301J0D01*
G02X498489Y884702I1301J0D01*
G01X498579Y884719D01*
G37*
G36*
G01X505979D02*
X506781Y886108D01*
X506751Y886195D01*
G02X506677Y886627I1227J433D01*
G02X509279I1301J0D01*
G02X508218Y885348I-1301J0D01*
G01X508128Y885331D01*
X507326Y883942D01*
X507356Y883855D01*
G02X507430Y883423I-1227J-433D01*
G02X504828I-1301J0D01*
G02X505889Y884702I1301J0D01*
G01X505979Y884719D01*
G37*
G36*
G01X513379D02*
X514181Y886108D01*
X514151Y886195D01*
G02X514077Y886627I1227J433D01*
G02X516679I1301J0D01*
G02X515618Y885348I-1301J0D01*
G01X515528Y885331D01*
X514726Y883942D01*
X514756Y883855D01*
G02X514830Y883423I-1227J-433D01*
G02X512228I-1301J0D01*
G02X513289Y884702I1301J0D01*
G01X513379Y884719D01*
G37*
G36*
G01X520779D02*
X521581Y886108D01*
X521551Y886195D01*
G02X521477Y886627I1227J433D01*
G02X524079I1301J0D01*
G02X523018Y885348I-1301J0D01*
G01X522928Y885331D01*
X522126Y883942D01*
X522156Y883855D01*
G02X522230Y883423I-1227J-433D01*
G02X519628I-1301J0D01*
G02X520689Y884702I1301J0D01*
G01X520779Y884719D01*
G37*
G36*
G01X475326Y965506D02*
G03Y966046I-294J270D01*
G02X474984Y966926I959J879D01*
G02X477586I1301J0D01*
G02X477244Y966046I-1301J-1D01*
G03Y965506I294J-270D01*
G02X477520Y965036I-959J-879D01*
G03X478012Y964778I380J126D01*
G02X478378Y964831I368J-1248D01*
G02Y962229I0J-1301D01*
G02X478035Y962275I0J1302D01*
G03X477542Y961992I-106J-386D01*
G02X477244Y961446I-1258J332D01*
G03Y960906I294J-270D01*
G02X477586Y960026I-959J-879D01*
G02X474984I-1301J0D01*
G02X475326Y960906I1301J1D01*
G03Y961446I-294J270D01*
G02X474984Y962326I959J879D01*
G02X475326Y963206I1301J1D01*
G03Y963746I-294J270D01*
G02X474984Y964626I959J879D01*
G02X475326Y965506I1301J1D01*
G37*
G36*
G01X477097Y976118D02*
G03X476583Y976429I-394J-70D01*
G02X476192Y976369I-391J1241D01*
G02Y978971I0J1301D01*
G02X477473Y977899I0J-1301D01*
G03X477987Y977588I394J70D01*
G02X478378Y977648I391J-1241D01*
G02Y975046I0J-1301D01*
G02X477097Y976118I0J1301D01*
G37*
G36*
G01X475326Y988506D02*
G03Y989046I-294J270D01*
G02X474984Y989926I959J879D01*
G02X477586I1301J0D01*
G02X477244Y989046I-1301J-1D01*
G03Y988506I294J-270D01*
G02X477586Y987626I-959J-879D01*
G02X474984I-1301J0D01*
G02X475326Y988506I1301J1D01*
G37*
G36*
G01Y995406D02*
G03Y995946I-294J270D01*
G02X474984Y996826I959J879D01*
G02X477586I1301J0D01*
G02X477244Y995946I-1301J-1D01*
G03Y995406I294J-270D01*
G02X477586Y994526I-959J-879D01*
G02X474984I-1301J0D01*
G02X475326Y995406I1301J1D01*
G37*
G36*
G01X477107Y982480D02*
G02X477077Y982756I1271J278D01*
G02X478378Y981455I1301J0D01*
G02X478087Y981488I0J1301D01*
G03X477606Y981013I-90J-390D01*
G02X477636Y980737I-1271J-278D01*
G02X476335Y982038I-1301J0D01*
G02X476626Y982005I0J-1301D01*
G03X477107Y982480I90J390D01*
G37*
G36*
G01X475326Y1005146D02*
G02X474984Y1006026I959J879D01*
G02X477586I1301J0D01*
G02X477244Y1005146I-1301J-1D01*
G03Y1004606I294J-270D01*
G02X477506Y1004175I-960J-879D01*
G03X478100Y1003978I375J138D01*
G02X478811Y1004189I710J-1090D01*
G02Y1001587I0J-1301D01*
G02X477590Y1002439I0J1301D01*
G03X476996Y1002636I-375J-138D01*
G02X476285Y1002425I-710J1090D01*
G02X474984Y1003726I0J1301D01*
G02X475326Y1004606I1301J1D01*
G03Y1005146I-294J270D01*
G37*
G36*
G01X472408Y1035232D02*
G03X471884Y1035373I-338J-213D01*
G02X471282Y1035225I-603J1153D01*
G02Y1037827I0J1301D01*
G02X472381Y1037222I0J-1301D01*
G03X472905Y1037081I338J213D01*
G02X473507Y1037229I603J-1153D01*
G02Y1034627I0J-1301D01*
G02X472408Y1035232I0J1301D01*
G37*
G36*
G01X798520Y762052D02*
G03X798532Y762607I-282J284D01*
G02X798135Y763625I1105J1017D01*
G02X801139I1502J0D01*
G02X800694Y762558I-1502J0D01*
G03X800682Y762003I282J-284D01*
G02X801079Y760985I-1105J-1017D01*
G02X799577Y759483I-1502J0D01*
G02X798370Y760091I0J1502D01*
G03X797766Y760135I-321J-239D01*
G02X796702Y759693I-1064J1060D01*
G02X795653Y760120I0J1502D01*
G03X795118Y760141I-279J-287D01*
G02X794157Y759793I-961J1153D01*
G02Y762797I0J1502D01*
G02X795206Y762370I0J-1502D01*
G03X795741Y762349I279J287D01*
G02X796702Y762697I961J-1153D01*
G02X797909Y762089I0J-1502D01*
G03X798513Y762045I321J239D01*
G02X798520Y762052I1065J-1058D01*
G37*
G36*
G01X892890Y913918D02*
G03X892457Y914377I-395J61D01*
G02X892317Y914370I-145J1495D01*
G02X893819Y915872I0J1502D01*
G02X893802Y915646I-1502J-1D01*
G03X894235Y915187I395J-61D01*
G02X894375Y915194I145J-1495D01*
G02X892873Y913692I0J-1502D01*
G02X892890Y913918I1502J1D01*
G37*
G36*
G01X898329Y974943D02*
G03X898121Y975151I-200J8D01*
G02X898062Y975150I-55J1501D01*
G02Y978154I0J1502D01*
G02X899560Y976755I0J-1502D01*
G03X899932Y976383I399J27D01*
G02X901332Y974884I-103J-1499D01*
G01Y971484D01*
G02X899932Y969985I-1503J0D01*
G03X899560Y969613I27J-399D01*
G02X898062Y968214I-1498J103D01*
G02Y971218I0J1502D01*
G02X898121Y971217I4J-1502D01*
G03X898329Y971425I8J200D01*
G02X898328Y971484I1501J55D01*
G01Y974884D01*
G02X898329Y974943I1502J4D01*
G37*
G36*
G01X1048476Y1258014D02*
G03X1047882Y1258124I-345J-203D01*
G02X1047010Y1257820I-872J1099D01*
G02Y1260624I0J1402D01*
G02X1048217Y1259935I0J-1402D01*
G03X1048811Y1259825I345J203D01*
G02X1049683Y1260129I872J-1099D01*
G02Y1257325I0J-1402D01*
G02X1048476Y1258014I0J1402D01*
G37*
G36*
G01X665656Y1262962D02*
G03X665635Y1263493I-309J254D01*
G02X665244Y1264464I1010J971D01*
G02X668048I1402J0D01*
G02X667731Y1263576I-1402J0D01*
G03X667752Y1263045I309J-254D01*
G02X668143Y1262074I-1010J-971D01*
G02X665339I-1402J0D01*
G02X665656Y1262962I1402J0D01*
G37*
G36*
G01X814212Y765846D02*
G02X813839Y766798I1028J952D01*
G02X816643I1402J0D01*
G02X815919Y765571I-1402J0D01*
G03X815830Y764938I194J-350D01*
G02X816272Y763874I-1060J-1064D01*
G02X815729Y762718I-1502J0D01*
G03X815735Y762097I255J-308D01*
G02X816302Y760922I-934J-1175D01*
G02X813298I-1502J0D01*
G02X813841Y762078I1502J0D01*
G03X813835Y762699I-255J308D01*
G02X813268Y763874I934J1175D01*
G02X814097Y765217I1502J0D01*
G03X814212Y765846I-179J358D01*
G37*
G36*
G01X783785Y765900D02*
G02X782515Y765200I-1270J802D01*
G02Y768204I0J1502D01*
G02X783731Y767583I0J-1501D01*
G03X784385Y767591I324J235D01*
G02X785541Y768200I1156J-793D01*
G02Y765396I0J-1402D01*
G02X784438Y765933I0J1401D01*
G03X783785Y765900I-315J-247D01*
G37*
G36*
G01X839859Y766026D02*
G02X838587Y765323I-1272J799D01*
G02Y768327I0J1502D01*
G02X839874Y767600I0J-1503D01*
G03X840555Y767594I342J207D01*
G02X841827Y768297I1272J-799D01*
G02X843103Y767588I0J-1503D01*
G03X843775Y767577I340J211D01*
G02X844941Y768200I1166J-780D01*
G02Y765396I0J-1402D01*
G02X843777Y766017I0J1401D01*
G03X843104Y766005I-333J-222D01*
G02X841827Y765293I-1277J789D01*
G02X840540Y766020I0J1503D01*
G03X839859Y766026I-342J-207D01*
G37*
G36*
G01X877334Y878677D02*
G02X876690Y879910I858J1233D01*
G02X879694I1502J0D01*
G02X879018Y878656I-1501J0D01*
G03X879010Y877993I220J-334D01*
G02X879654Y876760I-858J-1233D01*
G02X876650I-1502J0D01*
G02X877326Y878014I1501J0D01*
G03X877334Y878677I-220J334D01*
G37*
G36*
G01X938259Y987510D02*
G02X938238Y987762I1481J250D01*
G02X939740Y986260I1502J0D01*
G02X939055Y986425I-1J1502D01*
G03X938479Y986002I-182J-356D01*
G02X938500Y985750I-1481J-250D01*
G02X936998Y987252I-1502J0D01*
G02X937683Y987087I1J-1502D01*
G03X938259Y987510I182J356D01*
G37*
G36*
G01X843541Y1258659D02*
G02X843539Y1258727I1400J75D01*
G02X844941Y1257325I1402J0D01*
G02X844543Y1257383I1J1402D01*
G03X844030Y1256980I-113J-384D01*
G02X844032Y1256912I-1400J-75D01*
G02X842630Y1258314I-1402J0D01*
G02X843028Y1258256I-1J-1402D01*
G03X843541Y1258659I113J384D01*
G37*
G36*
G01X1077533Y1258103D02*
G02X1076520Y1257670I-1013J968D01*
G02Y1260474I0J1402D01*
G02X1077734Y1259773I0J-1402D01*
G03X1078370Y1259696I347J199D01*
G02X1079383Y1260129I1013J-968D01*
G02Y1257325I0J-1402D01*
G02X1078169Y1258026I0J1402D01*
G03X1077533Y1258103I-347J-199D01*
G37*
G36*
G01X706304Y1261254D02*
G02X705167Y1260672I-1137J820D01*
G02Y1263476I0J1402D01*
G02X706304Y1262894I0J-1402D01*
G03X706953I324J234D01*
G02X708090Y1263476I1137J-820D01*
G02Y1260672I0J-1402D01*
G02X706953Y1261254I0J1402D01*
G03X706304I-325J-234D01*
G37*
G36*
G01X754306Y1260842D02*
G02X753000Y1259950I-1306J510D01*
G02Y1262754I0J1402D01*
G02X753904Y1262423I-1J-1402D01*
G03X754535Y1262584I258J306D01*
G02X755841Y1263476I1306J-510D01*
G02Y1260672I0J-1402D01*
G02X754937Y1261003I1J1402D01*
G03X754306Y1260842I-258J-306D01*
G37*
G36*
G01X694681Y1263445D02*
G02X694644Y1263764I1365J320D01*
G02X696046Y1262362I1402J0D01*
G02X695897Y1262370I1J1402D01*
G03X695465Y1261881I-42J-398D01*
G02X695502Y1261562I-1365J-320D01*
G02X694100Y1262964I-1402J0D01*
G02X694249Y1262956I-1J-1402D01*
G03X694681Y1263445I42J398D01*
G37*
G36*
G01X1031559Y1265366D02*
G02X1030780Y1265130I-779J1166D01*
G02Y1267934I0J1402D01*
G02X1032149Y1266833I0J-1402D01*
G03X1032762Y1266586I391J86D01*
G02X1033541Y1266822I779J-1166D01*
G02Y1264018I0J-1402D01*
G02X1032172Y1265119I0J1402D01*
G03X1031559Y1265366I-391J-86D01*
G37*
G36*
G01X694045Y113651D02*
G03Y114205I-288J277D01*
G02X693653Y115178I1010J972D01*
G02X696457I1402J0D01*
G02X696065Y114205I-1402J-1D01*
G03Y113651I288J-277D01*
G02X696457Y112678I-1010J-972D01*
G02X693653I-1402J0D01*
G02X694045Y113651I1402J1D01*
G37*
G36*
G01X697588D02*
G03Y114205I-288J277D01*
G02X697196Y115178I1010J972D01*
G02X700000I1402J0D01*
G02X699608Y114205I-1402J-1D01*
G03Y113651I288J-277D01*
G02X700000Y112678I-1010J-972D01*
G02X697196I-1402J0D01*
G02X697588Y113651I1402J1D01*
G37*
G36*
G01X701131D02*
G03Y114205I-288J277D01*
G02X700739Y115178I1010J972D01*
G02X703543I1402J0D01*
G02X703151Y114205I-1402J-1D01*
G03Y113651I288J-277D01*
G02X703543Y112678I-1010J-972D01*
G02X700739I-1402J0D01*
G02X701131Y113651I1402J1D01*
G37*
G36*
G01X704675D02*
G03Y114205I-288J277D01*
G02X704283Y115178I1010J972D01*
G02X707087I1402J0D01*
G02X706695Y114205I-1402J-1D01*
G03Y113651I288J-277D01*
G02X707087Y112678I-1010J-972D01*
G02X704283I-1402J0D01*
G02X704675Y113651I1402J1D01*
G37*
G36*
G01X676504Y115377D02*
G03X675996Y115683I-392J-77D01*
G02X675560Y115618I-437J1437D01*
G02Y118622I0J1502D01*
G02X677034Y117411I0J-1503D01*
G03X677542Y117105I392J77D01*
G02X677978Y117170I437J-1437D01*
G02Y114166I0J-1502D01*
G02X676504Y115377I0J1503D01*
G37*
G36*
G01X727716Y130394D02*
G03Y130982I-270J294D01*
G02X727231Y132088I1017J1105D01*
G02X730235I1502J0D01*
G02X729750Y130982I-1502J-1D01*
G03Y130394I270J-294D01*
G02X730235Y129288I-1017J-1105D01*
G02X729705Y128143I-1502J0D01*
G03Y127533I259J-305D01*
G02X730235Y126388I-972J-1145D01*
G02X727231I-1502J0D01*
G02X727761Y127533I1502J0D01*
G03Y128143I-259J305D01*
G02X727231Y129288I972J1145D01*
G02X727716Y130394I1502J1D01*
G37*
G36*
G01X699864Y104215D02*
G02X699718Y104862I1356J646D01*
G02X702722I1502J0D01*
G02X702579Y104222I-1502J0D01*
G03X702894Y103654I362J-171D01*
G02X704222Y102162I-174J-1492D01*
G02X701218I-1502J0D01*
G02X701361Y102802I1502J0D01*
G03X701046Y103370I-362J171D01*
G02X700996Y103377I183J1491D01*
G03X700576Y102809I-59J-395D01*
G02X700722Y102162I-1356J-646D01*
G02X697718I-1502J0D01*
G02X697861Y102802I1502J0D01*
G03X697546Y103370I-362J171D01*
G02X697496Y103377I183J1491D01*
G03X697076Y102809I-59J-395D01*
G02X697222Y102162I-1356J-646D01*
G02X694218I-1502J0D01*
G02X694361Y102802I1502J0D01*
G03X694046Y103370I-362J171D01*
G02X692718Y104862I174J1492D01*
G02X695722I1502J0D01*
G02X695579Y104222I-1502J0D01*
G03X695894Y103654I362J-171D01*
G02X695944Y103647I-183J-1491D01*
G03X696364Y104215I59J395D01*
G02X696218Y104862I1356J646D01*
G02X699222I1502J0D01*
G02X699079Y104222I-1502J0D01*
G03X699394Y103654I362J-171D01*
G02X699444Y103647I-183J-1491D01*
G03X699864Y104215I59J395D01*
G37*
G36*
G01X679029Y104030D02*
G02X677790Y103378I-1239J851D01*
G02Y106382I0J1502D01*
G02X679128Y105562I0J-1502D01*
G03X679814Y105518I356J182D01*
G02X681053Y106170I1239J-851D01*
G02Y103166I0J-1502D01*
G02X679715Y103986I0J1502D01*
G03X679029Y104030I-356J-182D01*
G37*
G36*
G01X673145Y112366D02*
G02X672643Y113487I1001J1121D01*
G02X675647I1502J0D01*
G02X674809Y112140I-1502J0D01*
G03X674720Y111483I177J-359D01*
G02X675222Y110362I-1001J-1121D01*
G02X672218I-1502J0D01*
G02X673056Y111709I1502J0D01*
G03X673145Y112366I-177J359D01*
G37*
G36*
G01X686018Y114789D02*
G02X685532Y115896I1016J1106D01*
G02X688536I1502J0D01*
G02X688047Y114787I-1502J0D01*
G03X688046Y114197I269J-295D01*
G02X688532Y113090I-1016J-1106D01*
G02X688071Y112007I-1503J0D01*
G03X688279Y111324I277J-289D01*
G02X689521Y109845I-260J-1479D01*
G02X686517I-1502J0D01*
G02X686978Y110928I1503J0D01*
G03X686770Y111611I-277J289D01*
G02X685528Y113090I260J1479D01*
G02X686017Y114199I1502J0D01*
G03X686018Y114789I-269J295D01*
G37*
G36*
G01X711761Y116343D02*
G02X711231Y117488I972J1145D01*
G02X712733Y118990I1502J0D01*
G02X713997Y118300I0J-1503D01*
G03X714669I336J216D01*
G02X715933Y118990I1264J-813D01*
G02X717435Y117488I0J-1502D01*
G02X716905Y116343I-1502J0D01*
G03Y115733I259J-305D01*
G02X717435Y114588I-972J-1145D01*
G02X715933Y113086I-1502J0D01*
G02X714669Y113776I0J1503D01*
G03X713997I-336J-216D01*
G02X712733Y113086I-1264J813D01*
G02X711231Y114588I0J1502D01*
G02X711761Y115733I1502J0D01*
G03Y116343I-259J305D01*
G37*
G36*
G01X721197Y123676D02*
G02X719933Y122986I-1264J813D01*
G02Y125990I0J1502D01*
G02X721197Y125300I0J-1503D01*
G03X721869I336J216D01*
G02X723133Y125990I1264J-813D01*
G02Y122986I0J-1502D01*
G02X721869Y123676I0J1503D01*
G03X721197I-336J-216D01*
G37*
G36*
G01X699098Y125270D02*
Y125309D01*
G02X700600Y123807I1502J0D01*
G02X699744Y124075I0J1501D01*
G03X699117Y123736I-227J-329D01*
G01Y123697D01*
G02X697615Y125199I-1502J0D01*
G02X698471Y124931I0J-1501D01*
G03X699098Y125270I227J329D01*
G37*
G36*
G01X886207Y176133D02*
G02X886018Y176862I1313J729D01*
G02X889022I1502J0D01*
G02X887854Y175398I-1502J0D01*
G03X887593Y174814I89J-390D01*
G02X887782Y174085I-1313J-729D01*
G02X887614Y173394I-1502J-1D01*
G03X887874Y172822I355J-184D01*
G02X889022Y171362I-354J-1460D01*
G02X886018I-1502J0D01*
G02X886186Y172053I1502J1D01*
G03X885926Y172625I-355J184D01*
G02X884778Y174085I354J1460D01*
G02X885946Y175549I1502J0D01*
G03X886207Y176133I-89J390D01*
G37*
G36*
G01X1018227Y176795D02*
G03X1018795Y176816I274J292D01*
G02X1019900Y177301I1105J-1016D01*
G02X1021045Y176771I0J-1502D01*
G03X1021655I305J259D01*
G02X1022800Y177301I1145J-972D01*
G02Y174297I0J-1502D01*
G02X1021655Y174827I0J1502D01*
G03X1021045I-305J-259D01*
G02X1019900Y174297I-1145J972D01*
G02X1018873Y174703I0J1502D01*
G03X1018305Y174682I-274J-292D01*
G02X1017200Y174197I-1105J1016D01*
G02X1016055Y174727I0J1502D01*
G03X1015445I-305J-259D01*
G02X1014300Y174197I-1145J972D01*
G02Y177201I0J1502D01*
G02X1015445Y176671I0J-1502D01*
G03X1016055I305J259D01*
G02X1017200Y177201I1145J-972D01*
G02X1018227Y176795I0J-1502D01*
G37*
G36*
G01X1013145Y186271D02*
G03X1013755I305J259D01*
G02X1016045I1145J-972D01*
G03X1016655I305J259D01*
G02X1017800Y186801I1145J-972D01*
G02Y183797I0J-1502D01*
G02X1016655Y184327I0J1502D01*
G03X1016045I-305J-259D01*
G02X1013755I-1145J972D01*
G03X1013145I-305J-259D01*
G02X1012000Y183797I-1145J972D01*
G02Y186801I0J1502D01*
G02X1013145Y186271I0J-1502D01*
G37*
G36*
G01X999732Y191181D02*
G03X999178I-277J-288D01*
G02X998206Y190789I-972J1010D01*
G01X998205D01*
G02Y193593I0J1402D01*
G01X998206D01*
G02X999178Y193201I0J-1402D01*
G03X999732I277J288D01*
G02X1000704Y193593I972J-1010D01*
G01X1000705D01*
G02Y190789I0J-1402D01*
G01X1000704D01*
G02X999732Y191181I0J1402D01*
G37*
G36*
G01Y194725D02*
G03X999178I-277J-288D01*
G02X998206Y194333I-972J1010D01*
G01X998205D01*
G02Y197137I0J1402D01*
G01X998206D01*
G02X999178Y196745I0J-1402D01*
G03X999732I277J288D01*
G02X1000704Y197137I972J-1010D01*
G01X1000705D01*
G02Y194333I0J-1402D01*
G01X1000704D01*
G02X999732Y194725I0J1402D01*
G37*
G36*
G01Y198268D02*
G03X999178I-277J-288D01*
G02X998206Y197876I-972J1010D01*
G01X998205D01*
G02Y200680I0J1402D01*
G01X998206D01*
G02X999178Y200288I0J-1402D01*
G03X999732I277J288D01*
G02X1000704Y200680I972J-1010D01*
G01X1000705D01*
G02Y197876I0J-1402D01*
G01X1000704D01*
G02X999732Y198268I0J1402D01*
G37*
G36*
G01Y201811D02*
G03X999178I-277J-288D01*
G02X998206Y201419I-972J1010D01*
G01X998205D01*
G02Y204223I0J1402D01*
G01X998206D01*
G02X999178Y203831I0J-1402D01*
G03X999732I277J288D01*
G02X1000704Y204223I972J-1010D01*
G01X1000705D01*
G02Y201419I0J-1402D01*
G01X1000704D01*
G02X999732Y201811I0J1402D01*
G37*
G36*
G01X976499Y296128D02*
G03X977025I263J302D01*
G02X978012Y296498I987J-1131D01*
G02X979514Y294996I0J-1502D01*
G01Y294993D01*
G02X979358Y294328I-1502J2D01*
G03X979763Y293754I358J-177D01*
G02X979940Y293764I173J-1492D01*
G02X981442Y292262I0J-1502D01*
G02X981072Y291275I-1501J0D01*
G03Y290749I302J-263D01*
G02Y288775I-1131J-987D01*
G03Y288249I302J-263D01*
G02Y286275I-1131J-987D01*
G03Y285749I302J-263D01*
G02X981442Y284762I-1131J-987D01*
G02X979940Y283260I-1502J0D01*
G02X979790Y283268I5J1502D01*
G03X979384Y282707I-40J-398D01*
G02X979514Y282096I-1371J-611D01*
G02X979016Y280979I-1502J0D01*
G03Y280383I267J-298D01*
G02Y278149I-1004J-1117D01*
G03Y277553I267J-298D01*
G02X979514Y276436I-1004J-1117D01*
G02X976510I-1502J0D01*
G02X977008Y277553I1502J0D01*
G03Y278149I-267J298D01*
G02X976909Y278247I1006J1115D01*
G03X976615I-147J-136D01*
G02X975512Y277764I-1103J1018D01*
G02X974010Y279266I0J1502D01*
G02X974508Y280383I1502J0D01*
G03Y280979I-267J298D01*
G02X974010Y282096I1004J1117D01*
G02X975512Y283598I1502J0D01*
G02X976499Y283228I0J-1501D01*
G03X977025I263J302D01*
G02X978012Y283598I987J-1131D01*
G02X978162Y283590I-5J-1502D01*
G03X978568Y284151I40J398D01*
G02X978438Y284762I1371J611D01*
G02X978808Y285749I1501J0D01*
G03Y286275I-302J263D01*
G02Y288249I1131J987D01*
G03Y288775I-302J263D01*
G02Y290749I1131J987D01*
G03Y291275I-302J263D01*
G02X978438Y292262I1131J987D01*
G01Y292265D01*
G02X978594Y292930I1502J-2D01*
G03X978189Y293504I-358J177D01*
G02X978012Y293494I-173J1492D01*
G02X977025Y293864I0J1501D01*
G03X976499I-263J-302D01*
G02X975512Y293494I-987J1131D01*
G02Y296498I0J1502D01*
G02X976499Y296128I0J-1501D01*
G37*
G36*
G01X1035604Y306050D02*
G02X1034776Y307393I675J1343D01*
G02X1037780I1502J0D01*
G02X1036952Y306050I-1503J0D01*
G03Y305336I179J-357D01*
G02X1037780Y303993I-675J-1343D01*
G02X1034776I-1502J0D01*
G02X1035604Y305336I1503J0D01*
G03Y306050I-179J357D01*
G37*
G36*
G01X1090117Y299474D02*
G03X1090643I263J302D01*
G02X1092617I987J-1131D01*
G03X1093143I263J302D01*
G02X1094130Y299844I987J-1131D01*
G02Y296840I0J-1502D01*
G02X1093143Y297210I0J1501D01*
G03X1092617I-263J-302D01*
G02X1090643I-987J1131D01*
G03X1090117I-263J-302D01*
G02X1088143I-987J1131D01*
G03X1087617I-263J-302D01*
G02X1085643I-987J1131D01*
G03X1085117I-263J-302D01*
G02X1084130Y296840I-987J1131D01*
G02Y299844I0J1502D01*
G02X1085117Y299474I0J-1501D01*
G03X1085643I263J302D01*
G02X1087617I987J-1131D01*
G03X1088143I263J302D01*
G02X1090117I987J-1131D01*
G37*
G36*
G01X1083203Y290323D02*
G03X1083833I315J246D01*
G02X1086203I1185J-923D01*
G03X1086833I315J246D01*
G02X1088018Y290902I1185J-923D01*
G02Y287898I0J-1502D01*
G02X1086833Y288477I0J1502D01*
G03X1086203I-315J-246D01*
G02X1083833I-1185J923D01*
G03X1083203I-315J-246D01*
G02X1080833I-1185J923D01*
G03X1080203I-315J-246D01*
G02X1077833I-1185J923D01*
G03X1077203I-315J-246D01*
G02X1076018Y287898I-1185J923D01*
G02Y290902I0J1502D01*
G02X1077203Y290323I0J-1502D01*
G03X1077833I315J246D01*
G02X1080203I1185J-923D01*
G03X1080833I315J246D01*
G02X1083203I1185J-923D01*
G37*
G36*
G01X1082585Y274685D02*
G03X1083215I315J246D01*
G02X1085585I1185J-923D01*
G03X1086215I315J246D01*
G02X1087400Y275264I1185J-923D01*
G02Y272260I0J-1502D01*
G02X1086215Y272839I0J1502D01*
G03X1085585I-315J-246D01*
G02X1083215I-1185J923D01*
G03X1082585I-315J-246D01*
G02X1080215I-1185J923D01*
G03X1079585I-315J-246D01*
G02X1077215I-1185J923D01*
G03X1076585I-315J-246D01*
G02X1075400Y272260I-1185J923D01*
G02Y275264I0J1502D01*
G02X1076585Y274685I0J-1502D01*
G03X1077215I315J246D01*
G02X1079585I1185J-923D01*
G03X1080215I315J246D01*
G02X1082585I1185J-923D01*
G37*
G36*
G01X1081668Y268569D02*
G03X1081038I-315J-246D01*
G02X1079853Y267990I-1185J923D01*
G02Y270994I0J1502D01*
G02X1081038Y270415I0J-1502D01*
G03X1081668I315J246D01*
G02X1082853Y270994I1185J-923D01*
G02Y267990I0J-1502D01*
G02X1081668Y268569I0J1502D01*
G37*
G36*
G01X1079068Y261765D02*
G03X1079698I315J246D01*
G02X1082068I1185J-923D01*
G03X1082698I315J246D01*
G02X1083883Y262344I1185J-923D01*
G02Y259340I0J-1502D01*
G02X1082698Y259919I0J1502D01*
G03X1082068I-315J-246D01*
G02X1079698I-1185J923D01*
G03X1079068I-315J-246D01*
G02X1077883Y259340I-1185J923D01*
G02Y262344I0J1502D01*
G02X1079068Y261765I0J-1502D01*
G37*
G36*
G01X991421Y420296D02*
G03X991683Y420871I-92J389D01*
G02X991510Y421570I1329J700D01*
G02X994514I1502J0D01*
G02X993361Y420109I-1502J0D01*
G03X993099Y419534I92J-389D01*
G02X993272Y418835I-1329J-700D01*
G02X990268I-1502J0D01*
G02X991421Y420296I1502J0D01*
G37*
G36*
G01X989244Y408030D02*
G02X988159Y407566I-1086J1038D01*
G02Y410570I0J1502D01*
G02X989608Y409462I0J-1501D01*
G03X990284Y409290I386J104D01*
G02X991369Y409754I1086J-1038D01*
G02Y406750I0J-1502D01*
G02X989920Y407858I0J1501D01*
G03X989244Y408030I-386J-104D01*
G37*
G36*
G01X996674Y414260D02*
G02X995892Y415578I720J1318D01*
G02X998896I1502J0D01*
G02X998290Y414373I-1501J0D01*
G03X998337Y413701I239J-321D01*
G02X999119Y412383I-720J-1318D01*
G02X996115I-1502J0D01*
G02X996721Y413588I1501J0D01*
G03X996674Y414260I-239J321D01*
G37*
G36*
G01X1192737Y57909D02*
G03X1193321Y57943I276J289D01*
G02X1194478Y58488I1157J-956D01*
G02X1195686Y57878I0J-1501D01*
G03X1196326Y57873I322J238D01*
G02X1197520Y58464I1194J-911D01*
G02Y55460I0J-1502D01*
G02X1196312Y56070I0J1501D01*
G03X1195672Y56075I-322J-238D01*
G02X1194478Y55484I-1194J911D01*
G02X1193441Y55899I0J1503D01*
G03X1192857Y55865I-276J-289D01*
G02X1191700Y55320I-1157J956D01*
G02X1190544Y55863I0J1502D01*
G03X1189918Y55849I-307J-256D01*
G02X1188720Y55253I-1198J906D01*
G02Y58257I0J1502D01*
G02X1189876Y57714I0J-1502D01*
G03X1190502Y57728I307J256D01*
G02X1191700Y58324I1198J-906D01*
G02X1192737Y57909I0J-1503D01*
G37*
G36*
G01X1129095Y68663D02*
G02X1128495Y69864I902J1201D01*
G02X1131499I1502J0D01*
G02X1130860Y68635I-1501J0D01*
G03X1130850Y67987I230J-328D01*
G02X1131450Y66786I-902J-1201D01*
G02X1131445Y66664I-1502J0D01*
G03X1131992Y66260I399J-33D01*
G02X1132546Y66366I554J-1396D01*
G01X1132547D01*
G02X1131045Y64864I0J-1502D01*
G02X1131050Y64986I1502J0D01*
G03X1130503Y65390I-399J33D01*
G02X1129949Y65284I-554J1396D01*
G01X1129948D01*
G02X1128446Y66786I0J1502D01*
G02X1129085Y68015I1501J0D01*
G03X1129095Y68663I-230J328D01*
G37*
G36*
G01X1617382Y1438532D02*
X1616153Y1439760D01*
G02X1615714Y1440822I1062J1061D01*
G02X1617215Y1442324I1501J1D01*
G02X1618277Y1441884I0J-1502D01*
G01X1619945Y1440216D01*
G02X1620384Y1439154I-1062J-1061D01*
G01Y1423725D01*
G02X1619945Y1422663I-1501J-1D01*
G01X1617461Y1420179D01*
G02X1616399Y1419740I-1061J1062D01*
G01X1615062D01*
G02Y1422742I0J1501D01*
G01X1615777D01*
X1617382Y1424347D01*
Y1438532D01*
G37*
G36*
G01X1342816Y1318079D02*
G03Y1318605I-302J263D01*
G02X1342446Y1319592I1131J987D01*
G02X1345450I1502J0D01*
G02X1345080Y1318605I-1501J0D01*
G03Y1318079I302J-263D01*
G02X1345450Y1317092I-1131J-987D01*
G02X1342446I-1502J0D01*
G02X1342816Y1318079I1501J0D01*
G37*
G36*
G01X1374944D02*
G03Y1318605I-302J263D01*
G02X1374574Y1319592I1131J987D01*
G02X1377578I1502J0D01*
G02X1377208Y1318605I-1501J0D01*
G03Y1318079I302J-263D01*
G02X1377578Y1317092I-1131J-987D01*
G02X1374574I-1502J0D01*
G02X1374944Y1318079I1501J0D01*
G37*
G36*
G01X1407072D02*
G03Y1318605I-302J263D01*
G02X1406702Y1319592I1131J987D01*
G02X1409706I1502J0D01*
G02X1409336Y1318605I-1501J0D01*
G03Y1318079I302J-263D01*
G02X1409706Y1317092I-1131J-987D01*
G02X1406702I-1502J0D01*
G02X1407072Y1318079I1501J0D01*
G37*
G36*
G01X1439200D02*
G03Y1318605I-302J263D01*
G02X1438830Y1319592I1131J987D01*
G02X1441834I1502J0D01*
G02X1441464Y1318605I-1501J0D01*
G03Y1318079I302J-263D01*
G02X1441834Y1317092I-1131J-987D01*
G02X1438830I-1502J0D01*
G02X1439200Y1318079I1501J0D01*
G37*
G36*
G01X1460611Y1322687D02*
G03X1461110Y1322526I342J207D01*
G02X1461686Y1322644I576J-1349D01*
G02X1462262Y1322526I0J-1467D01*
G03X1462761Y1322687I157J368D01*
G02X1464016Y1323394I1255J-760D01*
G02Y1320460I0J-1467D01*
G02X1463440Y1320578I0J1467D01*
G03X1462941Y1320417I-157J-368D01*
G02X1460431I-1255J760D01*
G03X1459932Y1320578I-342J-207D01*
G02X1459356Y1320460I-576J1349D01*
G02X1458780Y1320578I0J1467D01*
G03X1458281Y1320417I-157J-368D01*
G02X1457026Y1319710I-1255J760D01*
G02Y1322644I0J1467D01*
G02X1457602Y1322526I0J-1467D01*
G03X1458101Y1322687I157J368D01*
G02X1460611I1255J-760D01*
G37*
G36*
G01X1361931Y1322473D02*
G03X1362468Y1322276I365J164D01*
G02X1363098Y1322418I630J-1325D01*
G02X1363557Y1322344I-1J-1467D01*
G03X1364045Y1322556I125J380D01*
G02X1365376Y1323405I1331J-619D01*
G02X1366719Y1322528I0J-1467D01*
G03X1367203Y1322306I366J160D01*
G02X1367635Y1322371I432J-1403D01*
G02Y1319437I0J-1467D01*
G02X1366292Y1320314I0J1467D01*
G03X1365808Y1320536I-366J-160D01*
G02X1365376Y1320471I-432J1403D01*
G02X1364917Y1320545I1J1467D01*
G03X1364429Y1320333I-125J-380D01*
G02X1363098Y1319484I-1331J619D01*
G02X1361760Y1320350I0J1467D01*
G03X1361223Y1320547I-365J-164D01*
G02X1360593Y1320405I-630J1325D01*
G02Y1323339I0J1467D01*
G02X1361931Y1322473I0J-1467D01*
G37*
G36*
G01X1367300Y1325966D02*
G03Y1326576I-259J305D01*
G02X1366770Y1327721I972J1145D01*
G02X1368272Y1329223I1502J0D01*
G02X1369761Y1327919I0J-1502D01*
G03X1370216Y1327577I396J53D01*
G02X1370438Y1327593I219J-1486D01*
G02X1370644Y1327579I1J-1502D01*
G03X1371085Y1327873I54J396D01*
G02X1372538Y1328993I1453J-383D01*
G02X1374040Y1327491I0J-1502D01*
G02X1373510Y1326346I-1502J0D01*
G03Y1325736I259J-305D01*
G02Y1323446I-972J-1145D01*
G03Y1322836I259J-305D01*
G02X1374040Y1321691I-972J-1145D01*
G02X1372538Y1320189I-1502J0D01*
G02X1371082Y1321321I0J1502D01*
G03X1370620Y1321616I-388J-98D01*
G02X1370338Y1321589I-284J1475D01*
G02X1368842Y1322961I0J1502D01*
G03X1368407Y1323325I-399J-34D01*
G02X1368272Y1323319I-134J1496D01*
G02X1366770Y1324821I0J1502D01*
G02X1367300Y1325966I1502J0D01*
G37*
G36*
G01X1399428D02*
G03Y1326576I-259J305D01*
G02X1398898Y1327721I972J1145D01*
G02X1400400Y1329223I1502J0D01*
G02X1401889Y1327919I0J-1502D01*
G03X1402344Y1327577I396J53D01*
G02X1402566Y1327593I219J-1486D01*
G02X1402772Y1327579I1J-1502D01*
G03X1403213Y1327873I54J396D01*
G02X1404666Y1328993I1453J-383D01*
G02X1406168Y1327491I0J-1502D01*
G02X1405638Y1326346I-1502J0D01*
G03Y1325736I259J-305D01*
G02Y1323446I-972J-1145D01*
G03Y1322836I259J-305D01*
G02X1406168Y1321691I-972J-1145D01*
G02X1404666Y1320189I-1502J0D01*
G02X1403210Y1321321I0J1502D01*
G03X1402748Y1321616I-388J-98D01*
G02X1402466Y1321589I-284J1475D01*
G02X1401748Y1321772I0J1502D01*
G03X1401172Y1321529I-191J-352D01*
G02X1399760Y1320460I-1412J398D01*
G02X1399184Y1320578I0J1467D01*
G03X1398685Y1320417I-157J-368D01*
G02X1396175I-1255J760D01*
G03X1395676Y1320578I-342J-207D01*
G02X1395100Y1320460I-576J1349D01*
G02X1394524Y1320578I0J1467D01*
G03X1394025Y1320417I-157J-368D01*
G02X1392770Y1319710I-1255J760D01*
G02Y1322644I0J1467D01*
G02X1393346Y1322526I0J-1467D01*
G03X1393845Y1322687I157J368D01*
G02X1396355I1255J-760D01*
G03X1396854Y1322526I342J207D01*
G02X1397430Y1322644I576J-1349D01*
G02X1398006Y1322526I0J-1467D01*
G03X1398505Y1322687I157J368D01*
G02X1399115Y1323244I1254J-761D01*
G03X1399246Y1323860I-176J359D01*
G02X1398898Y1324821I1153J961D01*
G02X1399428Y1325966I1502J0D01*
G37*
G36*
G01X1431556D02*
G03Y1326576I-259J305D01*
G02X1431026Y1327721I972J1145D01*
G02X1432528Y1329223I1502J0D01*
G02X1434017Y1327919I0J-1502D01*
G03X1434472Y1327577I396J53D01*
G02X1434694Y1327593I219J-1486D01*
G02X1434900Y1327579I1J-1502D01*
G03X1435341Y1327873I54J396D01*
G02X1436794Y1328993I1453J-383D01*
G02X1438296Y1327491I0J-1502D01*
G02X1437766Y1326346I-1502J0D01*
G03Y1325736I259J-305D01*
G02Y1323446I-972J-1145D01*
G03Y1322836I259J-305D01*
G02X1438296Y1321691I-972J-1145D01*
G02X1436794Y1320189I-1502J0D01*
G02X1435338Y1321321I0J1502D01*
G03X1434876Y1321616I-388J-98D01*
G02X1434594Y1321589I-284J1475D01*
G02X1433876Y1321772I0J1502D01*
G03X1433300Y1321529I-191J-352D01*
G02X1431888Y1320460I-1412J398D01*
G02X1431312Y1320578I0J1467D01*
G03X1430813Y1320417I-157J-368D01*
G02X1428303I-1255J760D01*
G03X1427804Y1320578I-342J-207D01*
G02X1427228Y1320460I-576J1349D01*
G02X1426652Y1320578I0J1467D01*
G03X1426153Y1320417I-157J-368D01*
G02X1424898Y1319710I-1255J760D01*
G02Y1322644I0J1467D01*
G02X1425474Y1322526I0J-1467D01*
G03X1425973Y1322687I157J368D01*
G02X1428483I1255J-760D01*
G03X1428982Y1322526I342J207D01*
G02X1429558Y1322644I576J-1349D01*
G02X1430134Y1322526I0J-1467D01*
G03X1430633Y1322687I157J368D01*
G02X1431243Y1323244I1254J-761D01*
G03X1431374Y1323860I-176J359D01*
G02X1431026Y1324821I1153J961D01*
G02X1431556Y1325966I1502J0D01*
G37*
G36*
G01X1463708Y1326917D02*
G03Y1327527I-259J305D01*
G02X1463178Y1328672I972J1145D01*
G02X1464680Y1330174I1502J0D01*
G02X1466172Y1328842I0J-1502D01*
G03X1466643Y1328494I398J45D01*
G02X1466919Y1328520I278J-1476D01*
G02X1467125Y1328506I1J-1502D01*
G03X1467566Y1328800I54J396D01*
G02X1469019Y1329920I1453J-383D01*
G02X1470521Y1328418I0J-1502D01*
G02X1469991Y1327273I-1502J0D01*
G03Y1326663I259J-305D01*
G02Y1324373I-972J-1145D01*
G03Y1323763I259J-305D01*
G02X1470521Y1322618I-972J-1145D01*
G02X1469019Y1321116I-1502J0D01*
G02X1467563Y1322248I0J1502D01*
G03X1467101Y1322543I-388J-98D01*
G02X1466819Y1322516I-284J1475D01*
G02X1465321Y1323913I0J1502D01*
G03X1464871Y1324282I-399J-28D01*
G02X1464680Y1324270I-189J1490D01*
G02X1463178Y1325772I0J1502D01*
G02X1463708Y1326917I1502J0D01*
G37*
G36*
G01X1356710Y1329839D02*
G03X1357019Y1330356I-71J394D01*
G02X1356946Y1330819I1429J463D01*
G02X1359950I1502J0D01*
G02X1358714Y1329341I-1502J0D01*
G03X1358405Y1328824I71J-394D01*
G02X1358478Y1328361I-1429J-463D01*
G02X1356976Y1326859I-1502J0D01*
G02X1355572Y1327829I0J1501D01*
G03X1354996Y1328032I-374J-142D01*
G02X1354238Y1327827I-758J1297D01*
G02Y1330831I0J1502D01*
G02X1355642Y1329861I0J-1501D01*
G03X1356218Y1329658I374J142D01*
G02X1356710Y1329839I757J-1298D01*
G37*
G36*
G01X1388838D02*
G03X1389147Y1330356I-71J394D01*
G02X1389074Y1330819I1429J463D01*
G02X1392078I1502J0D01*
G02X1390842Y1329341I-1502J0D01*
G03X1390533Y1328824I71J-394D01*
G02X1390606Y1328361I-1429J-463D01*
G02X1389104Y1326859I-1502J0D01*
G02X1387700Y1327829I0J1501D01*
G03X1387124Y1328032I-374J-142D01*
G02X1386366Y1327827I-758J1297D01*
G02Y1330831I0J1502D01*
G02X1387770Y1329861I0J-1501D01*
G03X1388346Y1329658I374J142D01*
G02X1388838Y1329839I757J-1298D01*
G37*
G36*
G01X1420966D02*
G03X1421275Y1330356I-71J394D01*
G02X1421202Y1330819I1429J463D01*
G02X1424206I1502J0D01*
G02X1422970Y1329341I-1502J0D01*
G03X1422661Y1328824I71J-394D01*
G02X1422734Y1328361I-1429J-463D01*
G02X1421232Y1326859I-1502J0D01*
G02X1419828Y1327829I0J1501D01*
G03X1419252Y1328032I-374J-142D01*
G02X1418494Y1327827I-758J1297D01*
G02Y1330831I0J1502D01*
G02X1419898Y1329861I0J-1501D01*
G03X1420474Y1329658I374J142D01*
G02X1420966Y1329839I757J-1298D01*
G37*
G36*
G01X1453094D02*
G03X1453403Y1330356I-71J394D01*
G02X1453330Y1330819I1429J463D01*
G02X1456334I1502J0D01*
G02X1455098Y1329341I-1502J0D01*
G03X1454789Y1328824I71J-394D01*
G02X1454862Y1328361I-1429J-463D01*
G02X1453360Y1326859I-1502J0D01*
G02X1451956Y1327829I0J1501D01*
G03X1451380Y1328032I-374J-142D01*
G02X1450622Y1327827I-758J1297D01*
G02Y1330831I0J1502D01*
G02X1452026Y1329861I0J-1501D01*
G03X1452602Y1329658I374J142D01*
G02X1453094Y1329839I757J-1298D01*
G37*
G36*
G01X1310688Y1331505D02*
G03Y1332031I-302J263D01*
G02X1310318Y1333018I1131J987D01*
G02X1313322I1502J0D01*
G02X1312952Y1332031I-1501J0D01*
G03Y1331505I302J-263D01*
G02X1313322Y1330518I-1131J-987D01*
G02X1310318I-1502J0D01*
G02X1310688Y1331505I1501J0D01*
G37*
G36*
G01X1471345Y1331500D02*
G03Y1332036I-296J268D01*
G02X1470958Y1333043I1115J1006D01*
G02X1473962I1502J0D01*
G02X1473575Y1332036I-1502J-1D01*
G03Y1331500I296J-268D01*
G02X1473962Y1330493I-1115J-1006D01*
G02X1470958I-1502J0D01*
G02X1471345Y1331500I1502J1D01*
G37*
G36*
G01X1474105Y1339101D02*
G03X1473764Y1339578I-392J80D01*
G02X1472454Y1341068I192J1490D01*
G02X1475458I1502J0D01*
G02X1475427Y1340766I-1502J2D01*
G03X1475768Y1340289I392J-80D01*
G02X1477078Y1338799I-192J-1490D01*
G02X1474074I-1502J0D01*
G02X1474105Y1339101I1502J-2D01*
G37*
G36*
G01X1335172Y1339392D02*
G03Y1340002I-259J305D01*
G02X1334642Y1341147I972J1145D01*
G02X1336144Y1342649I1502J0D01*
G02X1337615Y1341453I0J-1503D01*
G03X1338065Y1341138I392J81D01*
G02X1338288Y1341155I225J-1485D01*
G02X1338616Y1341119I1J-1502D01*
G03X1339078Y1341371I87J390D01*
G02X1340488Y1342355I1410J-518D01*
G02X1341990Y1340853I0J-1502D01*
G02X1341457Y1339706I-1501J0D01*
G03X1341441Y1339109I258J-306D01*
G02X1341912Y1338017I-1030J-1092D01*
G02X1341161Y1336716I-1502J0D01*
G03X1341120Y1336051I200J-346D01*
G02X1341716Y1334853I-906J-1198D01*
G02X1340214Y1333351I-1502J0D01*
G02X1338720Y1334694I0J1502D01*
G03X1338315Y1335051I-397J-43D01*
G01X1338288D01*
G02X1337523Y1335260I-1J1502D01*
G03X1336930Y1335010I-204J-344D01*
G02X1335504Y1333886I-1426J343D01*
G02X1334928Y1334004I0J1467D01*
G03X1334429Y1333843I-157J-368D01*
G02X1331919I-1255J760D01*
G03X1331420Y1334004I-342J-207D01*
G02X1330844Y1333886I-576J1349D01*
G02X1330268Y1334004I0J1467D01*
G03X1329769Y1333843I-157J-368D01*
G02X1328514Y1333136I-1255J760D01*
G02Y1336070I0J1467D01*
G02X1329090Y1335952I0J-1467D01*
G03X1329589Y1336113I157J368D01*
G02X1332099I1255J-760D01*
G03X1332598Y1335952I342J207D01*
G02X1333174Y1336070I576J-1349D01*
G02X1333750Y1335952I0J-1467D01*
G03X1334249Y1336113I157J368D01*
G02X1334859Y1336670I1254J-761D01*
G03X1334990Y1337286I-176J359D01*
G02X1334642Y1338247I1153J961D01*
G02X1335172Y1339392I1502J0D01*
G37*
G36*
G01X1497002Y1342633D02*
G03X1497459Y1343008I58J396D01*
G02X1498959Y1344432I1500J-78D01*
G02X1500424Y1343263I0J-1502D01*
G03X1500860Y1342954I390J88D01*
G02X1501033Y1342964I173J-1491D01*
G02Y1339960I0J-1502D01*
G02X1500889Y1339967I1J1502D01*
G03X1500451Y1339558I-38J-398D01*
G02X1500452Y1339517I-1501J-57D01*
G02X1498950Y1338015I-1502J0D01*
G02X1498665Y1338042I-1J1502D01*
G03X1498210Y1337775I-75J-393D01*
G02X1497425Y1336889I-1426J472D01*
G03X1497285Y1336275I171J-362D01*
G02X1497382Y1336140I-1141J-922D01*
G03X1497973Y1336045I338J214D01*
G02X1498924Y1336384I951J-1163D01*
G02X1499223Y1336354I0J-1502D01*
G03X1499691Y1336649I80J392D01*
G02X1501149Y1337789I1458J-362D01*
G02Y1334785I0J-1502D01*
G02X1500850Y1334815I0J1502D01*
G03X1500382Y1334520I-80J-392D01*
G02X1498924Y1333380I-1458J362D01*
G02X1497643Y1334098I0J1502D01*
G03X1497054Y1334202I-341J-209D01*
G02X1496144Y1333886I-910J1152D01*
G02X1495568Y1334004I0J1467D01*
G03X1495069Y1333843I-157J-368D01*
G02X1492559I-1255J760D01*
G03X1492060Y1334004I-342J-207D01*
G02X1491484Y1333886I-576J1349D01*
G02X1490908Y1334004I0J1467D01*
G03X1490409Y1333843I-157J-368D01*
G02X1489154Y1333136I-1255J760D01*
G02Y1336070I0J1467D01*
G02X1489730Y1335952I0J-1467D01*
G03X1490229Y1336113I157J368D01*
G02X1492739I1255J-760D01*
G03X1493238Y1335952I342J207D01*
G02X1493814Y1336070I576J-1349D01*
G02X1494390Y1335952I0J-1467D01*
G03X1494889Y1336113I157J368D01*
G02X1495499Y1336670I1254J-761D01*
G03X1495630Y1337286I-176J359D01*
G02X1495282Y1338247I1153J961D01*
G02X1495812Y1339392I1502J0D01*
G03Y1340002I-259J305D01*
G02X1495282Y1341147I972J1145D01*
G02X1496784Y1342649I1502J0D01*
G02X1497002Y1342633I-1J-1502D01*
G37*
G36*
G01X1324582Y1343265D02*
G03X1324891Y1343782I-71J394D01*
G02X1324818Y1344245I1429J463D01*
G02X1327822I1502J0D01*
G02X1326586Y1342767I-1502J0D01*
G03X1326277Y1342250I71J-394D01*
G02X1326350Y1341787I-1429J-463D01*
G02X1324848Y1340285I-1502J0D01*
G02X1323444Y1341255I0J1501D01*
G03X1322868Y1341458I-374J-142D01*
G02X1322110Y1341253I-758J1297D01*
G02Y1344257I0J1502D01*
G02X1323514Y1343287I0J-1501D01*
G03X1324090Y1343084I374J142D01*
G02X1324582Y1343265I757J-1298D01*
G37*
G36*
G01X1485222D02*
G03X1485531Y1343782I-71J394D01*
G02X1485458Y1344245I1429J463D01*
G02X1488462I1502J0D01*
G02X1487226Y1342767I-1502J0D01*
G03X1486917Y1342250I71J-394D01*
G02X1486990Y1341787I-1429J-463D01*
G02X1485488Y1340285I-1502J0D01*
G02X1484084Y1341255I0J1501D01*
G03X1483508Y1341458I-374J-142D01*
G02X1482750Y1341253I-758J1297D01*
G02Y1344257I0J1502D01*
G02X1484154Y1343287I0J-1501D01*
G03X1484730Y1343084I374J142D01*
G02X1485222Y1343265I757J-1298D01*
G37*
G36*
G01X1503456Y1354303D02*
G03Y1354829I-302J263D01*
G02X1503086Y1355816I1131J987D01*
G02X1506090I1502J0D01*
G02X1505720Y1354829I-1501J0D01*
G03Y1354303I302J-263D01*
G02X1506090Y1353316I-1131J-987D01*
G02X1503086I-1502J0D01*
G02X1503456Y1354303I1501J0D01*
G37*
G36*
G01X1278539Y1354349D02*
G03X1278439Y1354883I-339J213D01*
G02X1277832Y1356089I895J1206D01*
G02X1280836I1502J0D01*
G02X1280607Y1355292I-1501J0D01*
G03X1280707Y1354758I339J-213D01*
G02X1281314Y1353552I-895J-1206D01*
G02X1278310I-1502J0D01*
G02X1278539Y1354349I1501J0D01*
G37*
G36*
G01X1303044Y1362190D02*
G03Y1362800I-259J305D01*
G02X1302514Y1363945I972J1145D01*
G02X1304016Y1365447I1502J0D01*
G02X1305505Y1364143I0J-1502D01*
G03X1305960Y1363801I396J53D01*
G02X1306182Y1363817I219J-1486D01*
G02X1306722Y1363717I1J-1502D01*
G03X1307234Y1363933I144J373D01*
G02X1308616Y1364847I1382J-588D01*
G02X1310118Y1363345I0J-1502D01*
G02X1309588Y1362200I-1502J0D01*
G03Y1361590I259J-305D01*
G02X1310118Y1360445I-972J-1145D01*
G02X1309748Y1359458I-1501J0D01*
G03Y1358932I302J-263D01*
G02X1310118Y1357945I-1131J-987D01*
G02X1308616Y1356443I-1502J0D01*
G02X1307149Y1357623I0J1502D01*
G03X1306616Y1357911I-391J-86D01*
G02X1306082Y1357813I-534J1404D01*
G02X1305387Y1357983I-1J1502D01*
G03X1304837Y1357791I-185J-354D01*
G02X1303496Y1356920I-1341J597D01*
G02X1302920Y1357038I0J1467D01*
G03X1302421Y1356877I-157J-368D01*
G02X1299911I-1255J760D01*
G03X1299412Y1357038I-342J-207D01*
G02X1298836Y1356920I-576J1349D01*
G02X1298260Y1357038I0J1467D01*
G03X1297761Y1356877I-157J-368D01*
G02X1296506Y1356170I-1255J760D01*
G02Y1359104I0J1467D01*
G02X1297082Y1358986I0J-1467D01*
G03X1297581Y1359147I157J368D01*
G02X1300091I1255J-760D01*
G03X1300590Y1358986I342J207D01*
G02X1301166Y1359104I576J-1349D01*
G02X1301742Y1358986I0J-1467D01*
G03X1302241Y1359147I157J368D01*
G02X1302686Y1359610I1255J-760D01*
G03X1302791Y1360175I-221J333D01*
G02X1302514Y1361045I1225J869D01*
G02X1303044Y1362190I1502J0D01*
G37*
G36*
G01X1527940D02*
G03Y1362800I-259J305D01*
G02X1527410Y1363945I972J1145D01*
G02X1528912Y1365447I1502J0D01*
G02X1530401Y1364143I0J-1502D01*
G03X1530856Y1363801I396J53D01*
G02X1531078Y1363817I219J-1486D01*
G02X1531284Y1363803I1J-1502D01*
G03X1531725Y1364097I54J396D01*
G02X1533178Y1365217I1453J-383D01*
G02X1534680Y1363715I0J-1502D01*
G02X1534150Y1362570I-1502J0D01*
G03Y1361960I259J-305D01*
G02Y1359670I-972J-1145D01*
G03Y1359060I259J-305D01*
G02X1534680Y1357915I-972J-1145D01*
G02X1533178Y1356413I-1502J0D01*
G02X1531722Y1357545I0J1502D01*
G03X1531260Y1357840I-388J-98D01*
G02X1530978Y1357813I-284J1475D01*
G02X1530260Y1357996I0J1502D01*
G03X1529684Y1357753I-191J-352D01*
G02X1528272Y1356684I-1412J398D01*
G02X1527696Y1356802I0J1467D01*
G03X1527197Y1356641I-157J-368D01*
G02X1524687I-1255J760D01*
G03X1524188Y1356802I-342J-207D01*
G02X1523612Y1356684I-576J1349D01*
G02X1523036Y1356802I0J1467D01*
G03X1522537Y1356641I-157J-368D01*
G02X1521282Y1355934I-1255J760D01*
G02Y1358868I0J1467D01*
G02X1521858Y1358750I0J-1467D01*
G03X1522357Y1358911I157J368D01*
G02X1524867I1255J-760D01*
G03X1525366Y1358750I342J207D01*
G02X1525942Y1358868I576J-1349D01*
G02X1526518Y1358750I0J-1467D01*
G03X1527017Y1358911I157J368D01*
G02X1527627Y1359468I1254J-761D01*
G03X1527758Y1360084I-176J359D01*
G02X1527410Y1361045I1153J961D01*
G02X1527940Y1362190I1502J0D01*
G37*
G36*
G01X1517350Y1366063D02*
G03X1517659Y1366580I-71J394D01*
G02X1517586Y1367043I1429J463D01*
G02X1520590I1502J0D01*
G02X1519354Y1365565I-1502J0D01*
G03X1519045Y1365048I71J-394D01*
G02X1519118Y1364585I-1429J-463D01*
G02X1517616Y1363083I-1502J0D01*
G02X1516212Y1364053I0J1501D01*
G03X1515636Y1364256I-374J-142D01*
G02X1514878Y1364051I-758J1297D01*
G02Y1367055I0J1502D01*
G02X1516282Y1366085I0J-1501D01*
G03X1516858Y1365882I374J142D01*
G02X1517350Y1366063I757J-1298D01*
G37*
G36*
G01X1292574Y1366299D02*
G03X1292883Y1366816I-71J394D01*
G02X1292810Y1367279I1429J463D01*
G02X1295814I1502J0D01*
G02X1294578Y1365801I-1502J0D01*
G03X1294269Y1365284I71J-394D01*
G02X1294342Y1364821I-1429J-463D01*
G02X1292840Y1363319I-1502J0D01*
G02X1291436Y1364289I0J1501D01*
G03X1290860Y1364492I-374J-142D01*
G02X1290102Y1364287I-758J1297D01*
G02Y1367291I0J1502D01*
G02X1291506Y1366321I0J-1501D01*
G03X1292082Y1366118I374J142D01*
G02X1292574Y1366299I757J-1298D01*
G37*
G36*
G01X1341407Y1373442D02*
G03X1342018Y1373459I298J266D01*
G02X1343193Y1374025I1175J-937D01*
G02X1344378Y1373446I0J-1502D01*
G03X1345008I315J246D01*
G02X1346193Y1374025I1185J-923D01*
G02Y1371021I0J-1502D01*
G02X1345008Y1371600I0J1502D01*
G03X1344378I-315J-246D01*
G02X1343193Y1371021I-1185J923D01*
G02X1342074Y1371521I0J1502D01*
G03X1341463Y1371504I-298J-266D01*
G02X1340288Y1370938I-1175J937D01*
G02X1339103Y1371517I0J1502D01*
G03X1338473I-315J-246D01*
G02X1336103I-1185J923D01*
G03X1335473I-315J-246D01*
G02X1333103I-1185J923D01*
G03X1332473I-315J-246D01*
G02X1331288Y1370938I-1185J923D01*
G02Y1373942I0J1502D01*
G02X1332473Y1373363I0J-1502D01*
G03X1333103I315J246D01*
G02X1335473I1185J-923D01*
G03X1336103I315J246D01*
G02X1338473I1185J-923D01*
G03X1339103I315J246D01*
G02X1340288Y1373942I1185J-923D01*
G02X1341407Y1373442I0J-1502D01*
G37*
G36*
G01X1330199Y1376975D02*
G03Y1377525I-290J275D01*
G02X1329786Y1378560I1090J1035D01*
G02X1332790I1502J0D01*
G02X1332377Y1377525I-1503J0D01*
G03Y1376975I290J-275D01*
G02X1332473Y1376863I-1091J-1032D01*
G03X1333103I315J246D01*
G02X1335473I1185J-923D01*
G03X1336103I315J246D01*
G02X1338473I1185J-923D01*
G03X1339103I315J246D01*
G02X1340288Y1377442I1185J-923D01*
G02X1341407Y1376942I0J-1502D01*
G03X1342018Y1376959I298J266D01*
G02X1343193Y1377525I1175J-937D01*
G02X1344378Y1376946I0J-1502D01*
G03X1345008I315J246D01*
G02X1346193Y1377525I1185J-923D01*
G02Y1374521I0J-1502D01*
G02X1345008Y1375100I0J1502D01*
G03X1344378I-315J-246D01*
G02X1343193Y1374521I-1185J923D01*
G02X1342074Y1375021I0J1502D01*
G03X1341463Y1375004I-298J-266D01*
G02X1340288Y1374438I-1175J937D01*
G02X1339103Y1375017I0J1502D01*
G03X1338473I-315J-246D01*
G02X1336103I-1185J923D01*
G03X1335473I-315J-246D01*
G02X1333103I-1185J923D01*
G03X1332473I-315J-246D01*
G02X1331288Y1374438I-1185J923D01*
G02X1329786Y1375940I0J1502D01*
G02X1330199Y1376975I1503J0D01*
G37*
G36*
G01X1348743Y1379745D02*
G03Y1380375I-246J315D01*
G02X1348164Y1381560I923J1185D01*
G02X1349666Y1383062I1502J0D01*
G02X1350851Y1382483I0J-1502D01*
G03X1351481I315J246D01*
G02X1352666Y1383062I1185J-923D01*
G02X1354168Y1381560I0J-1502D01*
G02X1353589Y1380375I-1502J0D01*
G03Y1379745I246J-315D01*
G02X1354168Y1378560I-923J-1185D01*
G02X1353755Y1377525I-1503J0D01*
G03Y1376975I290J-275D01*
G02X1354168Y1375940I-1090J-1035D01*
G02X1352666Y1374438I-1502J0D01*
G02X1351481Y1375017I0J1502D01*
G03X1350851I-315J-246D01*
G02X1349666Y1374438I-1185J923D01*
G02X1348164Y1375940I0J1502D01*
G02X1348577Y1376975I1503J0D01*
G03Y1377525I-290J275D01*
G02X1348164Y1378560I1090J1035D01*
G02X1348743Y1379745I1502J0D01*
G37*
G36*
G01X1627140Y1383624D02*
G03X1627666I263J302D01*
G02X1628653Y1383994I987J-1131D01*
G02X1629660Y1383607I1J-1502D01*
G03X1630196I268J296D01*
G02X1631203Y1383994I1006J-1115D01*
G02X1632705Y1382492I0J-1502D01*
G02X1632335Y1381505I-1501J0D01*
G03Y1380979I302J-263D01*
G02Y1379005I-1131J-987D01*
G03Y1378479I302J-263D01*
G02Y1376505I-1131J-987D01*
G03Y1375979I302J-263D01*
G02Y1374005I-1131J-987D01*
G03Y1373479I302J-263D01*
G02Y1371505I-1131J-987D01*
G03Y1370979I302J-263D01*
G02Y1369005I-1131J-987D01*
G03Y1368479I302J-263D01*
G02X1632705Y1367492I-1131J-987D01*
G02X1631203Y1365990I-1502J0D01*
G02X1630196Y1366377I-1J1502D01*
G03X1629660I-268J-296D01*
G02X1628653Y1365990I-1006J1115D01*
G02X1627666Y1366360I0J1501D01*
G03X1627140I-263J-302D01*
G02X1626153Y1365990I-987J1131D01*
G02X1624651Y1367492I0J1502D01*
G02X1625021Y1368479I1501J0D01*
G03Y1369005I-302J263D01*
G02Y1370979I1131J987D01*
G03Y1371505I-302J263D01*
G02Y1373479I1131J987D01*
G03Y1374005I-302J263D01*
G02Y1375979I1131J987D01*
G03Y1376505I-302J263D01*
G02Y1378479I1131J987D01*
G03Y1379005I-302J263D01*
G02Y1380979I1131J987D01*
G03Y1381505I-302J263D01*
G02X1624651Y1382492I1131J987D01*
G02X1626153Y1383994I1502J0D01*
G02X1627140Y1383624I0J-1501D01*
G37*
G36*
G01X1646728Y1383607D02*
G03X1647264I268J296D01*
G02X1648271Y1383994I1006J-1115D01*
G02X1649258Y1383624I0J-1501D01*
G03X1649784I263J302D01*
G02X1650771Y1383994I987J-1131D01*
G02X1652273Y1382492I0J-1502D01*
G02X1651903Y1381505I-1501J0D01*
G03Y1380979I302J-263D01*
G02Y1379005I-1131J-987D01*
G03Y1378479I302J-263D01*
G02Y1376505I-1131J-987D01*
G03Y1375979I302J-263D01*
G02Y1374005I-1131J-987D01*
G03Y1373479I302J-263D01*
G02Y1371505I-1131J-987D01*
G03Y1370979I302J-263D01*
G02Y1369005I-1131J-987D01*
G03Y1368479I302J-263D01*
G02X1652273Y1367492I-1131J-987D01*
G02X1650771Y1365990I-1502J0D01*
G02X1649784Y1366360I0J1501D01*
G03X1649258I-263J-302D01*
G02X1648271Y1365990I-987J1131D01*
G02X1647264Y1366377I-1J1502D01*
G03X1646728I-268J-296D01*
G02X1645721Y1365990I-1006J1115D01*
G02X1644219Y1367492I0J1502D01*
G02X1644589Y1368479I1501J0D01*
G03Y1369005I-302J263D01*
G02Y1370979I1131J987D01*
G03Y1371505I-302J263D01*
G02Y1373479I1131J987D01*
G03Y1374005I-302J263D01*
G02Y1375979I1131J987D01*
G03Y1376505I-302J263D01*
G02Y1378479I1131J987D01*
G03Y1379005I-302J263D01*
G02Y1380979I1131J987D01*
G03Y1381505I-302J263D01*
G02X1644219Y1382492I1131J987D01*
G02X1645721Y1383994I1502J0D01*
G02X1646728Y1383607I1J-1502D01*
G37*
G36*
G01X1665240Y1383624D02*
G03X1665766I263J302D01*
G02X1666753Y1383994I987J-1131D01*
G02X1667760Y1383607I1J-1502D01*
G03X1668296I268J296D01*
G02X1669303Y1383994I1006J-1115D01*
G02X1670805Y1382492I0J-1502D01*
G02X1670435Y1381505I-1501J0D01*
G03Y1380979I302J-263D01*
G02Y1379005I-1131J-987D01*
G03Y1378479I302J-263D01*
G02Y1376505I-1131J-987D01*
G03Y1375979I302J-263D01*
G02Y1374005I-1131J-987D01*
G03Y1373479I302J-263D01*
G02Y1371505I-1131J-987D01*
G03Y1370979I302J-263D01*
G02Y1369005I-1131J-987D01*
G03Y1368479I302J-263D01*
G02X1670805Y1367492I-1131J-987D01*
G02X1669303Y1365990I-1502J0D01*
G02X1668296Y1366377I-1J1502D01*
G03X1667760I-268J-296D01*
G02X1666753Y1365990I-1006J1115D01*
G02X1665766Y1366360I0J1501D01*
G03X1665240I-263J-302D01*
G02X1664253Y1365990I-987J1131D01*
G02X1662751Y1367492I0J1502D01*
G02X1663121Y1368479I1501J0D01*
G03Y1369005I-302J263D01*
G02Y1370979I1131J987D01*
G03Y1371505I-302J263D01*
G02Y1373479I1131J987D01*
G03Y1374005I-302J263D01*
G02Y1375979I1131J987D01*
G03Y1376505I-302J263D01*
G02Y1378479I1131J987D01*
G03Y1379005I-302J263D01*
G02Y1380979I1131J987D01*
G03Y1381505I-302J263D01*
G02X1662751Y1382492I1131J987D01*
G02X1664253Y1383994I1502J0D01*
G02X1665240Y1383624I0J-1501D01*
G37*
G36*
G01X1687369Y1383607D02*
G03X1687905I268J296D01*
G02X1688912Y1383994I1006J-1115D01*
G02X1689899Y1383624I0J-1501D01*
G03X1690425I263J302D01*
G02X1691412Y1383994I987J-1131D01*
G02X1692914Y1382492I0J-1502D01*
G02X1692544Y1381505I-1501J0D01*
G03Y1380979I302J-263D01*
G02Y1379005I-1131J-987D01*
G03Y1378479I302J-263D01*
G02Y1376505I-1131J-987D01*
G03Y1375979I302J-263D01*
G02Y1374005I-1131J-987D01*
G03Y1373479I302J-263D01*
G02Y1371505I-1131J-987D01*
G03Y1370979I302J-263D01*
G02Y1369005I-1131J-987D01*
G03Y1368479I302J-263D01*
G02X1692914Y1367492I-1131J-987D01*
G02X1691412Y1365990I-1502J0D01*
G02X1690425Y1366360I0J1501D01*
G03X1689899I-263J-302D01*
G02X1688912Y1365990I-987J1131D01*
G02X1687905Y1366377I-1J1502D01*
G03X1687369I-268J-296D01*
G02X1686362Y1365990I-1006J1115D01*
G02X1684860Y1367492I0J1502D01*
G02X1685230Y1368479I1501J0D01*
G03Y1369005I-302J263D01*
G02Y1370979I1131J987D01*
G03Y1371505I-302J263D01*
G02Y1373479I1131J987D01*
G03Y1374005I-302J263D01*
G02Y1375979I1131J987D01*
G03Y1376505I-302J263D01*
G02Y1378479I1131J987D01*
G03Y1379005I-302J263D01*
G02Y1380979I1131J987D01*
G03Y1381505I-302J263D01*
G02X1684860Y1382492I1131J987D01*
G02X1686362Y1383994I1502J0D01*
G02X1687369Y1383607I1J-1502D01*
G37*
G36*
G01X1145254Y1386315D02*
G03X1145790I268J296D01*
G02X1146797Y1386702I1006J-1115D01*
G02X1147784Y1386332I0J-1501D01*
G03X1148310I263J302D01*
G02X1149297Y1386702I987J-1131D01*
G02X1150799Y1385200I0J-1502D01*
G02X1150429Y1384213I-1501J0D01*
G03Y1383687I302J-263D01*
G02Y1381713I-1131J-987D01*
G03Y1381187I302J-263D01*
G02Y1379213I-1131J-987D01*
G03Y1378687I302J-263D01*
G02Y1376713I-1131J-987D01*
G03Y1376187I302J-263D01*
G02Y1374213I-1131J-987D01*
G03Y1373687I302J-263D01*
G02Y1371713I-1131J-987D01*
G03Y1371187I302J-263D01*
G02X1150799Y1370200I-1131J-987D01*
G02X1149297Y1368698I-1502J0D01*
G02X1148310Y1369068I0J1501D01*
G03X1147784I-263J-302D01*
G02X1146797Y1368698I-987J1131D01*
G02X1145790Y1369085I-1J1502D01*
G03X1145254I-268J-296D01*
G02X1144247Y1368698I-1006J1115D01*
G02X1142745Y1370200I0J1502D01*
G02X1143115Y1371187I1501J0D01*
G03Y1371713I-302J263D01*
G02Y1373687I1131J987D01*
G03Y1374213I-302J263D01*
G02Y1376187I1131J987D01*
G03Y1376713I-302J263D01*
G02Y1378687I1131J987D01*
G03Y1379213I-302J263D01*
G02Y1381187I1131J987D01*
G03Y1381713I-302J263D01*
G02Y1383687I1131J987D01*
G03Y1384213I-302J263D01*
G02X1142745Y1385200I1131J987D01*
G02X1144247Y1386702I1502J0D01*
G02X1145254Y1386315I1J-1502D01*
G37*
G36*
G01X1163766Y1386332D02*
G03X1164292I263J302D01*
G02X1165279Y1386702I987J-1131D01*
G02X1166286Y1386315I1J-1502D01*
G03X1166822I268J296D01*
G02X1167829Y1386702I1006J-1115D01*
G02X1169331Y1385200I0J-1502D01*
G02X1168961Y1384213I-1501J0D01*
G03Y1383687I302J-263D01*
G02Y1381713I-1131J-987D01*
G03Y1381187I302J-263D01*
G02Y1379213I-1131J-987D01*
G03Y1378687I302J-263D01*
G02Y1376713I-1131J-987D01*
G03Y1376187I302J-263D01*
G02Y1374213I-1131J-987D01*
G03Y1373687I302J-263D01*
G02Y1371713I-1131J-987D01*
G03Y1371187I302J-263D01*
G02X1169331Y1370200I-1131J-987D01*
G02X1167829Y1368698I-1502J0D01*
G02X1166822Y1369085I-1J1502D01*
G03X1166286I-268J-296D01*
G02X1165279Y1368698I-1006J1115D01*
G02X1164292Y1369068I0J1501D01*
G03X1163766I-263J-302D01*
G02X1162779Y1368698I-987J1131D01*
G02X1161277Y1370200I0J1502D01*
G02X1161647Y1371187I1501J0D01*
G03Y1371713I-302J263D01*
G02Y1373687I1131J987D01*
G03Y1374213I-302J263D01*
G02Y1376187I1131J987D01*
G03Y1376713I-302J263D01*
G02Y1378687I1131J987D01*
G03Y1379213I-302J263D01*
G02Y1381187I1131J987D01*
G03Y1381713I-302J263D01*
G02Y1383687I1131J987D01*
G03Y1384213I-302J263D01*
G02X1161277Y1385200I1131J987D01*
G02X1162779Y1386702I1502J0D01*
G02X1163766Y1386332I0J-1501D01*
G37*
G36*
G01X1183754Y1386315D02*
G03X1184290I268J296D01*
G02X1185297Y1386702I1006J-1115D01*
G02X1186284Y1386332I0J-1501D01*
G03X1186810I263J302D01*
G02X1187797Y1386702I987J-1131D01*
G02X1189299Y1385200I0J-1502D01*
G02X1188929Y1384213I-1501J0D01*
G03Y1383687I302J-263D01*
G02Y1381713I-1131J-987D01*
G03Y1381187I302J-263D01*
G02Y1379213I-1131J-987D01*
G03Y1378687I302J-263D01*
G02Y1376713I-1131J-987D01*
G03Y1376187I302J-263D01*
G02Y1374213I-1131J-987D01*
G03Y1373687I302J-263D01*
G02Y1371713I-1131J-987D01*
G03Y1371187I302J-263D01*
G02X1189299Y1370200I-1131J-987D01*
G02X1187797Y1368698I-1502J0D01*
G02X1186810Y1369068I0J1501D01*
G03X1186284I-263J-302D01*
G02X1185297Y1368698I-987J1131D01*
G02X1184290Y1369085I-1J1502D01*
G03X1183754I-268J-296D01*
G02X1182747Y1368698I-1006J1115D01*
G02X1181245Y1370200I0J1502D01*
G02X1181615Y1371187I1501J0D01*
G03Y1371713I-302J263D01*
G02Y1373687I1131J987D01*
G03Y1374213I-302J263D01*
G02Y1376187I1131J987D01*
G03Y1376713I-302J263D01*
G02Y1378687I1131J987D01*
G03Y1379213I-302J263D01*
G02Y1381187I1131J987D01*
G03Y1381713I-302J263D01*
G02Y1383687I1131J987D01*
G03Y1384213I-302J263D01*
G02X1181245Y1385200I1131J987D01*
G02X1182747Y1386702I1502J0D01*
G02X1183754Y1386315I1J-1502D01*
G37*
G36*
G01X1661364Y1429778D02*
G03Y1430304I-302J263D01*
G02X1660994Y1431291I1131J987D01*
G02X1663998I1502J0D01*
G02X1663628Y1430304I-1501J0D01*
G03Y1429778I302J-263D01*
G02X1663998Y1428791I-1131J-987D01*
G02X1660994I-1502J0D01*
G02X1661364Y1429778I1501J0D01*
G37*
G36*
G01X1623238Y1429773D02*
G03Y1430309I-296J268D01*
G02X1622851Y1431316I1115J1006D01*
G02X1625855I1502J0D01*
G02X1625468Y1430309I-1502J-1D01*
G03Y1429773I296J-268D01*
G02X1625855Y1428766I-1115J-1006D01*
G02X1622851I-1502J0D01*
G02X1623238Y1429773I1502J1D01*
G37*
G36*
G01X1159890Y1432486D02*
G03Y1433012I-302J263D01*
G02X1159520Y1433999I1131J987D01*
G02X1162524I1502J0D01*
G02X1162154Y1433012I-1501J0D01*
G03Y1432486I302J-263D01*
G02X1162524Y1431499I-1131J-987D01*
G02X1159520I-1502J0D01*
G02X1159890Y1432486I1501J0D01*
G37*
G36*
G01X1121764Y1432481D02*
G03Y1433017I-296J268D01*
G02X1121377Y1434024I1115J1006D01*
G02X1124381I1502J0D01*
G02X1123994Y1433017I-1502J-1D01*
G03Y1432481I296J-268D01*
G02X1124381Y1431474I-1115J-1006D01*
G02X1121377I-1502J0D01*
G02X1121764Y1432481I1502J1D01*
G37*
G36*
G01X1647705Y1437365D02*
G03Y1437975I-259J305D01*
G02X1647175Y1439120I972J1145D01*
G02X1650179I1502J0D01*
G02X1650176Y1439029I-1502J4D01*
G03X1650695Y1438624I399J-23D01*
G02X1651143Y1438692I447J-1434D01*
G02X1651349Y1438678I1J-1502D01*
G03X1651790Y1438972I54J396D01*
G02X1653243Y1440092I1453J-383D01*
G02X1654745Y1438590I0J-1502D01*
G02X1654215Y1437445I-1502J0D01*
G03Y1436835I259J-305D01*
G02Y1434545I-972J-1145D01*
G03Y1433935I259J-305D01*
G02X1654745Y1432790I-972J-1145D01*
G02X1653243Y1431288I-1502J0D01*
G02X1651787Y1432420I0J1502D01*
G03X1651325Y1432715I-388J-98D01*
G02X1651043Y1432688I-284J1475D01*
G02X1650000Y1433109I0J1502D01*
G03X1649361Y1432994I-278J-287D01*
G02X1648037Y1432159I-1324J632D01*
G02X1647461Y1432277I0J1467D01*
G03X1646962Y1432116I-157J-368D01*
G02X1644452I-1255J760D01*
G03X1643953Y1432277I-342J-207D01*
G02X1643377Y1432159I-576J1349D01*
G02X1642801Y1432277I0J1467D01*
G03X1642302Y1432116I-157J-368D01*
G02X1641047Y1431409I-1255J760D01*
G02Y1434343I0J1467D01*
G02X1641623Y1434225I0J-1467D01*
G03X1642122Y1434386I157J368D01*
G02X1644632I1255J-760D01*
G03X1645131Y1434225I342J207D01*
G02X1645707Y1434343I576J-1349D01*
G02X1646283Y1434225I0J-1467D01*
G03X1646782Y1434386I157J368D01*
G02X1647270Y1434876I1254J-761D01*
G03X1647401Y1435428I-209J341D01*
G02X1647175Y1436220I1275J792D01*
G02X1647705Y1437365I1502J0D01*
G37*
G36*
G01X1685848Y1437665D02*
G03Y1438275I-259J305D01*
G02X1685318Y1439420I972J1145D01*
G02X1686820Y1440922I1502J0D01*
G02X1688309Y1439618I0J-1502D01*
G03X1688764Y1439276I396J53D01*
G02X1688986Y1439292I219J-1486D01*
G02X1689192Y1439278I1J-1502D01*
G03X1689633Y1439572I54J396D01*
G02X1691086Y1440692I1453J-383D01*
G02X1692588Y1439190I0J-1502D01*
G02X1692058Y1438045I-1502J0D01*
G03Y1437435I259J-305D01*
G02Y1435145I-972J-1145D01*
G03Y1434535I259J-305D01*
G02X1692588Y1433390I-972J-1145D01*
G02X1691086Y1431888I-1502J0D01*
G02X1689630Y1433020I0J1502D01*
G03X1689168Y1433315I-388J-98D01*
G02X1688886Y1433288I-284J1475D01*
G02X1688168Y1433471I0J1502D01*
G03X1687592Y1433228I-191J-352D01*
G02X1686180Y1432159I-1412J398D01*
G02X1685604Y1432277I0J1467D01*
G03X1685105Y1432116I-157J-368D01*
G02X1682595I-1255J760D01*
G03X1682096Y1432277I-342J-207D01*
G02X1681520Y1432159I-576J1349D01*
G02X1680944Y1432277I0J1467D01*
G03X1680445Y1432116I-157J-368D01*
G02X1679190Y1431409I-1255J760D01*
G02Y1434343I0J1467D01*
G02X1679766Y1434225I0J-1467D01*
G03X1680265Y1434386I157J368D01*
G02X1682775I1255J-760D01*
G03X1683274Y1434225I342J207D01*
G02X1683850Y1434343I576J-1349D01*
G02X1684426Y1434225I0J-1467D01*
G03X1684925Y1434386I157J368D01*
G02X1685535Y1434943I1254J-761D01*
G03X1685666Y1435559I-176J359D01*
G02X1685318Y1436520I1153J961D01*
G02X1685848Y1437665I1502J0D01*
G37*
G36*
G01X1184374Y1440373D02*
G03Y1440983I-259J305D01*
G02X1183844Y1442128I972J1145D01*
G02X1185346Y1443630I1502J0D01*
G02X1186835Y1442326I0J-1502D01*
G03X1187290Y1441984I396J53D01*
G02X1187512Y1442000I219J-1486D01*
G02X1187718Y1441986I1J-1502D01*
G03X1188159Y1442280I54J396D01*
G02X1189612Y1443400I1453J-383D01*
G02X1191114Y1441898I0J-1502D01*
G02X1190584Y1440753I-1502J0D01*
G03Y1440143I259J-305D01*
G02Y1437853I-972J-1145D01*
G03Y1437243I259J-305D01*
G02X1191114Y1436098I-972J-1145D01*
G02X1189612Y1434596I-1502J0D01*
G02X1188156Y1435728I0J1502D01*
G03X1187694Y1436023I-388J-98D01*
G02X1187412Y1435996I-284J1475D01*
G02X1186694Y1436179I0J1502D01*
G03X1186118Y1435936I-191J-352D01*
G02X1184706Y1434867I-1412J398D01*
G02X1184130Y1434985I0J1467D01*
G03X1183631Y1434824I-157J-368D01*
G02X1181121I-1255J760D01*
G03X1180622Y1434985I-342J-207D01*
G02X1180046Y1434867I-576J1349D01*
G02X1179470Y1434985I0J1467D01*
G03X1178971Y1434824I-157J-368D01*
G02X1177716Y1434117I-1255J760D01*
G02Y1437051I0J1467D01*
G02X1178292Y1436933I0J-1467D01*
G03X1178791Y1437094I157J368D01*
G02X1181301I1255J-760D01*
G03X1181800Y1436933I342J207D01*
G02X1182376Y1437051I576J-1349D01*
G02X1182952Y1436933I0J-1467D01*
G03X1183451Y1437094I157J368D01*
G02X1184061Y1437651I1254J-761D01*
G03X1184192Y1438267I-176J359D01*
G02X1183844Y1439228I1153J961D01*
G02X1184374Y1440373I1502J0D01*
G37*
G36*
G01X1636945Y1441714D02*
G03X1637312Y1442191I-25J399D01*
G02X1637283Y1442483I1473J294D01*
G02X1640287I1502J0D01*
G02X1638882Y1440984I-1502J0D01*
G03X1638515Y1440507I25J-399D01*
G02X1638544Y1440215I-1473J-294D01*
G02X1635540I-1502J0D01*
G02X1636945Y1441714I1502J0D01*
G37*
G36*
G01X1675088D02*
G03X1675455Y1442191I-25J399D01*
G02X1675426Y1442483I1473J294D01*
G02X1678430I1502J0D01*
G02X1677025Y1440984I-1502J0D01*
G03X1676658Y1440507I25J-399D01*
G02X1676687Y1440215I-1473J-294D01*
G02X1673683I-1502J0D01*
G02X1675088Y1441714I1502J0D01*
G37*
G36*
G01X1128119Y1444072D02*
G03Y1444645I-279J286D01*
G02X1127667Y1445719I1050J1074D01*
G02X1130671I1502J0D01*
G02X1130219Y1444645I-1502J0D01*
G03Y1444072I279J-287D01*
G02X1130671Y1442998I-1050J-1074D01*
G02X1127667I-1502J0D01*
G02X1128119Y1444072I1502J0D01*
G37*
G36*
G01X1166372Y1444169D02*
G03Y1444793I-251J312D01*
G02X1165810Y1445964I939J1171D01*
G02X1168814I1502J0D01*
G02X1168252Y1444793I-1501J0D01*
G03Y1444169I251J-312D01*
G02X1168814Y1442998I-939J-1171D01*
G02X1165810I-1502J0D01*
G02X1166372Y1444169I1501J0D01*
G37*
G36*
G01X1483519Y1446742D02*
G03Y1447372I-246J315D01*
G02X1482940Y1448557I923J1185D01*
G02X1485944I1502J0D01*
G02X1485365Y1447372I-1502J0D01*
G03Y1446742I246J-315D01*
G02X1485944Y1445557I-923J-1185D01*
G02X1482940I-1502J0D01*
G02X1483519Y1446742I1502J0D01*
G37*
G36*
G01X1458188Y1446854D02*
G03Y1447484I-246J315D01*
G02X1457609Y1448669I923J1185D01*
G02X1460613I1502J0D01*
G02X1460034Y1447484I-1502J0D01*
G03Y1446854I246J-315D01*
G02X1460613Y1445669I-923J-1185D01*
G02X1457609I-1502J0D01*
G02X1458188Y1446854I1502J0D01*
G37*
G36*
G01X1466644D02*
G03Y1447484I-246J315D01*
G02X1466065Y1448669I923J1185D01*
G02X1469069I1502J0D01*
G02X1468490Y1447484I-1502J0D01*
G03Y1446854I246J-315D01*
G02X1469069Y1445669I-923J-1185D01*
G02X1466065I-1502J0D01*
G02X1466644Y1446854I1502J0D01*
G37*
G36*
G01X1475044D02*
G03Y1447484I-246J315D01*
G02X1474465Y1448669I923J1185D01*
G02X1477469I1502J0D01*
G02X1476890Y1447484I-1502J0D01*
G03Y1446854I246J-315D01*
G02X1477469Y1445669I-923J-1185D01*
G02X1474465I-1502J0D01*
G02X1475044Y1446854I1502J0D01*
G37*
G36*
G01X1367840Y1447049D02*
Y1448142D01*
G02X1367340Y1449261I1002J1119D01*
G02X1370344I1502J0D01*
G02X1369844Y1448142I-1502J0D01*
G01Y1446634D01*
G02X1369550Y1445926I-1002J1D01*
G01X1364438Y1440814D01*
G02X1363730Y1440520I-709J708D01*
G01X1307630D01*
G02X1306922Y1440814I1J1002D01*
G01X1301911Y1445824D01*
X1177504D01*
X1176956Y1445277D01*
Y1445193D01*
G02X1175551Y1443692I-1502J-2D01*
G03X1175184Y1443215I25J-399D01*
G02X1175213Y1442923I-1473J-294D01*
G02X1172209I-1502J0D01*
G02X1173614Y1444422I1502J0D01*
G03X1173981Y1444899I-25J399D01*
G02X1173952Y1445191I1473J294D01*
G02X1175456Y1446693I1502J0D01*
G01X1175540D01*
X1176381Y1447534D01*
G02X1177089Y1447828I709J-708D01*
G01X1302326D01*
G02X1303034Y1447534I-1J-1002D01*
G01X1308045Y1442524D01*
X1363315D01*
X1367840Y1447049D01*
G37*
G36*
G01X1170634Y1448792D02*
X1172602Y1450760D01*
G02X1173310Y1451054I709J-708D01*
G01X1305350D01*
G02X1306058Y1450760I-1J-1002D01*
G01X1310545Y1446274D01*
X1361291D01*
G02X1362410Y1446774I1119J-1002D01*
G02Y1443770I0J-1502D01*
G02X1361291Y1444270I0J1502D01*
G01X1310130D01*
G02X1309422Y1444564I1J1002D01*
G01X1304935Y1449050D01*
X1173725D01*
X1172344Y1447669D01*
Y1446769D01*
G02X1172844Y1445650I-1002J-1119D01*
G02X1169840I-1502J0D01*
G02X1170340Y1446769I1502J0D01*
G01Y1448084D01*
G02X1170634Y1448792I1002J-1D01*
G37*
G36*
G01X1508212Y1431326D02*
X1535379Y1458493D01*
G02X1536087Y1458786I708J-709D01*
G01X1618727D01*
G02X1619435Y1458493I0J-1002D01*
G01X1627012Y1450916D01*
X1628967D01*
G02X1629675Y1450623I0J-1002D01*
G01X1635351Y1444947D01*
G02X1635644Y1444239I-709J-708D01*
G01Y1444104D01*
X1635703Y1444046D01*
G02X1636145Y1442982I-1060J-1064D01*
G02X1633141I-1502J0D01*
G02X1633504Y1443961I1502J0D01*
G01X1628552Y1448914D01*
X1626597D01*
G02X1625889Y1449207I0J1002D01*
G01X1618312Y1456784D01*
X1536502D01*
X1509335Y1429617D01*
G02X1508627Y1429324I-708J709D01*
G01X1450946D01*
X1449962Y1428340D01*
G02X1449254Y1428046I-709J708D01*
G01X1439946D01*
G02X1439238Y1428340I1J1002D01*
G01X1435535Y1432042D01*
X1432685D01*
X1430152Y1429509D01*
Y1422028D01*
G02X1429858Y1421320I-1002J1D01*
G01X1423561Y1415023D01*
G02X1422853Y1414730I-708J709D01*
G01X1422602D01*
X1422544Y1414671D01*
G02X1421480Y1414229I-1064J1060D01*
G02Y1417233I0J1502D01*
G02X1422388Y1416927I-1J-1502D01*
G01X1422527Y1416822D01*
X1428148Y1422443D01*
Y1429924D01*
G02X1428442Y1430632I1002J-1D01*
G01X1431562Y1433752D01*
G02X1432270Y1434046I709J-708D01*
G01X1435950D01*
G02X1436658Y1433752I-1J-1002D01*
G01X1440361Y1430050D01*
X1448839D01*
X1449823Y1431033D01*
G02X1450531Y1431326I708J-709D01*
G01X1508212D01*
G37*
G36*
G01X1185515Y1454858D02*
X1191393Y1460735D01*
G02X1192101Y1461028I708J-709D01*
G01X1301135D01*
G02X1301843Y1460735I0J-1002D01*
G01X1312346Y1450232D01*
X1363681D01*
G02X1364800Y1450733I1120J-1001D01*
G02Y1447729I0J-1502D01*
G02X1363681Y1448230I1J1502D01*
G01X1311931D01*
G02X1311223Y1448523I0J1002D01*
G01X1300720Y1459026D01*
X1192516D01*
X1186638Y1453148D01*
G02X1185930Y1452854I-709J708D01*
G01X1164079D01*
X1162540Y1451316D01*
Y1449516D01*
G02X1162247Y1448808I-1002J0D01*
G01X1160034Y1446595D01*
G02X1159326Y1446302I-708J709D01*
G01X1139838D01*
X1138813Y1445277D01*
Y1445193D01*
G02X1137408Y1443692I-1502J-2D01*
G03X1137041Y1443215I25J-399D01*
G02X1137070Y1442923I-1473J-294D01*
G02X1134066I-1502J0D01*
G02X1135471Y1444422I1502J0D01*
G03X1135838Y1444899I-25J399D01*
G02X1135809Y1445191I1473J294D01*
G02X1137313Y1446693I1502J0D01*
G01X1137397D01*
X1138715Y1448011D01*
G02X1139423Y1448304I708J-709D01*
G01X1158911D01*
X1160538Y1449931D01*
Y1451731D01*
G02X1160831Y1452439I1002J0D01*
G01X1162956Y1454564D01*
G02X1163664Y1454858I709J-708D01*
G01X1185515D01*
G37*
G36*
G01X1642142Y1466830D02*
G03Y1467460I-246J315D01*
G02X1641563Y1468645I923J1185D01*
G02X1644567I1502J0D01*
G02X1643988Y1467460I-1502J0D01*
G03Y1466830I246J-315D01*
G02Y1464460I-923J-1185D01*
G03Y1463830I246J-315D01*
G02X1644567Y1462645I-923J-1185D01*
G02X1644197Y1461658I-1501J0D01*
G03Y1461132I302J-263D01*
G02Y1459158I-1131J-987D01*
G03Y1458632I302J-263D01*
G02X1644567Y1457645I-1131J-987D01*
G02X1641563I-1502J0D01*
G02X1641933Y1458632I1501J0D01*
G03Y1459158I-302J263D01*
G02Y1461132I1131J987D01*
G03Y1461658I-302J263D01*
G02X1641563Y1462645I1131J987D01*
G02X1642142Y1463830I1502J0D01*
G03Y1464460I-246J315D01*
G02Y1466830I923J1185D01*
G37*
G36*
G01X1630802Y1469877D02*
G03X1631328I263J302D01*
G02X1632315Y1470247I987J-1131D01*
G02X1633500Y1469668I0J-1502D01*
G03X1634130I315J246D01*
G02X1635315Y1470247I1185J-923D01*
G02X1636817Y1468745I0J-1502D01*
G02X1636238Y1467560I-1502J0D01*
G03Y1466930I246J-315D01*
G02Y1464560I-923J-1185D01*
G03Y1463930I246J-315D01*
G02X1636817Y1462745I-923J-1185D01*
G02X1636447Y1461758I-1501J0D01*
G03Y1461232I302J-263D01*
G02Y1459258I-1131J-987D01*
G03Y1458732I302J-263D01*
G02X1636817Y1457745I-1131J-987D01*
G02X1635315Y1456243I-1502J0D01*
G02X1634130Y1456822I0J1502D01*
G03X1633500I-315J-246D01*
G02X1632315Y1456243I-1185J923D01*
G02X1631328Y1456613I0J1501D01*
G03X1630802I-263J-302D01*
G02X1629815Y1456243I-987J1131D01*
G02X1628313Y1457745I0J1502D01*
G02X1628683Y1458732I1501J0D01*
G03Y1459258I-302J263D01*
G02Y1461232I1131J987D01*
G03Y1461758I-302J263D01*
G02X1628313Y1462745I1131J987D01*
G02X1628892Y1463930I1502J0D01*
G03Y1464560I-246J315D01*
G02Y1466930I923J1185D01*
G03Y1467560I-246J315D01*
G02X1628313Y1468745I923J1185D01*
G02X1629815Y1470247I1502J0D01*
G02X1630802Y1469877I0J-1501D01*
G37*
G36*
G01X1140668Y1469538D02*
G03Y1470168I-246J315D01*
G02X1140089Y1471353I923J1185D01*
G02X1143093I1502J0D01*
G02X1142514Y1470168I-1502J0D01*
G03Y1469538I246J-315D01*
G02Y1467168I-923J-1185D01*
G03Y1466538I246J-315D01*
G02X1143093Y1465353I-923J-1185D01*
G02X1142723Y1464366I-1501J0D01*
G03Y1463840I302J-263D01*
G02Y1461866I-1131J-987D01*
G03Y1461340I302J-263D01*
G02X1143093Y1460353I-1131J-987D01*
G02X1140089I-1502J0D01*
G02X1140459Y1461340I1501J0D01*
G03Y1461866I-302J263D01*
G02Y1463840I1131J987D01*
G03Y1464366I-302J263D01*
G02X1140089Y1465353I1131J987D01*
G02X1140668Y1466538I1502J0D01*
G03Y1467168I-246J315D01*
G02Y1469538I923J1185D01*
G37*
G36*
G01X1129328Y1472585D02*
G03X1129854I263J302D01*
G02X1130841Y1472955I987J-1131D01*
G02X1132026Y1472376I0J-1502D01*
G03X1132656I315J246D01*
G02X1133841Y1472955I1185J-923D01*
G02X1135343Y1471453I0J-1502D01*
G02X1134764Y1470268I-1502J0D01*
G03Y1469638I246J-315D01*
G02Y1467268I-923J-1185D01*
G03Y1466638I246J-315D01*
G02X1135343Y1465453I-923J-1185D01*
G02X1134973Y1464466I-1501J0D01*
G03Y1463940I302J-263D01*
G02Y1461966I-1131J-987D01*
G03Y1461440I302J-263D01*
G02X1135343Y1460453I-1131J-987D01*
G02X1133841Y1458951I-1502J0D01*
G02X1132656Y1459530I0J1502D01*
G03X1132026I-315J-246D01*
G02X1130841Y1458951I-1185J923D01*
G02X1129854Y1459321I0J1501D01*
G03X1129328I-263J-302D01*
G02X1128341Y1458951I-987J1131D01*
G02X1126839Y1460453I0J1502D01*
G02X1127209Y1461440I1501J0D01*
G03Y1461966I-302J263D01*
G02Y1463940I1131J987D01*
G03Y1464466I-302J263D01*
G02X1126839Y1465453I1131J987D01*
G02X1127418Y1466638I1502J0D01*
G03Y1467268I-246J315D01*
G02Y1469638I923J1185D01*
G03Y1470268I-246J315D01*
G02X1126839Y1471453I923J1185D01*
G02X1128341Y1472955I1502J0D01*
G02X1129328Y1472585I0J-1501D01*
G37*
G36*
G01X1641460Y1472722D02*
G03X1640830I-315J-246D01*
G02X1639645Y1472143I-1185J923D01*
G02Y1475147I0J1502D01*
G02X1640830Y1474568I0J-1502D01*
G03X1641460I315J246D01*
G02X1642645Y1475147I1185J-923D01*
G02Y1472143I0J-1502D01*
G02X1641460Y1472722I0J1502D01*
G37*
G36*
G01X1409364Y1326196D02*
G02X1408969Y1326143I-395J1449D01*
G02X1410471Y1327645I0J1502D01*
G02X1410431Y1327300I-1502J-1D01*
G03X1410925Y1326822I389J-92D01*
G02X1411320Y1326875I395J-1449D01*
G02X1409818Y1325373I0J-1502D01*
G02X1409858Y1325718I1502J1D01*
G03X1409364Y1326196I-389J92D01*
G37*
G36*
G01X1377305Y1326154D02*
G02X1377214Y1326151I-95J1499D01*
G02X1378716Y1327653I0J1502D01*
G02X1378685Y1327352I-1502J3D01*
G03X1379101Y1326872I392J-80D01*
G02X1379192Y1326875I95J-1499D01*
G02X1377690Y1325373I0J-1502D01*
G02X1377721Y1325674I1502J-3D01*
G03X1377305Y1326154I-392J80D01*
G37*
G36*
G01X1441563Y1326309D02*
G02X1441332Y1326291I-232J1484D01*
G02X1442834Y1327793I0J1502D01*
G02X1442772Y1327366I-1501J0D01*
G03X1443217Y1326857I384J-114D01*
G02X1443448Y1326875I232J-1484D01*
G02X1441946Y1325373I0J-1502D01*
G02X1442008Y1325800I1501J0D01*
G03X1441563Y1326309I-384J114D01*
G37*
G36*
G01X1349344Y1330440D02*
G02X1348736Y1331647I894J1207D01*
G02X1351740I1502J0D01*
G02X1351132Y1330440I-1502J0D01*
G03Y1329798I239J-321D01*
G02X1351740Y1328591I-894J-1207D01*
G02X1348736I-1502J0D01*
G02X1349344Y1329798I1502J0D01*
G03Y1330440I-239J321D01*
G37*
G36*
G01X1381472D02*
G02X1380864Y1331647I894J1207D01*
G02X1383868I1502J0D01*
G02X1383260Y1330440I-1502J0D01*
G03Y1329798I239J-321D01*
G02X1383868Y1328591I-894J-1207D01*
G02X1380864I-1502J0D01*
G02X1381472Y1329798I1502J0D01*
G03Y1330440I-239J321D01*
G37*
G36*
G01X1413600D02*
G02X1412992Y1331647I894J1207D01*
G02X1415996I1502J0D01*
G02X1415388Y1330440I-1502J0D01*
G03Y1329798I239J-321D01*
G02X1415996Y1328591I-894J-1207D01*
G02X1412992I-1502J0D01*
G02X1413600Y1329798I1502J0D01*
G03Y1330440I-239J321D01*
G37*
G36*
G01X1445728D02*
G02X1445120Y1331647I894J1207D01*
G02X1448124I1502J0D01*
G02X1447516Y1330440I-1502J0D01*
G03Y1329798I239J-321D01*
G02X1448124Y1328591I-894J-1207D01*
G02X1445120I-1502J0D01*
G02X1445728Y1329798I1502J0D01*
G03Y1330440I-239J321D01*
G37*
G36*
G01X1317216Y1343866D02*
G02X1316608Y1345073I894J1207D01*
G02X1319612I1502J0D01*
G02X1319004Y1343866I-1502J0D01*
G03Y1343224I239J-321D01*
G02X1319612Y1342017I-894J-1207D01*
G02X1316608I-1502J0D01*
G02X1317216Y1343224I1502J0D01*
G03Y1343866I-239J321D01*
G37*
G36*
G01X1477856D02*
G02X1477248Y1345073I894J1207D01*
G02X1480252I1502J0D01*
G02X1479644Y1343866I-1502J0D01*
G03Y1343224I239J-321D01*
G02X1480252Y1342017I-894J-1207D01*
G02X1477248I-1502J0D01*
G02X1477856Y1343224I1502J0D01*
G03Y1343866I-239J321D01*
G37*
G36*
G01X1505876Y1362741D02*
G02X1505570Y1362710I-304J1471D01*
G02X1507072Y1364212I0J1502D01*
G02X1506949Y1363617I-1501J0D01*
G03X1507398Y1363068I367J-158D01*
G02X1507704Y1363099I304J-1471D01*
G02X1506202Y1361597I0J-1502D01*
G02X1506325Y1362192I1501J0D01*
G03X1505876Y1362741I-367J158D01*
G37*
G36*
G01X1509984Y1366664D02*
G02X1509376Y1367871I894J1207D01*
G02X1512380I1502J0D01*
G02X1511772Y1366664I-1502J0D01*
G03Y1366022I239J-321D01*
G02X1512380Y1364815I-894J-1207D01*
G02X1509376I-1502J0D01*
G02X1509984Y1366022I1502J0D01*
G03Y1366664I-239J321D01*
G37*
G36*
G01X1285208Y1366900D02*
G02X1284600Y1368107I894J1207D01*
G02X1287604I1502J0D01*
G02X1286996Y1366900I-1502J0D01*
G03Y1366258I239J-321D01*
G02X1287604Y1365051I-894J-1207D01*
G02X1284600I-1502J0D01*
G02X1285208Y1366258I1502J0D01*
G03Y1366900I-239J321D01*
G37*
G36*
G01X1268338Y1370350D02*
G02X1267510Y1371693I675J1343D01*
G02X1270514I1502J0D01*
G02X1269686Y1370350I-1503J0D01*
G03Y1369636I179J-357D01*
G02X1270514Y1368293I-675J-1343D01*
G02X1267510I-1502J0D01*
G02X1268338Y1369636I1503J0D01*
G03Y1370350I-179J357D01*
G37*
G36*
G01X1325676Y1382401D02*
G03X1326306I315J246D01*
G02X1327491Y1382980I1185J-923D01*
G02X1328993Y1381478I0J-1502D01*
G02X1328414Y1380293I-1502J0D01*
G03Y1379663I246J-315D01*
G02X1328993Y1378478I-923J-1185D01*
G02X1328580Y1377443I-1503J0D01*
G03Y1376893I290J-275D01*
G02X1328993Y1375858I-1090J-1035D01*
G02X1327491Y1374356I-1502J0D01*
G02X1326306Y1374935I0J1502D01*
G03X1325676I-315J-246D01*
G02X1325303Y1374594I-1186J922D01*
G03Y1373922I216J-336D01*
G02X1325767Y1373451I-812J-1264D01*
G03X1326398Y1373388I340J211D01*
G02X1327491Y1373860I1093J-1030D01*
G02Y1370856I0J-1502D01*
G02X1326215Y1371565I0J1503D01*
G03X1325584Y1371628I-340J-211D01*
G02X1324491Y1371156I-1093J1030D01*
G02X1322989Y1372658I0J1502D01*
G02X1323679Y1373922I1503J0D01*
G03Y1374594I-216J336D01*
G02X1322989Y1375858I813J1264D01*
G02X1323402Y1376893I1503J0D01*
G03Y1377443I-290J275D01*
G02X1322989Y1378478I1090J1035D01*
G02X1323568Y1379663I1502J0D01*
G03Y1380293I-246J315D01*
G02X1322989Y1381478I923J1185D01*
G02X1324491Y1382980I1502J0D01*
G02X1325676Y1382401I0J-1502D01*
G37*
G36*
G01X1128186Y1386315D02*
G03X1128722I268J296D01*
G02X1129729Y1386702I1006J-1115D01*
G02X1131231Y1385200I0J-1502D01*
G02X1130861Y1384213I-1501J0D01*
G03Y1383687I302J-263D01*
G02Y1381713I-1131J-987D01*
G03Y1381187I302J-263D01*
G02Y1379213I-1131J-987D01*
G03Y1378687I302J-263D01*
G02Y1376713I-1131J-987D01*
G03Y1376187I302J-263D01*
G02Y1374213I-1131J-987D01*
G03Y1373687I302J-263D01*
G02Y1371713I-1131J-987D01*
G03Y1371187I302J-263D01*
G02X1131231Y1370200I-1131J-987D01*
G02X1130870Y1369223I-1503J0D01*
G03X1131167Y1368563I304J-260D01*
G02X1134702Y1364962I-67J-3601D01*
G02X1127498I-3602J0D01*
G02X1129278Y1368069I3602J0D01*
G03X1129213Y1368790I-203J345D01*
G02X1128722Y1369085I514J1411D01*
G03X1128186I-268J-296D01*
G02X1127179Y1368698I-1006J1115D01*
G02X1126192Y1369068I0J1501D01*
G03X1125666I-263J-302D01*
G02X1124679Y1368698I-987J1131D01*
G02X1123177Y1370200I0J1502D01*
G02X1123547Y1371187I1501J0D01*
G03Y1371713I-302J263D01*
G02Y1373687I1131J987D01*
G03Y1374213I-302J263D01*
G02Y1376187I1131J987D01*
G03Y1376713I-302J263D01*
G02Y1378687I1131J987D01*
G03Y1379213I-302J263D01*
G02Y1381187I1131J987D01*
G03Y1381713I-302J263D01*
G02Y1383687I1131J987D01*
G03Y1384213I-302J263D01*
G02X1123177Y1385200I1131J987D01*
G02X1124679Y1386702I1502J0D01*
G02X1125666Y1386332I0J-1501D01*
G03X1126192I263J302D01*
G02X1127179Y1386702I987J-1131D01*
G02X1128186Y1386315I1J-1502D01*
G37*
G36*
G01X1434788Y1395066D02*
G02X1433960Y1396409I675J1343D01*
G02X1436964I1502J0D01*
G02X1436136Y1395066I-1503J0D01*
G03Y1394352I179J-357D01*
G02X1436964Y1393009I-675J-1343D01*
G02X1433960I-1502J0D01*
G02X1434788Y1394352I1503J0D01*
G03Y1395066I-179J357D01*
G37*
G36*
G01X1350492Y1406044D02*
G03X1351060I284J282D01*
G02X1352126Y1406488I1066J-1058D01*
G02X1353628Y1404986I0J-1502D01*
G02X1353049Y1403801I-1502J0D01*
G03Y1403171I246J-315D01*
G02X1353628Y1401986I-923J-1185D01*
G02X1352126Y1400484I-1502J0D01*
G02X1351060Y1400928I0J1502D01*
G03X1350492I-284J-282D01*
G02X1349426Y1400484I-1066J1058D01*
G02X1348193Y1401128I0J1502D01*
G03X1347537I-328J-229D01*
G02X1346304Y1400484I-1233J858D01*
G02X1345119Y1401063I0J1502D01*
G03X1344489I-315J-246D01*
G02X1342119I-1185J923D01*
G03X1341489I-315J-246D01*
G02X1339119I-1185J923D01*
G03X1338489I-315J-246D01*
G02X1336119I-1185J923D01*
G03X1335489I-315J-246D01*
G02X1333119I-1185J923D01*
G03X1332489I-315J-246D01*
G02X1331304Y1400484I-1185J923D01*
G02X1329802Y1401986I0J1502D01*
G02X1330381Y1403171I1502J0D01*
G03Y1403801I-246J315D01*
G02X1329970Y1404295I923J1185D01*
G03X1329260I-355J-184D01*
G02X1327926Y1403484I-1334J692D01*
G02Y1406488I0J1502D01*
G02X1329260Y1405677I0J-1503D01*
G03X1329970I355J184D01*
G02X1331304Y1406488I1334J-692D01*
G02X1332489Y1405909I0J-1502D01*
G03X1333119I315J246D01*
G02X1335489I1185J-923D01*
G03X1336119I315J246D01*
G02X1338489I1185J-923D01*
G03X1339119I315J246D01*
G02X1341489I1185J-923D01*
G03X1342119I315J246D01*
G02X1344489I1185J-923D01*
G03X1345119I315J246D01*
G02X1346304Y1406488I1185J-923D01*
G02X1347537Y1405844I0J-1502D01*
G03X1348193I328J229D01*
G02X1349426Y1406488I1233J-858D01*
G02X1350492Y1406044I0J-1502D01*
G37*
G36*
G01X1458342Y1408467D02*
G02X1458138Y1408453I-205J1488D01*
G02X1459640Y1409955I0J1502D01*
G02X1459582Y1409540I-1502J-2D01*
G03X1460020Y1409033I384J-111D01*
G02X1460224Y1409047I205J-1488D01*
G02X1458722Y1407545I0J-1502D01*
G02X1458780Y1407960I1502J2D01*
G03X1458342Y1408467I-384J111D01*
G37*
G36*
G01X1385362Y1408946D02*
G02X1385109Y1408925I-250J1481D01*
G02X1386611Y1410427I0J1502D01*
G02X1386579Y1410120I-1502J1D01*
G03X1387038Y1409644I391J-82D01*
G02X1387291Y1409665I250J-1481D01*
G02X1385789Y1408163I0J-1502D01*
G02X1385821Y1408470I1502J-1D01*
G03X1385362Y1408946I-391J82D01*
G37*
G36*
G01X1344422Y1426193D02*
G03X1345021Y1426212I291J274D01*
G02X1346178Y1426756I1157J-958D01*
G02X1347680Y1425254I0J-1502D01*
G02X1347320Y1424278I-1503J0D01*
G03X1347341Y1423735I304J-260D01*
G02X1347463Y1423597I-1062J-1062D01*
G03X1348093I315J246D01*
G02X1349278Y1424176I1185J-923D01*
G02X1350780Y1422674I0J-1502D01*
G02X1350437Y1421719I-1501J0D01*
G03X1350485Y1421161I309J-255D01*
G02X1350532Y1421119I-977J-1141D01*
G03X1350844Y1421170I136J146D01*
G02X1352166Y1421958I1322J-715D01*
G02X1353668Y1420456I0J-1502D01*
G02X1353089Y1419271I-1502J0D01*
G03Y1418641I246J-315D01*
G02Y1416271I-923J-1185D01*
G03Y1415641I246J-315D01*
G02Y1413271I-923J-1185D01*
G03Y1412641I246J-315D01*
G02Y1410271I-923J-1185D01*
G03Y1409641I246J-315D01*
G02X1353668Y1408456I-923J-1185D01*
G02X1352166Y1406954I-1502J0D01*
G02X1351100Y1407398I0J1502D01*
G03X1350532I-284J-282D01*
G02X1349466Y1406954I-1066J1058D01*
G02X1348295Y1407515I0J1503D01*
G03X1347679Y1407523I-311J-251D01*
G02X1346534Y1406994I-1144J973D01*
G02X1345032Y1408496I0J1502D01*
G02X1345611Y1409681I1502J0D01*
G03Y1410311I-246J315D01*
G02X1345032Y1411496I923J1185D01*
G02X1345521Y1412605I1502J0D01*
G03X1345481Y1413227I-270J295D01*
G02X1345159Y1413533I862J1230D01*
G03X1344529I-315J-246D01*
G02X1342159I-1185J923D01*
G03X1341529I-315J-246D01*
G02X1339159I-1185J923D01*
G03X1338529I-315J-246D01*
G02X1336159I-1185J923D01*
G03X1335529I-315J-246D01*
G02X1333159I-1185J923D01*
G03X1332529I-315J-246D01*
G02X1332054Y1413132I-1186J922D01*
G03X1331940Y1412518I189J-353D01*
G02X1332306Y1411536I-1136J-983D01*
G02X1331727Y1410351I-1502J0D01*
G03Y1409721I246J-315D01*
G02X1332306Y1408536I-923J-1185D01*
G02X1330804Y1407034I-1502J0D01*
G02X1329712Y1407505I0J1501D01*
G03X1329115Y1407488I-291J-274D01*
G02X1327966Y1406954I-1149J969D01*
G02X1326796Y1407514I0J1502D01*
G03X1326181Y1407523I-311J-251D01*
G02X1325042Y1407000I-1139J979D01*
G02X1323540Y1408502I0J1502D01*
G02X1324119Y1409687I1502J0D01*
G03Y1410317I-246J315D01*
G02X1323975Y1410445I924J1184D01*
G03X1323375Y1410408I-284J-282D01*
G02X1322186Y1409824I-1189J918D01*
G02X1320684Y1411326I0J1502D01*
G02X1321263Y1412511I1502J0D01*
G03Y1413141I-246J315D01*
G02Y1415511I923J1185D01*
G03Y1416141I-246J315D01*
G02X1320684Y1417326I923J1185D01*
G02X1321093Y1418357I1502J1D01*
G03X1321102Y1418896I-291J274D01*
G02X1320726Y1419890I1126J994D01*
G02X1321135Y1420921I1502J1D01*
G03X1321144Y1421460I-291J274D01*
G02X1320768Y1422454I1126J994D01*
G02X1321177Y1423485I1502J1D01*
G03X1321186Y1424024I-291J274D01*
G02X1320810Y1425018I1126J994D01*
G02X1322312Y1426520I1502J0D01*
G02X1323379Y1426075I0J-1502D01*
G03X1323979Y1426112I284J282D01*
G02X1325168Y1426696I1189J-918D01*
G02X1326338Y1426136I0J-1502D01*
G03X1326953Y1426127I311J251D01*
G02X1328092Y1426650I1139J-979D01*
G02X1329426Y1425839I0J-1503D01*
G03X1330136I355J184D01*
G02X1331470Y1426650I1334J-692D01*
G02X1332655Y1426071I0J-1502D01*
G03X1333285I315J246D01*
G02X1334470Y1426650I1185J-923D01*
G02X1335593Y1426145I0J-1501D01*
G03X1336194Y1426149I299J266D01*
G02X1337328Y1426666I1134J-985D01*
G02X1338513Y1426087I0J-1502D01*
G03X1339143I315J246D01*
G02X1341513I1185J-923D01*
G03X1342143I315J246D01*
G02X1343328Y1426666I1185J-923D01*
G02X1344422Y1426193I0J-1502D01*
G37*
G36*
G01X1514660Y1431860D02*
G02X1514635Y1432135I1477J273D01*
G02X1516137Y1430633I1502J0D01*
G02X1515655Y1430712I-1J1502D01*
G03X1515134Y1430260I-128J-379D01*
G02X1515159Y1429985I-1477J-273D01*
G02X1513968Y1428515I-1503J0D01*
G03X1513656Y1428055I82J-391D01*
G02X1513679Y1427795I-1479J-262D01*
G02X1512177Y1426293I-1502J0D01*
G02X1511980Y1426306I0J1502D01*
G03X1511528Y1425892I-53J-396D01*
G02X1511529Y1425825I-1501J-56D01*
G02X1510027Y1424323I-1502J0D01*
G02X1509625Y1424378I1J1502D01*
G03X1509118Y1424003I-107J-386D01*
G02X1507617Y1422543I-1501J42D01*
G02Y1425547I0J1502D01*
G02X1508019Y1425492I-1J-1502D01*
G03X1508526Y1425867I107J386D01*
G02X1510027Y1427327I1501J-42D01*
G02X1510224Y1427314I0J-1502D01*
G03X1510676Y1427728I53J396D01*
G02X1510675Y1427795I1501J56D01*
G02X1511866Y1429265I1503J0D01*
G03X1512178Y1429725I-82J391D01*
G02X1512155Y1429985I1479J262D01*
G02X1513657Y1431487I1502J0D01*
G02X1514139Y1431408I1J-1502D01*
G03X1514660Y1431860I128J379D01*
G37*
G36*
G01X1110241Y1433458D02*
X1114084Y1437301D01*
G02X1115853Y1438034I1769J-1768D01*
G02X1118354Y1435532I-1J-2502D01*
G02X1117622Y1433763I-2501J-1D01*
G01X1114512Y1430653D01*
Y1427995D01*
G03X1115109Y1427647I400J0D01*
G02X1115853Y1427844I744J-1306D01*
G02X1117355Y1426342I0J-1502D01*
G02X1117104Y1425511I-1501J0D01*
G01Y1413217D01*
X1121438Y1408884D01*
X1198052D01*
G02X1198937Y1408517I0J-1251D01*
G01X1242423Y1365030D01*
X1271673D01*
G02X1272558Y1364664I1J-1251D01*
G01X1274709Y1362513D01*
G03X1275391Y1362816I283J283D01*
G02X1275389Y1362891I1500J78D01*
G02X1276891Y1361389I1502J0D01*
G02X1276816Y1361391I3J1502D01*
G03X1276513Y1360709I-20J-399D01*
G01X1276741Y1360481D01*
G02X1277108Y1359596I-884J-885D01*
G01Y1358930D01*
X1277137Y1358882D01*
G02X1277358Y1358098I-1280J-784D01*
G02X1275856Y1356596I-1502J0D01*
G02X1274825Y1357006I0J1501D01*
G03X1274198Y1356903I-274J-291D01*
G02X1271990Y1355578I-2208J1177D01*
G02X1270221Y1356310I-1J2501D01*
G01X1268901Y1357630D01*
X1240320D01*
G02X1238551Y1358363I0J2501D01*
G01X1195864Y1401050D01*
X1119812D01*
G02X1118043Y1401783I0J2501D01*
G01X1110241Y1409585D01*
G02X1109508Y1411354I1768J1769D01*
G01Y1431689D01*
G02X1110241Y1433458I2501J0D01*
G37*
G36*
G01X1146231Y1440823D02*
G02X1145701Y1441968I972J1145D01*
G02X1148705I1502J0D01*
G01Y1441948D01*
G03X1149202Y1441555I400J-5D01*
G02X1149569Y1441600I365J-1457D01*
G02X1149775Y1441586I1J-1502D01*
G03X1150216Y1441880I54J396D01*
G02X1151669Y1443000I1453J-383D01*
G02X1153171Y1441498I0J-1502D01*
G02X1152641Y1440353I-1502J0D01*
G03Y1439743I259J-305D01*
G02Y1437453I-972J-1145D01*
G03Y1436843I259J-305D01*
G02X1153171Y1435698I-972J-1145D01*
G02X1151669Y1434196I-1502J0D01*
G02X1150213Y1435328I0J1502D01*
G03X1149751Y1435623I-388J-98D01*
G02X1149469Y1435596I-284J1475D01*
G02X1148533Y1435923I0J1503D01*
G03X1147915Y1435765I-249J-313D01*
G02X1146563Y1434867I-1352J569D01*
G02X1145987Y1434985I0J1467D01*
G03X1145488Y1434824I-157J-368D01*
G02X1142978I-1255J760D01*
G03X1142479Y1434985I-342J-207D01*
G02X1141903Y1434867I-576J1349D01*
G02X1141327Y1434985I0J1467D01*
G03X1140828Y1434824I-157J-368D01*
G02X1139573Y1434117I-1255J760D01*
G02Y1437051I0J1467D01*
G02X1140149Y1436933I0J-1467D01*
G03X1140648Y1437094I157J368D01*
G02X1143158I1255J-760D01*
G03X1143657Y1436933I342J207D01*
G02X1144233Y1437051I576J-1349D01*
G02X1144809Y1436933I0J-1467D01*
G03X1145308Y1437094I157J368D01*
G02X1145849Y1437615I1254J-761D01*
G03X1145980Y1438197I-195J350D01*
G02X1145701Y1439068I1223J872D01*
G02X1146231Y1440213I1502J0D01*
G03Y1440823I-259J305D01*
G37*
G36*
G01X1390563Y1446034D02*
G02X1389220Y1445206I-1343J675D01*
G02Y1448210I0J1502D01*
G02X1390563Y1447382I0J-1503D01*
G03X1391277I357J179D01*
G02X1392620Y1448210I1343J-675D01*
G02Y1445206I0J-1502D01*
G02X1391277Y1446034I0J1503D01*
G03X1390563I-357J-179D01*
G37*
G36*
G01X1659045Y1467468D02*
G03X1659675I315J246D01*
G02X1660860Y1468047I1185J-923D01*
G02X1662362Y1466545I0J-1502D01*
G02X1661992Y1465558I-1501J0D01*
G03Y1465032I302J-263D01*
G02Y1463058I-1131J-987D01*
G03Y1462532I302J-263D01*
G02Y1460558I-1131J-987D01*
G03Y1460032I302J-263D01*
G02X1662362Y1459045I-1131J-987D01*
G02X1661896Y1457957I-1503J0D01*
G03X1661915Y1457361I276J-290D01*
G02X1662452Y1456210I-965J-1151D01*
G02X1661953Y1455092I-1502J0D01*
G03X1661946Y1454502I267J-298D01*
G02X1662422Y1453405I-1026J-1097D01*
G02X1660920Y1451903I-1502J0D01*
G02X1659735Y1452482I0J1502D01*
G03X1659105I-315J-246D01*
G02X1657920Y1451903I-1185J923D01*
G02X1656693Y1452538I0J1503D01*
G03X1656141Y1452638I-327J-230D01*
G02X1655295Y1452377I-846J1241D01*
G02X1654110Y1452956I0J1502D01*
G03X1653480I-315J-246D01*
G02X1652295Y1452377I-1185J923D01*
G02X1650793Y1453879I0J1502D01*
G02X1651382Y1455071I1501J0D01*
G03Y1455707I-243J318D01*
G02X1650793Y1456899I912J1192D01*
G02X1652295Y1458401I1502J0D01*
G02X1653480Y1457822I0J-1502D01*
G03X1654110I315J246D01*
G02X1655295Y1458401I1185J-923D01*
G02X1655849Y1458295I0J-1501D01*
G03X1656388Y1458747I147J372D01*
G02X1656358Y1459045I1472J299D01*
G02X1656728Y1460032I1501J0D01*
G03Y1460558I-302J263D01*
G02Y1462532I1131J987D01*
G03Y1463058I-302J263D01*
G02Y1465032I1131J987D01*
G03Y1465558I-302J263D01*
G02X1656358Y1466545I1131J987D01*
G02X1657860Y1468047I1502J0D01*
G02X1659045Y1467468I0J-1502D01*
G37*
G36*
G01X1157571Y1470176D02*
G03X1158201I315J246D01*
G02X1159386Y1470755I1185J-923D01*
G02X1160888Y1469253I0J-1502D01*
G02X1160518Y1468266I-1501J0D01*
G03Y1467740I302J-263D01*
G02Y1465766I-1131J-987D01*
G03Y1465240I302J-263D01*
G02Y1463266I-1131J-987D01*
G03Y1462740I302J-263D01*
G02X1160888Y1461753I-1131J-987D01*
G02X1160422Y1460665I-1503J0D01*
G03X1160441Y1460069I276J-290D01*
G02X1160978Y1458918I-965J-1151D01*
G02X1160479Y1457800I-1502J0D01*
G03X1160472Y1457210I267J-298D01*
G02X1160948Y1456113I-1026J-1097D01*
G02X1159446Y1454611I-1502J0D01*
G02X1158261Y1455190I0J1502D01*
G03X1157631I-315J-246D01*
G02X1156446Y1454611I-1185J923D01*
G02X1155219Y1455246I0J1503D01*
G03X1154667Y1455346I-327J-230D01*
G02X1153821Y1455085I-846J1241D01*
G02X1152636Y1455664I0J1502D01*
G03X1152006I-315J-246D01*
G02X1150821Y1455085I-1185J923D01*
G02X1149319Y1456587I0J1502D01*
G02X1149908Y1457779I1501J0D01*
G03Y1458415I-243J318D01*
G02X1149319Y1459607I912J1192D01*
G02X1150821Y1461109I1502J0D01*
G02X1152006Y1460530I0J-1502D01*
G03X1152636I315J246D01*
G02X1153821Y1461109I1185J-923D01*
G02X1154375Y1461003I0J-1501D01*
G03X1154914Y1461455I147J372D01*
G02X1154884Y1461753I1472J299D01*
G02X1155254Y1462740I1501J0D01*
G03Y1463266I-302J263D01*
G02Y1465240I1131J987D01*
G03Y1465766I-302J263D01*
G02Y1467740I1131J987D01*
G03Y1468266I-302J263D01*
G02X1154884Y1469253I1131J987D01*
G02X1156386Y1470755I1502J0D01*
G02X1157571Y1470176I0J-1502D01*
G37*
G36*
G01X1324571Y174667D02*
G03X1324401Y175178I-365J162D01*
G02X1323683Y176402I684J1224D01*
G02X1326487I1402J0D01*
G02X1326367Y175834I-1402J0D01*
G03X1326537Y175323I365J-162D01*
G02X1327255Y174099I-684J-1224D01*
G02X1324451I-1402J0D01*
G02X1324571Y174667I1402J0D01*
G37*
G36*
G01X1336768Y196861D02*
G03X1336658Y197436I-323J236D01*
G02X1336000Y198624I743J1188D01*
G02X1338804I1402J0D01*
G02X1338535Y197798I-1403J0D01*
G03X1338645Y197223I323J-236D01*
G02X1339303Y196035I-743J-1188D01*
G02X1336499I-1402J0D01*
G02X1336768Y196861I1403J0D01*
G37*
G36*
G01X1338808Y200790D02*
G03X1338280Y200786I-262J-302D01*
G02X1337345Y200429I-935J1046D01*
G02Y203233I0J1402D01*
G02X1338264Y202890I0J-1403D01*
G03X1338792Y202894I262J302D01*
G02X1339727Y203251I935J-1046D01*
G02Y200447I0J-1402D01*
G02X1338808Y200790I0J1403D01*
G37*
G36*
G01X1299354Y236704D02*
G03X1299376Y237214I-296J268D01*
G02X1299091Y238062I1117J847D01*
G02X1301895I1402J0D01*
G02X1301532Y237120I-1402J-1D01*
G03X1301510Y236610I296J-268D01*
G02X1301795Y235762I-1117J-847D01*
G02X1298991I-1402J0D01*
G02X1299354Y236704I1402J1D01*
G37*
G36*
G01X1305929Y256078D02*
G03X1305534Y256472I-400J-6D01*
G02X1304050Y257974I18J1502D01*
G02X1305552Y259476I1502J0D01*
G02X1307054Y257995I0J-1502D01*
G03X1307449Y257601I400J6D01*
G02X1308933Y256099I-18J-1502D01*
G01Y256071D01*
G03X1309322Y255663I400J-8D01*
G02X1310785Y254189I-39J-1501D01*
G03X1311204Y253797I400J8D01*
G02X1311275Y253799I78J-1500D01*
G02X1312768Y252462I0J-1502D01*
G03X1313155Y252107I397J45D01*
G02X1314619Y250605I-38J-1502D01*
G02X1314618Y250541I-1502J-9D01*
G03X1314947Y250130I399J-17D01*
G02X1316187Y248651I-262J-1479D01*
G02X1313183I-1502J0D01*
G02X1313184Y248715I1502J9D01*
G03X1312855Y249126I-399J17D01*
G02X1311624Y250440I262J1479D01*
G03X1311237Y250795I-397J-45D01*
G02X1309773Y252270I38J1502D01*
G03X1309354Y252662I-400J-8D01*
G02X1309283Y252660I-78J1500D01*
G02X1307781Y254162I0J1502D01*
G01Y254190D01*
G03X1307392Y254598I-400J8D01*
G02X1305929Y256078I39J1501D01*
G37*
G36*
G01X1290148Y276728D02*
G03Y277358I-246J315D01*
G02X1289569Y278543I923J1185D01*
G02X1292573I1502J0D01*
G02X1291994Y277358I-1502J0D01*
G03Y276728I246J-315D01*
G02X1292573Y275543I-923J-1185D01*
G02X1289569I-1502J0D01*
G02X1290148Y276728I1502J0D01*
G37*
G36*
G01X1321287Y157129D02*
G02X1321250Y157449I1365J320D01*
G02X1322652Y156047I1402J0D01*
G02X1322319Y156087I0J1402D01*
G03X1321834Y155608I-95J-388D01*
G02X1321871Y155288I-1365J-320D01*
G02X1320469Y156690I-1402J0D01*
G02X1320802Y156650I0J-1402D01*
G03X1321287Y157129I95J388D01*
G37*
G36*
G01X1341659Y158723D02*
G02X1341534Y159301I1277J579D01*
G02X1344338I1402J0D01*
G02X1343479Y158008I-1403J0D01*
G03X1343269Y157475I155J-369D01*
G02X1343388Y157025I-1277J-578D01*
G03X1343857Y156668I398J37D01*
G02X1344103Y156690I247J-1380D01*
G02X1344317Y156674I3J-1402D01*
G03X1344770Y157153I62J395D01*
G02X1344738Y157449I1370J298D01*
G02X1346140Y158851I1402J0D01*
G02X1347368Y158126I0J-1402D01*
G03X1347866Y157948I350J193D01*
G02X1347942Y157976I522J-1301D01*
G03X1348156Y158564I-127J379D01*
G02X1347949Y159298I1195J733D01*
G02X1350753I1402J0D01*
G02X1349795Y157968I-1402J0D01*
G03X1349581Y157380I127J-379D01*
G02X1349788Y156646I-1195J-733D01*
G02X1348386Y155244I-1402J0D01*
G02X1347158Y155969I0J1402D01*
G03X1346660Y156147I-350J-193D01*
G02X1346140Y156047I-520J1302D01*
G02X1345926Y156063I-3J1402D01*
G03X1345473Y155584I-62J-395D01*
G02X1345505Y155288I-1370J-298D01*
G02X1344103Y153886I-1402J0D01*
G02X1342707Y155160I0J1402D01*
G03X1342238Y155517I-398J-37D01*
G02X1341992Y155495I-247J1380D01*
G02X1340858Y156073I0J1401D01*
G03X1340355Y156196I-324J-235D01*
G02X1339727Y156047I-629J1253D01*
G02Y158851I0J1402D01*
G02X1340861Y158273I0J-1401D01*
G03X1341364Y158150I324J235D01*
G02X1341449Y158190I639J-1248D01*
G03X1341659Y158723I-155J369D01*
G37*
G36*
G01X1317821Y187949D02*
G02X1317100Y189174I680J1225D01*
G02X1319904I1402J0D01*
G02X1319183Y187949I-1401J0D01*
G03Y187249I194J-350D01*
G02Y184799I-680J-1225D01*
G03Y184099I194J-350D01*
G02X1319904Y182874I-680J-1225D01*
G02X1317100I-1402J0D01*
G02X1317821Y184099I1401J0D01*
G03Y184799I-194J350D01*
G02Y187249I680J1225D01*
G03Y187949I-194J350D01*
G37*
G36*
G01X1327271D02*
G02X1326550Y189174I680J1225D01*
G02X1327952Y190576I1402J0D01*
G02X1329177Y189855I0J-1401D01*
G03X1329877I350J194D01*
G02X1331102Y190576I1225J-680D01*
G02X1332504Y189174I0J-1402D01*
G02X1331783Y187949I-1401J0D01*
G03Y187249I194J-350D01*
G02Y184799I-680J-1225D01*
G03Y184099I194J-350D01*
G02Y181649I-680J-1225D01*
G03Y180949I194J-350D01*
G02Y178499I-680J-1225D01*
G03Y177799I194J-350D01*
G02X1332327Y177255I-681J-1225D01*
G03X1333027I350J194D01*
G02X1334252Y177976I1225J-680D01*
G02Y175172I0J-1402D01*
G02X1333999Y175195I0J1403D01*
G03X1333559Y174646I-72J-393D01*
G02X1333670Y174099I-1292J-547D01*
G02X1330866I-1402J0D01*
G02X1330989Y174673I1401J0D01*
G03X1330730Y175222I-365J163D01*
G02X1329700Y176574I372J1352D01*
G02X1330421Y177799I1401J0D01*
G03Y178499I-194J350D01*
G02Y180949I680J1225D01*
G03Y181649I-194J350D01*
G02X1329877Y182193I681J1225D01*
G03X1329177I-350J-194D01*
G02X1326727I-1225J680D01*
G03X1326027I-350J-194D01*
G02X1325483Y181649I-1225J681D01*
G03Y180949I194J-350D01*
G02X1326204Y179724I-680J-1225D01*
G02X1323400I-1402J0D01*
G02X1324121Y180949I1401J0D01*
G03Y181649I-194J350D01*
G02Y184099I680J1225D01*
G03Y184799I-194J350D01*
G02X1323400Y186024I680J1225D01*
G02X1324802Y187426I1402J0D01*
G02X1326027Y186705I0J-1401D01*
G03X1326727I350J194D01*
G02X1327271Y187249I1225J-681D01*
G03Y187949I-194J350D01*
G37*
G36*
G01X1326027Y204243D02*
G02X1324802Y203522I-1225J680D01*
G02Y206326I0J1402D01*
G02X1326027Y205605I0J-1401D01*
G03X1326727I350J194D01*
G02X1327952Y206326I1225J-680D01*
G02X1329354Y204924I0J-1402D01*
G02X1328633Y203699I-1401J0D01*
G03Y202999I194J-350D01*
G02Y200549I-680J-1225D01*
G03Y199849I194J-350D01*
G02Y197399I-680J-1225D01*
G03Y196699I194J-350D01*
G02X1329177Y196155I-681J-1225D01*
G03X1329877I350J194D01*
G02X1332327I1225J-680D01*
G03X1333027I350J194D01*
G02X1334252Y196876I1225J-680D01*
G02Y194072I0J-1402D01*
G02X1333027Y194793I0J1401D01*
G03X1332327I-350J-194D01*
G02X1329877I-1225J680D01*
G03X1329177I-350J-194D01*
G02X1326727I-1225J680D01*
G03X1326027I-350J-194D01*
G02X1323577I-1225J680D01*
G03X1322877I-350J-194D01*
G02X1320427I-1225J680D01*
G03X1319727I-350J-194D01*
G02X1317277I-1225J680D01*
G03X1316577I-350J-194D01*
G02X1315352Y194072I-1225J680D01*
G02Y196876I0J1402D01*
G02X1316577Y196155I0J-1401D01*
G03X1317277I350J194D01*
G02X1319727I1225J-680D01*
G03X1320427I350J194D01*
G02X1320971Y196699I1225J-681D01*
G03Y197399I-194J350D01*
G02Y199849I680J1225D01*
G03Y200549I-194J350D01*
G02X1320250Y201774I680J1225D01*
G02X1323054I1402J0D01*
G02X1322333Y200549I-1401J0D01*
G03Y199849I194J-350D01*
G02Y197399I-680J-1225D01*
G03Y196699I194J-350D01*
G02X1322877Y196155I-681J-1225D01*
G03X1323577I350J194D01*
G02X1326027I1225J-680D01*
G03X1326727I350J194D01*
G02X1327271Y196699I1225J-681D01*
G03Y197399I-194J350D01*
G02Y199849I680J1225D01*
G03Y200549I-194J350D01*
G02Y202999I680J1225D01*
G03Y203699I-194J350D01*
G02X1326727Y204243I681J1225D01*
G03X1326027I-350J-194D01*
G37*
G36*
G01X1337746Y205430D02*
G02X1337102Y205273I-645J1245D01*
G02Y208077I0J1402D01*
G02X1338468Y206989I0J-1402D01*
G03X1339042Y206723I390J89D01*
G02X1339686Y206880I645J-1245D01*
G02Y204076I0J-1402D01*
G02X1338320Y205164I0J1402D01*
G03X1337746Y205430I-390J-89D01*
G37*
G36*
G01X1318187Y206774D02*
G02X1318040Y207399I1255J625D01*
G02X1320844I1402J0D01*
G02X1319966Y206098I-1403J0D01*
G03X1319757Y205549I149J-371D01*
G02X1319904Y204924I-1255J-625D01*
G02X1318502Y203522I-1402J0D01*
G02X1317277Y204243I0J1401D01*
G03X1316577I-350J-194D01*
G02X1315352Y203522I-1225J680D01*
G02Y206326I0J1402D01*
G02X1316577Y205605I0J-1401D01*
G03X1317277I350J194D01*
G02X1317978Y206225I1226J-680D01*
G03X1318187Y206774I-149J371D01*
G37*
G36*
G01X1280633Y255396D02*
G02X1280223Y255339I-410J1446D01*
G02Y258343I0J1502D01*
G02X1281641Y257336I0J-1502D01*
G03X1282150Y257090I378J132D01*
G02X1282645Y257174I495J-1419D01*
G02X1284148Y255671I0J-1503D01*
G01Y252271D01*
G02X1283230Y250887I-1502J0D01*
G03X1283156Y250191I156J-368D01*
G02X1283795Y248962I-862J-1229D01*
G02X1280791I-1502J0D01*
G02X1281708Y250345I1501J0D01*
G03X1281782Y251041I-156J368D01*
G02X1281278Y251648I863J1230D01*
G03X1280688Y251812I-364J-166D01*
G02X1279841Y251550I-848J1240D01*
G02Y254554I0J1502D01*
G02X1280553Y254375I1J-1502D01*
G03X1281142Y254727I189J352D01*
G01Y255011D01*
G03X1280633Y255396I-400J0D01*
G37*
G36*
G01X1253194Y305519D02*
G02X1252040Y304978I-1154J960D01*
G02Y307982I0J1502D01*
G02X1253342Y307229I0J-1502D01*
G03X1253996Y307172I347J199D01*
G02X1255150Y307713I1154J-960D01*
G02Y304709I0J-1502D01*
G02X1253848Y305462I0J1502D01*
G03X1253194Y305519I-347J-199D01*
G37*
G36*
G01X1331223Y867920D02*
X1330421Y869310D01*
X1330331Y869327D01*
G02X1329270Y870606I240J1279D01*
G02X1331872I1301J0D01*
G02X1331798Y870174I-1301J1D01*
G01X1331768Y870087D01*
X1332570Y868697D01*
X1332660Y868680D01*
G02X1333721Y867401I-240J-1279D01*
G02X1331119I-1301J0D01*
G02X1331193Y867833I1301J-1D01*
G01X1331223Y867920D01*
G37*
G36*
G01X1338623D02*
X1337821Y869310D01*
X1337731Y869327D01*
G02X1336670Y870606I240J1279D01*
G02X1339272I1301J0D01*
G02X1339198Y870174I-1301J1D01*
G01X1339168Y870087D01*
X1339970Y868697D01*
X1340060Y868680D01*
G02X1341121Y867401I-240J-1279D01*
G02X1338519I-1301J0D01*
G02X1338593Y867833I1301J-1D01*
G01X1338623Y867920D01*
G37*
G36*
G01X1346023D02*
X1345221Y869310D01*
X1345131Y869327D01*
G02X1344070Y870606I240J1279D01*
G02X1346672I1301J0D01*
G02X1346598Y870174I-1301J1D01*
G01X1346568Y870087D01*
X1347370Y868697D01*
X1347460Y868680D01*
G02X1348521Y867401I-240J-1279D01*
G02X1345919I-1301J0D01*
G02X1345993Y867833I1301J-1D01*
G01X1346023Y867920D01*
G37*
G36*
G01X1326721Y871902D02*
X1327523Y873291D01*
X1327493Y873378D01*
G02X1327419Y873810I1227J433D01*
G02X1330021I1301J0D01*
G02X1328960Y872531I-1301J0D01*
G01X1328870Y872514D01*
X1328068Y871125D01*
X1328098Y871038D01*
G02X1328172Y870606I-1227J-433D01*
G02X1325570I-1301J0D01*
G02X1326631Y871885I1301J0D01*
G01X1326721Y871902D01*
G37*
G36*
G01X1334121D02*
X1334923Y873291D01*
X1334893Y873378D01*
G02X1334819Y873810I1227J433D01*
G02X1337421I1301J0D01*
G02X1336360Y872531I-1301J0D01*
G01X1336270Y872514D01*
X1335468Y871125D01*
X1335498Y871038D01*
G02X1335572Y870606I-1227J-433D01*
G02X1332970I-1301J0D01*
G02X1334031Y871885I1301J0D01*
G01X1334121Y871902D01*
G37*
G36*
G01X1341521D02*
X1342323Y873291D01*
X1342293Y873378D01*
G02X1342219Y873810I1227J433D01*
G02X1344821I1301J0D01*
G02X1343760Y872531I-1301J0D01*
G01X1343670Y872514D01*
X1342868Y871125D01*
X1342898Y871038D01*
G02X1342972Y870606I-1227J-433D01*
G02X1340370I-1301J0D01*
G02X1341431Y871885I1301J0D01*
G01X1341521Y871902D01*
G37*
G36*
G01X1348921D02*
X1349723Y873291D01*
X1349693Y873378D01*
G02X1349619Y873810I1227J433D01*
G02X1352221I1301J0D01*
G02X1351160Y872531I-1301J0D01*
G01X1351070Y872514D01*
X1350268Y871125D01*
X1350298Y871038D01*
G02X1350372Y870606I-1227J-433D01*
G02X1347770I-1301J0D01*
G02X1348831Y871885I1301J0D01*
G01X1348921Y871902D01*
G37*
G36*
G01X1353423Y880738D02*
X1352622Y882126D01*
X1352531Y882143D01*
G02X1351469Y883423I240J1280D01*
G02X1354073I1302J0D01*
G02X1353999Y882990I-1302J0D01*
G01X1353968Y882903D01*
X1354768Y881516D01*
X1354859Y881499D01*
G02X1355922Y880219I-239J-1280D01*
G02X1353318I-1302J0D01*
G02X1353392Y880652I1302J0D01*
G01X1353423Y880738D01*
G37*
G36*
G01X1360823D02*
X1360022Y882126D01*
X1359931Y882143D01*
G02X1358869Y883423I240J1280D01*
G02X1361473I1302J0D01*
G02X1361399Y882990I-1302J0D01*
G01X1361368Y882903D01*
X1362168Y881516D01*
X1362259Y881499D01*
G02X1363322Y880219I-239J-1280D01*
G02X1360718I-1302J0D01*
G02X1360792Y880652I1302J0D01*
G01X1360823Y880738D01*
G37*
G36*
G01X1368223D02*
X1367422Y882126D01*
X1367331Y882143D01*
G02X1366269Y883423I240J1280D01*
G02X1368873I1302J0D01*
G02X1368799Y882990I-1302J0D01*
G01X1368768Y882903D01*
X1369568Y881516D01*
X1369659Y881499D01*
G02X1370722Y880219I-239J-1280D01*
G02X1368118I-1302J0D01*
G02X1368192Y880652I1302J0D01*
G01X1368223Y880738D01*
G37*
G36*
G01X1356322Y884720D02*
X1357123Y886107D01*
X1357092Y886194D01*
G02X1357018Y886627I1228J433D01*
G02X1359622I1302J0D01*
G02X1358559Y885347I-1302J0D01*
G01X1358469Y885330D01*
X1357668Y883943D01*
X1357699Y883856D01*
G02X1357773Y883423I-1228J-433D01*
G02X1355169I-1302J0D01*
G02X1356232Y884703I1302J0D01*
G01X1356322Y884720D01*
G37*
G36*
G01X1363722D02*
X1364523Y886107D01*
X1364492Y886194D01*
G02X1364418Y886627I1228J433D01*
G02X1367022I1302J0D01*
G02X1365959Y885347I-1302J0D01*
G01X1365869Y885330D01*
X1365068Y883943D01*
X1365099Y883856D01*
G02X1365173Y883423I-1228J-433D01*
G02X1362569I-1302J0D01*
G02X1363632Y884703I1302J0D01*
G01X1363722Y884720D01*
G37*
G36*
G01X1402057Y948078D02*
G03Y948618I-294J270D01*
G02X1401715Y949498I959J879D01*
G02X1404317I1301J0D01*
G02X1403975Y948618I-1301J-1D01*
G03Y948078I294J-270D01*
G02X1404317Y947198I-959J-879D01*
G02X1401715I-1301J0D01*
G02X1402057Y948078I1301J1D01*
G37*
G36*
G01X1429605Y950018D02*
G03Y950558I-294J270D01*
G02X1429263Y951438I959J879D01*
G02X1431865I1301J0D01*
G02X1431523Y950558I-1301J-1D01*
G03Y950018I294J-270D01*
G02X1431865Y949138I-959J-879D01*
G02X1429263I-1301J0D01*
G02X1429605Y950018I1301J1D01*
G37*
G36*
G01X1441496Y955616D02*
G03X1440932I-282J-284D01*
G02X1440015Y955238I-917J923D01*
G02Y957840I0J1301D01*
G02X1440932Y957462I0J-1301D01*
G03X1441496I282J284D01*
G02X1442413Y957840I917J-923D01*
G02Y955238I0J-1301D01*
G02X1441496Y955616I0J1301D01*
G37*
G36*
G01X1402087Y964514D02*
G03Y965054I-294J270D01*
G02X1401745Y965934I959J879D01*
G02X1404347I1301J0D01*
G02X1404005Y965054I-1301J-1D01*
G03Y964514I294J-270D01*
G02X1404347Y963634I-959J-879D01*
G02X1401745I-1301J0D01*
G02X1402087Y964514I1301J1D01*
G37*
G36*
G01X1429575Y964708D02*
G03Y965248I-294J270D01*
G02X1429233Y966128I959J879D01*
G02X1431835I1301J0D01*
G02X1431493Y965248I-1301J-1D01*
G03Y964708I294J-270D01*
G02X1431835Y963828I-959J-879D01*
G02X1429233I-1301J0D01*
G02X1429575Y964708I1301J1D01*
G37*
G36*
G01X1402087Y978915D02*
G03Y979455I-294J270D01*
G02X1401745Y980335I959J879D01*
G02X1404347I1301J0D01*
G02X1404005Y979455I-1301J-1D01*
G03Y978915I294J-270D01*
G02X1404347Y978035I-959J-879D01*
G02X1401745I-1301J0D01*
G02X1402087Y978915I1301J1D01*
G37*
G36*
G01X1429445Y979788D02*
G03Y980328I-294J270D01*
G02X1429103Y981208I959J879D01*
G02X1431705I1301J0D01*
G02X1431363Y980328I-1301J-1D01*
G03Y979788I294J-270D01*
G02X1431705Y978908I-959J-879D01*
G02X1429103I-1301J0D01*
G02X1429445Y979788I1301J1D01*
G37*
G36*
G01X1392802Y984653D02*
G03X1392240I-281J-284D01*
G02X1391326Y984278I-914J926D01*
G02Y986880I0J1301D01*
G02X1392240Y986505I0J-1301D01*
G03X1392802I281J284D01*
G02X1393716Y986880I914J-926D01*
G02Y984278I0J-1301D01*
G02X1392802Y984653I0J1301D01*
G37*
G36*
G01X1441496Y984656D02*
G03X1440932I-282J-284D01*
G02X1440015Y984278I-917J923D01*
G02Y986880I0J1301D01*
G02X1440932Y986502I0J-1301D01*
G03X1441496I282J284D01*
G02X1442413Y986880I917J-923D01*
G02Y984278I0J-1301D01*
G02X1441496Y984656I0J1301D01*
G37*
G36*
G01X1402087Y993301D02*
G03Y993841I-294J270D01*
G02X1401745Y994721I959J879D01*
G02X1404347I1301J0D01*
G02X1404005Y993841I-1301J-1D01*
G03Y993301I294J-270D01*
G02X1404347Y992421I-959J-879D01*
G02X1401745I-1301J0D01*
G02X1402087Y993301I1301J1D01*
G37*
G36*
G01X1429645Y993878D02*
G03Y994418I-294J270D01*
G02X1429303Y995298I959J879D01*
G02X1431905I1301J0D01*
G02X1431563Y994418I-1301J-1D01*
G03Y993878I294J-270D01*
G02X1431905Y992998I-959J-879D01*
G02X1429303I-1301J0D01*
G02X1429645Y993878I1301J1D01*
G37*
G36*
G01X1392802Y999133D02*
G03X1392240I-281J-284D01*
G02X1391326Y998758I-914J926D01*
G02Y1001360I0J1301D01*
G02X1392240Y1000985I0J-1301D01*
G03X1392802I281J284D01*
G02X1393716Y1001360I914J-926D01*
G02Y998758I0J-1301D01*
G02X1392802Y999133I0J1301D01*
G37*
G36*
G01X1441496Y999136D02*
G03X1440932I-282J-284D01*
G02X1440015Y998758I-917J923D01*
G02Y1001360I0J1301D01*
G02X1440932Y1000982I0J-1301D01*
G03X1441496I282J284D01*
G02X1442413Y1001360I917J-923D01*
G02Y998758I0J-1301D01*
G02X1441496Y999136I0J1301D01*
G37*
G36*
G01X1402087Y1007754D02*
G03Y1008294I-294J270D01*
G02X1401745Y1009174I959J879D01*
G02X1404347I1301J0D01*
G02X1404005Y1008294I-1301J-1D01*
G03Y1007754I294J-270D01*
G02X1404347Y1006874I-959J-879D01*
G02X1401745I-1301J0D01*
G02X1402087Y1007754I1301J1D01*
G37*
G36*
G01X1429625Y1007988D02*
G03Y1008528I-294J270D01*
G02X1429283Y1009408I959J879D01*
G02X1431885I1301J0D01*
G02X1431543Y1008528I-1301J-1D01*
G03Y1007988I294J-270D01*
G02X1431885Y1007108I-959J-879D01*
G02X1429283I-1301J0D01*
G02X1429625Y1007988I1301J1D01*
G37*
G36*
G01X1392802Y1013613D02*
G03X1392240I-281J-284D01*
G02X1391326Y1013238I-914J926D01*
G02Y1015840I0J1301D01*
G02X1392240Y1015465I0J-1301D01*
G03X1392802I281J284D01*
G02X1393716Y1015840I914J-926D01*
G02Y1013238I0J-1301D01*
G02X1392802Y1013613I0J1301D01*
G37*
G36*
G01X1441496Y1013616D02*
G03X1440932I-282J-284D01*
G02X1440015Y1013238I-917J923D01*
G02Y1015840I0J1301D01*
G02X1440932Y1015462I0J-1301D01*
G03X1441496I282J284D01*
G02X1442413Y1015840I917J-923D01*
G02Y1013238I0J-1301D01*
G02X1441496Y1013616I0J1301D01*
G37*
G36*
G01X1402087Y1020542D02*
G03Y1021082I-294J270D01*
G02X1401745Y1021962I959J879D01*
G02X1404347I1301J0D01*
G02X1404005Y1021082I-1301J-1D01*
G03Y1020542I294J-270D01*
G02X1404347Y1019662I-959J-879D01*
G02X1401745I-1301J0D01*
G02X1402087Y1020542I1301J1D01*
G37*
G36*
G01X1429616Y1020765D02*
G03Y1021305I-294J270D01*
G02X1429274Y1022185I959J879D01*
G02X1431876I1301J0D01*
G02X1431534Y1021305I-1301J-1D01*
G03Y1020765I294J-270D01*
G02X1431876Y1019885I-959J-879D01*
G02X1429274I-1301J0D01*
G02X1429616Y1020765I1301J1D01*
G37*
G36*
G01X1394058Y1029736D02*
G03X1394646I294J272D01*
G02X1396558I956J-881D01*
G03X1397146I294J272D01*
G02X1398102Y1030155I956J-881D01*
G02Y1027553I0J-1301D01*
G02X1397146Y1027972I0J1300D01*
G03X1396558I-294J-272D01*
G02X1394646I-956J881D01*
G03X1394058I-294J-272D01*
G02X1392146I-956J881D01*
G03X1391558I-294J-272D01*
G02X1389646I-956J881D01*
G03X1389058I-294J-272D01*
G02X1388102Y1027553I-956J881D01*
G02Y1030155I0J1301D01*
G02X1389058Y1029736I0J-1300D01*
G03X1389646I294J272D01*
G02X1391558I956J-881D01*
G03X1392146I294J272D01*
G02X1394058I956J-881D01*
G37*
G36*
G01X1383507Y1032850D02*
G03Y1033390I-294J270D01*
G02X1383165Y1034270I959J879D01*
G02X1385767I1301J0D01*
G02X1385425Y1033390I-1301J-1D01*
G03Y1032850I294J-270D01*
G02X1385767Y1031970I-959J-879D01*
G02X1383165I-1301J0D01*
G02X1383507Y1032850I1301J1D01*
G37*
G36*
G01X1434850Y1152237D02*
G03X1434324I-263J-302D01*
G02X1433337Y1151867I-987J1131D01*
G02Y1154871I0J1502D01*
G02X1434324Y1154501I0J-1501D01*
G03X1434850I263J302D01*
G02X1435837Y1154871I987J-1131D01*
G02Y1151867I0J-1502D01*
G02X1434850Y1152237I0J1501D01*
G37*
G36*
G01X1434400Y1160437D02*
G03X1433874I-263J-302D01*
G02X1432887Y1160067I-987J1131D01*
G02Y1163071I0J1502D01*
G02X1433874Y1162701I0J-1501D01*
G03X1434400I263J302D01*
G02X1435387Y1163071I987J-1131D01*
G02Y1160067I0J-1502D01*
G02X1434400Y1160437I0J1501D01*
G37*
G36*
G01Y1168937D02*
G03X1433874I-263J-302D01*
G02X1432887Y1168567I-987J1131D01*
G02Y1171571I0J1502D01*
G02X1433874Y1171201I0J-1501D01*
G03X1434400I263J302D01*
G02X1435387Y1171571I987J-1131D01*
G02Y1168567I0J-1502D01*
G02X1434400Y1168937I0J1501D01*
G37*
G36*
G01X1331223Y855103D02*
X1330421Y856493D01*
X1330331Y856510D01*
G02X1329270Y857789I240J1279D01*
G02X1331872I1301J0D01*
G02X1331798Y857357I-1301J1D01*
G01X1331768Y857270D01*
X1332570Y855880D01*
X1332660Y855863D01*
G02X1333721Y854584I-240J-1279D01*
G02X1331119I-1301J0D01*
G02X1331193Y855016I1301J-1D01*
G01X1331223Y855103D01*
G37*
G36*
G01X1338623D02*
X1337821Y856493D01*
X1337731Y856510D01*
G02X1336670Y857789I240J1279D01*
G02X1339272I1301J0D01*
G02X1339198Y857357I-1301J1D01*
G01X1339168Y857270D01*
X1339970Y855880D01*
X1340060Y855863D01*
G02X1341121Y854584I-240J-1279D01*
G02X1338519I-1301J0D01*
G02X1338593Y855016I1301J-1D01*
G01X1338623Y855103D01*
G37*
G36*
G01X1346023D02*
X1345221Y856493D01*
X1345131Y856510D01*
G02X1344070Y857789I240J1279D01*
G02X1346672I1301J0D01*
G02X1346598Y857357I-1301J1D01*
G01X1346568Y857270D01*
X1347370Y855880D01*
X1347460Y855863D01*
G02X1348521Y854584I-240J-1279D01*
G02X1345919I-1301J0D01*
G02X1345993Y855016I1301J-1D01*
G01X1346023Y855103D01*
G37*
G36*
G01X1353423D02*
X1352621Y856493D01*
X1352531Y856510D01*
G02X1351470Y857789I240J1279D01*
G02X1354072I1301J0D01*
G02X1353998Y857357I-1301J1D01*
G01X1353968Y857270D01*
X1354770Y855880D01*
X1354860Y855863D01*
G02X1355921Y854584I-240J-1279D01*
G02X1353319I-1301J0D01*
G02X1353393Y855016I1301J-1D01*
G01X1353423Y855103D01*
G37*
G36*
G01X1360823D02*
X1360021Y856493D01*
X1359931Y856510D01*
G02X1358870Y857789I240J1279D01*
G02X1361472I1301J0D01*
G02X1361398Y857357I-1301J1D01*
G01X1361368Y857270D01*
X1362170Y855880D01*
X1362260Y855863D01*
G02X1363321Y854584I-240J-1279D01*
G02X1360719I-1301J0D01*
G02X1360793Y855016I1301J-1D01*
G01X1360823Y855103D01*
G37*
G36*
G01X1368223D02*
X1367421Y856493D01*
X1367331Y856510D01*
G02X1366270Y857789I240J1279D01*
G02X1368872I1301J0D01*
G02X1368798Y857357I-1301J1D01*
G01X1368768Y857270D01*
X1369570Y855880D01*
X1369660Y855863D01*
G02X1370721Y854584I-240J-1279D01*
G02X1368119I-1301J0D01*
G02X1368193Y855016I1301J-1D01*
G01X1368223Y855103D01*
G37*
G36*
G01X1334121Y859085D02*
X1334923Y860474D01*
X1334893Y860561D01*
G02X1334819Y860993I1227J433D01*
G02X1337421I1301J0D01*
G02X1336360Y859714I-1301J0D01*
G01X1336270Y859697D01*
X1335468Y858308D01*
X1335498Y858221D01*
G02X1335572Y857789I-1227J-433D01*
G02X1332970I-1301J0D01*
G02X1334031Y859068I1301J0D01*
G01X1334121Y859085D01*
G37*
G36*
G01X1341521D02*
X1342323Y860474D01*
X1342293Y860561D01*
G02X1342219Y860993I1227J433D01*
G02X1344821I1301J0D01*
G02X1343760Y859714I-1301J0D01*
G01X1343670Y859697D01*
X1342868Y858308D01*
X1342898Y858221D01*
G02X1342972Y857789I-1227J-433D01*
G02X1340370I-1301J0D01*
G02X1341431Y859068I1301J0D01*
G01X1341521Y859085D01*
G37*
G36*
G01X1348921D02*
X1349723Y860474D01*
X1349693Y860561D01*
G02X1349619Y860993I1227J433D01*
G02X1352221I1301J0D01*
G02X1351160Y859714I-1301J0D01*
G01X1351070Y859697D01*
X1350268Y858308D01*
X1350298Y858221D01*
G02X1350372Y857789I-1227J-433D01*
G02X1347770I-1301J0D01*
G02X1348831Y859068I1301J0D01*
G01X1348921Y859085D01*
G37*
G36*
G01X1356321D02*
X1357123Y860474D01*
X1357093Y860561D01*
G02X1357019Y860993I1227J433D01*
G02X1359621I1301J0D01*
G02X1358560Y859714I-1301J0D01*
G01X1358470Y859697D01*
X1357668Y858308D01*
X1357698Y858221D01*
G02X1357772Y857789I-1227J-433D01*
G02X1355170I-1301J0D01*
G02X1356231Y859068I1301J0D01*
G01X1356321Y859085D01*
G37*
G36*
G01X1363721D02*
X1364523Y860474D01*
X1364493Y860561D01*
G02X1364419Y860993I1227J433D01*
G02X1367021I1301J0D01*
G02X1365960Y859714I-1301J0D01*
G01X1365870Y859697D01*
X1365068Y858308D01*
X1365098Y858221D01*
G02X1365172Y857789I-1227J-433D01*
G02X1362570I-1301J0D01*
G02X1363631Y859068I1301J0D01*
G01X1363721Y859085D01*
G37*
G36*
G01X1368223Y867920D02*
X1367421Y869310D01*
X1367331Y869327D01*
G02X1366270Y870606I240J1279D01*
G02X1368872I1301J0D01*
G02X1368798Y870174I-1301J1D01*
G01X1368768Y870087D01*
X1369570Y868697D01*
X1369660Y868680D01*
G02X1370721Y867401I-240J-1279D01*
G02X1368119I-1301J0D01*
G02X1368193Y867833I1301J-1D01*
G01X1368223Y867920D01*
G37*
G36*
G01X1375623D02*
X1374821Y869310D01*
X1374731Y869327D01*
G02X1373670Y870606I240J1279D01*
G02X1376272I1301J0D01*
G02X1376198Y870174I-1301J1D01*
G01X1376168Y870087D01*
X1376970Y868697D01*
X1377060Y868680D01*
G02X1378121Y867401I-240J-1279D01*
G02X1375519I-1301J0D01*
G02X1375593Y867833I1301J-1D01*
G01X1375623Y867920D01*
G37*
G36*
G01X1363721Y871902D02*
X1364523Y873291D01*
X1364493Y873378D01*
G02X1364419Y873810I1227J433D01*
G02X1367021I1301J0D01*
G02X1365960Y872531I-1301J0D01*
G01X1365870Y872514D01*
X1365068Y871125D01*
X1365098Y871038D01*
G02X1365172Y870606I-1227J-433D01*
G02X1362570I-1301J0D01*
G02X1363631Y871885I1301J0D01*
G01X1363721Y871902D01*
G37*
G36*
G01X1371121D02*
X1371923Y873291D01*
X1371893Y873378D01*
G02X1371819Y873810I1227J433D01*
G02X1374421I1301J0D01*
G02X1373360Y872531I-1301J0D01*
G01X1373270Y872514D01*
X1372468Y871125D01*
X1372498Y871038D01*
G02X1372572Y870606I-1227J-433D01*
G02X1369970I-1301J0D01*
G02X1371031Y871885I1301J0D01*
G01X1371121Y871902D01*
G37*
G36*
G01X1378521D02*
X1379323Y873291D01*
X1379293Y873378D01*
G02X1379219Y873810I1227J433D01*
G02X1381821I1301J0D01*
G02X1380760Y872531I-1301J0D01*
G01X1380670Y872514D01*
X1379868Y871125D01*
X1379898Y871038D01*
G02X1379972Y870606I-1227J-433D01*
G02X1377370I-1301J0D01*
G02X1378431Y871885I1301J0D01*
G01X1378521Y871902D01*
G37*
G36*
G01X1378522Y884720D02*
X1379323Y886107D01*
X1379292Y886194D01*
G02X1379218Y886627I1228J433D01*
G02X1381822I1302J0D01*
G02X1380759Y885347I-1302J0D01*
G01X1380669Y885330D01*
X1379868Y883943D01*
X1379899Y883856D01*
G02X1379973Y883423I-1228J-433D01*
G02X1377369I-1302J0D01*
G02X1378432Y884703I1302J0D01*
G01X1378522Y884720D01*
G37*
G36*
G01X1381070Y857789D02*
G02X1383672I1301J0D01*
G02X1383598Y857357I-1301J1D01*
G01X1383568Y857270D01*
X1384370Y855880D01*
X1384460Y855863D01*
G02X1385521Y854584I-240J-1279D01*
G02X1382919I-1301J0D01*
G02X1382993Y855016I1301J-1D01*
G01X1383023Y855103D01*
X1382221Y856493D01*
X1382131Y856510D01*
G02X1381070Y857789I240J1279D01*
G37*
G36*
G01X1388470D02*
G02X1391072I1301J0D01*
G02X1390998Y857357I-1301J1D01*
G01X1390968Y857270D01*
X1391770Y855880D01*
X1391860Y855863D01*
G02X1392921Y854584I-240J-1279D01*
G02X1390319I-1301J0D01*
G02X1390393Y855016I1301J-1D01*
G01X1390423Y855103D01*
X1389621Y856493D01*
X1389531Y856510D01*
G02X1388470Y857789I240J1279D01*
G37*
G36*
G01X1379219Y860993D02*
G02X1381821I1301J0D01*
G02X1380760Y859714I-1301J0D01*
G01X1380670Y859697D01*
X1379868Y858308D01*
X1379898Y858221D01*
G02X1379972Y857789I-1227J-433D01*
G02X1377370I-1301J0D01*
G02X1378431Y859068I1301J0D01*
G01X1378521Y859085D01*
X1379323Y860474D01*
X1379293Y860561D01*
G02X1379219Y860993I1227J433D01*
G37*
G36*
G01X1386619D02*
G02X1389221I1301J0D01*
G02X1388160Y859714I-1301J0D01*
G01X1388070Y859697D01*
X1387268Y858308D01*
X1387298Y858221D01*
G02X1387372Y857789I-1227J-433D01*
G02X1384770I-1301J0D01*
G02X1385831Y859068I1301J0D01*
G01X1385921Y859085D01*
X1386723Y860474D01*
X1386693Y860561D01*
G02X1386619Y860993I1227J433D01*
G37*
G36*
G01X1394019D02*
G02X1396621I1301J0D01*
G02X1395560Y859714I-1301J0D01*
G01X1395470Y859697D01*
X1394668Y858308D01*
X1394698Y858221D01*
G02X1394772Y857789I-1227J-433D01*
G02X1392170I-1301J0D01*
G02X1393231Y859068I1301J0D01*
G01X1393321Y859085D01*
X1394123Y860474D01*
X1394093Y860561D01*
G02X1394019Y860993I1227J433D01*
G37*
G36*
G01X1392170Y870606D02*
G02X1394772I1301J0D01*
G02X1393711Y869327I-1301J0D01*
G01X1393621Y869310D01*
X1392817Y867918D01*
X1392848Y867832D01*
G02X1392921Y867404I-1228J-430D01*
G01Y867401D01*
G02X1390319I-1301J0D01*
G02X1391381Y868680I1301J0D01*
G01X1391472Y868697D01*
X1392274Y870087D01*
X1392244Y870174D01*
G02X1392170Y870606I1227J433D01*
G37*
G36*
G01X1380044Y987301D02*
G03Y987841I-294J270D01*
G02X1379702Y988721I959J879D01*
G02X1382304I1301J0D01*
G02X1381962Y987841I-1301J-1D01*
G03Y987301I294J-270D01*
G02X1382304Y986421I-959J-879D01*
G02X1379702I-1301J0D01*
G02X1380044Y987301I1301J1D01*
G37*
G36*
G01X1380284Y993851D02*
G03Y994391I-294J270D01*
G02X1379942Y995271I959J879D01*
G02X1382544I1301J0D01*
G02X1382202Y994391I-1301J-1D01*
G03Y993851I294J-270D01*
G02X1382544Y992971I-959J-879D01*
G02X1379942I-1301J0D01*
G02X1380284Y993851I1301J1D01*
G37*
G36*
G01X1379596Y1007298D02*
G03X1380128Y1007547I151J370D01*
G02X1381369Y1008457I1241J-391D01*
G02X1382670Y1007156I0J-1301D01*
G02X1382326Y1006275I-1300J0D01*
G03X1382327Y1005732I294J-271D01*
G02X1382674Y1004848I-954J-885D01*
G02X1381373Y1003547I-1301J0D01*
G02X1380099Y1004584I0J1301D01*
G03X1379566Y1004877I-392J-81D01*
G02X1379104Y1004792I-463J1216D01*
G02Y1007394I0J1301D01*
G02X1379596Y1007298I1J-1301D01*
G37*
G36*
G01X1379423Y965673D02*
G02X1378671Y965434I-752J1062D01*
G02Y968036I0J1301D01*
G02X1379902Y967155I0J-1301D01*
G03X1380512Y966958I379J129D01*
G02X1381264Y967197I752J-1062D01*
G02X1382565Y965896I0J-1301D01*
G02X1382223Y965016I-1301J-1D01*
G03Y964476I294J-270D01*
G02X1382565Y963596I-959J-879D01*
G02X1379963I-1301J0D01*
G02X1380305Y964476I1301J1D01*
G03Y965016I-294J270D01*
G02X1380033Y965476I960J878D01*
G03X1379423Y965673I-379J-129D01*
G37*
G36*
G01X1607012Y748156D02*
X1611912D01*
G02Y740952I0J-3602D01*
G01X1607012D01*
G02Y748156I0J3602D01*
G37*
G36*
G01X1666412D02*
X1671312D01*
G02Y740952I0J-3602D01*
G01X1666412D01*
G02Y748156I0J3602D01*
G37*
G36*
G01X1725812D02*
X1730712D01*
G02Y740952I0J-3602D01*
G01X1725812D01*
G02Y748156I0J3602D01*
G37*
G36*
G01X1636712D02*
X1641612D01*
G02Y740952I0J-3602D01*
G01X1636712D01*
G02Y748156I0J3602D01*
G37*
G36*
G01X1708021Y727412D02*
G03X1707414Y727379I-289J-276D01*
G02X1705035Y726208I-2379J1831D01*
G02Y732212I0J3002D01*
G02X1707915Y730058I0J-3002D01*
G03X1708469Y729809I384J113D01*
G02X1709107Y729951I638J-1360D01*
G02Y726947I0J-1502D01*
G02X1708021Y727412I0J1501D01*
G37*
G36*
G01X1593881Y737651D02*
G03X1594479I299J266D01*
G02X1595600Y738154I1121J-998D01*
G02X1596707Y737667I0J-1502D01*
G03X1597305Y737675I295J270D01*
G02X1598440Y738194I1136J-983D01*
G02Y735190I0J-1502D01*
G02X1597333Y735677I0J1502D01*
G03X1596735Y735669I-295J-270D01*
G02X1595600Y735150I-1136J983D01*
G02X1594479Y735653I0J1501D01*
G03X1593881I-299J-266D01*
G02X1592760Y735150I-1121J998D01*
G02Y738154I0J1502D01*
G02X1593881Y737651I0J-1501D01*
G37*
G36*
G01X1480272Y855880D02*
X1481074Y857270D01*
X1481044Y857357D01*
G02X1480970Y857789I1227J433D01*
G02X1483572I1301J0D01*
G02X1482511Y856510I-1301J0D01*
G01X1482421Y856493D01*
X1481617Y855101D01*
X1481648Y855015D01*
G02X1481721Y854584I-1228J-430D01*
G02X1479119I-1301J0D01*
G02X1480181Y855863I1301J0D01*
G01X1480272Y855880D01*
G37*
G36*
G01X1487672D02*
X1488474Y857270D01*
X1488444Y857357D01*
G02X1488370Y857789I1227J433D01*
G02X1490972I1301J0D01*
G02X1489911Y856510I-1301J0D01*
G01X1489821Y856493D01*
X1489017Y855101D01*
X1489048Y855015D01*
G02X1489121Y854584I-1228J-430D01*
G02X1486519I-1301J0D01*
G02X1487581Y855863I1301J0D01*
G01X1487672Y855880D01*
G37*
G36*
G01X1495072D02*
X1495874Y857270D01*
X1495844Y857357D01*
G02X1495770Y857789I1227J433D01*
G02X1498372I1301J0D01*
G02X1497311Y856510I-1301J0D01*
G01X1497221Y856493D01*
X1496417Y855101D01*
X1496448Y855015D01*
G02X1496521Y854584I-1228J-430D01*
G02X1493919I-1301J0D01*
G02X1494981Y855863I1301J0D01*
G01X1495072Y855880D01*
G37*
G36*
G01X1502472D02*
X1503274Y857270D01*
X1503244Y857357D01*
G02X1503170Y857789I1227J433D01*
G02X1505772I1301J0D01*
G02X1504711Y856510I-1301J0D01*
G01X1504621Y856493D01*
X1503817Y855101D01*
X1503848Y855015D01*
G02X1503921Y854584I-1228J-430D01*
G02X1501319I-1301J0D01*
G02X1502381Y855863I1301J0D01*
G01X1502472Y855880D01*
G37*
G36*
G01X1477373Y858305D02*
X1476570Y859697D01*
X1476480Y859714D01*
G02X1475419Y860993I240J1279D01*
G02X1478021I1301J0D01*
G02X1477947Y860561I-1301J1D01*
G01X1477917Y860474D01*
X1478718Y859085D01*
X1478809Y859068D01*
G02X1479872Y857789I-238J-1279D01*
G02X1477270I-1301J0D01*
G02X1477343Y858219I1301J0D01*
G01X1477373Y858305D01*
G37*
G36*
G01X1484773D02*
X1483970Y859697D01*
X1483880Y859714D01*
G02X1482819Y860993I240J1279D01*
G02X1485421I1301J0D01*
G02X1485347Y860561I-1301J1D01*
G01X1485317Y860474D01*
X1486118Y859085D01*
X1486209Y859068D01*
G02X1487272Y857789I-238J-1279D01*
G02X1484670I-1301J0D01*
G02X1484743Y858219I1301J0D01*
G01X1484773Y858305D01*
G37*
G36*
G01X1492173D02*
X1491370Y859697D01*
X1491280Y859714D01*
G02X1490219Y860993I240J1279D01*
G02X1492821I1301J0D01*
G02X1492747Y860561I-1301J1D01*
G01X1492717Y860474D01*
X1493518Y859085D01*
X1493609Y859068D01*
G02X1494672Y857789I-238J-1279D01*
G02X1492070I-1301J0D01*
G02X1492143Y858219I1301J0D01*
G01X1492173Y858305D01*
G37*
G36*
G01X1499573D02*
X1498770Y859697D01*
X1498680Y859714D01*
G02X1497619Y860993I240J1279D01*
G02X1500221I1301J0D01*
G02X1500147Y860561I-1301J1D01*
G01X1500117Y860474D01*
X1500918Y859085D01*
X1501009Y859068D01*
G02X1502072Y857789I-238J-1279D01*
G02X1499470I-1301J0D01*
G02X1499543Y858219I1301J0D01*
G01X1499573Y858305D01*
G37*
G36*
G01X1472872Y868697D02*
X1473674Y870087D01*
X1473644Y870174D01*
G02X1473570Y870606I1227J433D01*
G02X1476172I1301J0D01*
G02X1475111Y869327I-1301J0D01*
G01X1475021Y869310D01*
X1474217Y867918D01*
X1474248Y867832D01*
G02X1474321Y867401I-1228J-430D01*
G02X1471719I-1301J0D01*
G02X1472781Y868680I1301J0D01*
G01X1472872Y868697D01*
G37*
G36*
G01X1480272D02*
X1481074Y870087D01*
X1481044Y870174D01*
G02X1480970Y870606I1227J433D01*
G02X1483572I1301J0D01*
G02X1482511Y869327I-1301J0D01*
G01X1482421Y869310D01*
X1481617Y867918D01*
X1481648Y867832D01*
G02X1481721Y867401I-1228J-430D01*
G02X1479119I-1301J0D01*
G02X1480181Y868680I1301J0D01*
G01X1480272Y868697D01*
G37*
G36*
G01X1487672D02*
X1488474Y870087D01*
X1488444Y870174D01*
G02X1488370Y870606I1227J433D01*
G02X1490972I1301J0D01*
G02X1489911Y869327I-1301J0D01*
G01X1489821Y869310D01*
X1489017Y867918D01*
X1489048Y867832D01*
G02X1489121Y867401I-1228J-430D01*
G02X1486519I-1301J0D01*
G02X1487581Y868680I1301J0D01*
G01X1487672Y868697D01*
G37*
G36*
G01X1495072D02*
X1495874Y870087D01*
X1495844Y870174D01*
G02X1495770Y870606I1227J433D01*
G02X1498372I1301J0D01*
G02X1497311Y869327I-1301J0D01*
G01X1497221Y869310D01*
X1496417Y867918D01*
X1496448Y867832D01*
G02X1496521Y867401I-1228J-430D01*
G02X1493919I-1301J0D01*
G02X1494981Y868680I1301J0D01*
G01X1495072Y868697D01*
G37*
G36*
G01X1469973Y871122D02*
X1469170Y872514D01*
X1469080Y872531D01*
G02X1468019Y873810I240J1279D01*
G02X1470621I1301J0D01*
G02X1470547Y873378I-1301J1D01*
G01X1470517Y873291D01*
X1471318Y871902D01*
X1471409Y871885D01*
G02X1472472Y870606I-238J-1279D01*
G02X1469870I-1301J0D01*
G02X1469943Y871036I1301J0D01*
G01X1469973Y871122D01*
G37*
G36*
G01X1477373D02*
X1476570Y872514D01*
X1476480Y872531D01*
G02X1475419Y873810I240J1279D01*
G02X1478021I1301J0D01*
G02X1477947Y873378I-1301J1D01*
G01X1477917Y873291D01*
X1478718Y871902D01*
X1478809Y871885D01*
G02X1479872Y870606I-238J-1279D01*
G02X1477270I-1301J0D01*
G02X1477343Y871036I1301J0D01*
G01X1477373Y871122D01*
G37*
G36*
G01X1484773D02*
X1483970Y872514D01*
X1483880Y872531D01*
G02X1482819Y873810I240J1279D01*
G02X1485421I1301J0D01*
G02X1485347Y873378I-1301J1D01*
G01X1485317Y873291D01*
X1486118Y871902D01*
X1486209Y871885D01*
G02X1487272Y870606I-238J-1279D01*
G02X1484670I-1301J0D01*
G02X1484743Y871036I1301J0D01*
G01X1484773Y871122D01*
G37*
G36*
G01X1492173D02*
X1491370Y872514D01*
X1491280Y872531D01*
G02X1490219Y873810I240J1279D01*
G02X1492821I1301J0D01*
G02X1492747Y873378I-1301J1D01*
G01X1492717Y873291D01*
X1493518Y871902D01*
X1493609Y871885D01*
G02X1494672Y870606I-238J-1279D01*
G02X1492070I-1301J0D01*
G02X1492143Y871036I1301J0D01*
G01X1492173Y871122D01*
G37*
G36*
G01X1499573D02*
X1498771Y872514D01*
X1498680Y872531D01*
G02X1497619Y873810I240J1279D01*
G02X1500221I1301J0D01*
G02X1500147Y873378I-1301J1D01*
G01X1500117Y873291D01*
X1500918Y871902D01*
X1501009Y871885D01*
G02X1502072Y870606I-238J-1279D01*
G02X1499470I-1301J0D01*
G02X1499543Y871035I1301J-1D01*
G01X1499573Y871122D01*
G37*
G36*
G01X1464423Y880737D02*
X1463621Y882127D01*
X1463531Y882144D01*
G02X1462470Y883423I240J1279D01*
G02X1465072I1301J0D01*
G02X1464998Y882991I-1301J1D01*
G01X1464968Y882904D01*
X1465769Y881515D01*
X1465860Y881498D01*
G02X1466921Y880219I-240J-1279D01*
G02X1464319I-1301J0D01*
G02X1464393Y880651I1301J-1D01*
G01X1464423Y880737D01*
G37*
G36*
G01X1471823D02*
X1471021Y882127D01*
X1470931Y882144D01*
G02X1469870Y883423I240J1279D01*
G02X1472472I1301J0D01*
G02X1472398Y882991I-1301J1D01*
G01X1472368Y882904D01*
X1473169Y881515D01*
X1473260Y881498D01*
G02X1474321Y880219I-240J-1279D01*
G02X1471719I-1301J0D01*
G02X1471793Y880651I1301J-1D01*
G01X1471823Y880737D01*
G37*
G36*
G01X1479223D02*
X1478421Y882127D01*
X1478331Y882144D01*
G02X1477270Y883423I240J1279D01*
G02X1479872I1301J0D01*
G02X1479798Y882991I-1301J1D01*
G01X1479768Y882904D01*
X1480569Y881515D01*
X1480660Y881498D01*
G02X1481721Y880219I-240J-1279D01*
G02X1479119I-1301J0D01*
G02X1479193Y880651I1301J-1D01*
G01X1479223Y880737D01*
G37*
G36*
G01X1486623D02*
X1485821Y882127D01*
X1485731Y882144D01*
G02X1484670Y883423I240J1279D01*
G02X1487272I1301J0D01*
G02X1487198Y882991I-1301J1D01*
G01X1487168Y882904D01*
X1487969Y881515D01*
X1488060Y881498D01*
G02X1489121Y880219I-240J-1279D01*
G02X1486519I-1301J0D01*
G02X1486593Y880651I1301J-1D01*
G01X1486623Y880737D01*
G37*
G36*
G01X1494023D02*
X1493222Y882127D01*
X1493131Y882144D01*
G02X1492070Y883423I240J1279D01*
G02X1494672I1301J0D01*
G02X1494598Y882991I-1301J1D01*
G01X1494568Y882904D01*
X1495369Y881515D01*
X1495460Y881498D01*
G02X1496521Y880219I-240J-1279D01*
G02X1493919I-1301J0D01*
G02X1493993Y880650I1301J-1D01*
G01X1494023Y880737D01*
G37*
G36*
G01X1501424Y880736D02*
X1500622Y882127D01*
X1500531Y882144D01*
G02X1499470Y883423I240J1279D01*
G02X1502072I1301J0D01*
G02X1501998Y882991I-1301J1D01*
G01X1501968Y882904D01*
X1502769Y881515D01*
X1502860Y881498D01*
G02X1503922Y880219I-239J-1279D01*
G02X1501320I-1301J0D01*
G02X1501393Y880650I1301J1D01*
G01X1501424Y880736D01*
G37*
G36*
G01X1467321Y884719D02*
X1468123Y886108D01*
X1468093Y886195D01*
G02X1468019Y886627I1227J433D01*
G02X1470621I1301J0D01*
G02X1469560Y885348I-1301J0D01*
G01X1469470Y885331D01*
X1468668Y883942D01*
X1468698Y883855D01*
G02X1468772Y883423I-1227J-433D01*
G02X1466170I-1301J0D01*
G02X1467231Y884702I1301J0D01*
G01X1467321Y884719D01*
G37*
G36*
G01X1474721D02*
X1475523Y886108D01*
X1475493Y886195D01*
G02X1475419Y886627I1227J433D01*
G02X1478021I1301J0D01*
G02X1476960Y885348I-1301J0D01*
G01X1476870Y885331D01*
X1476068Y883942D01*
X1476098Y883855D01*
G02X1476172Y883423I-1227J-433D01*
G02X1473570I-1301J0D01*
G02X1474631Y884702I1301J0D01*
G01X1474721Y884719D01*
G37*
G36*
G01X1482121D02*
X1482923Y886108D01*
X1482893Y886195D01*
G02X1482819Y886627I1227J433D01*
G02X1485421I1301J0D01*
G02X1484360Y885348I-1301J0D01*
G01X1484270Y885331D01*
X1483468Y883942D01*
X1483498Y883855D01*
G02X1483572Y883423I-1227J-433D01*
G02X1480970I-1301J0D01*
G02X1482031Y884702I1301J0D01*
G01X1482121Y884719D01*
G37*
G36*
G01X1489521D02*
X1490323Y886108D01*
X1490293Y886195D01*
G02X1490219Y886627I1227J433D01*
G02X1492821I1301J0D01*
G02X1491760Y885348I-1301J0D01*
G01X1491670Y885331D01*
X1490868Y883942D01*
X1490898Y883855D01*
G02X1490972Y883423I-1227J-433D01*
G02X1488370I-1301J0D01*
G02X1489431Y884702I1301J0D01*
G01X1489521Y884719D01*
G37*
G36*
G01X1496921D02*
X1497723Y886108D01*
X1497693Y886195D01*
G02X1497619Y886627I1227J433D01*
G02X1500221I1301J0D01*
G02X1499160Y885348I-1301J0D01*
G01X1499070Y885331D01*
X1498268Y883942D01*
X1498298Y883855D01*
G02X1498372Y883423I-1227J-433D01*
G02X1495770I-1301J0D01*
G02X1496831Y884702I1301J0D01*
G01X1496921Y884719D01*
G37*
G36*
G01X1442957Y929307D02*
G03X1443497I270J294D01*
G02X1444377Y929649I879J-959D01*
G02X1445257Y929307I1J-1301D01*
G03X1445797I270J294D01*
G02X1446677Y929649I879J-959D01*
G02Y927047I0J-1301D01*
G02X1445797Y927389I-1J1301D01*
G03X1445257I-270J-294D01*
G02X1444377Y927047I-879J959D01*
G02X1443497Y927389I-1J1301D01*
G03X1442957I-270J-294D01*
G02X1442077Y927047I-879J959D01*
G02X1441197Y927389I-1J1301D01*
G03X1440657I-270J-294D01*
G02X1439777Y927047I-879J959D01*
G02X1438897Y927389I-1J1301D01*
G03X1438357I-270J-294D01*
G02X1437477Y927047I-879J959D01*
G02X1436597Y927389I-1J1301D01*
G03X1436057I-270J-294D01*
G02X1435177Y927047I-879J959D01*
G02Y929649I0J1301D01*
G02X1436057Y929307I1J-1301D01*
G03X1436597I270J294D01*
G02X1437477Y929649I879J-959D01*
G02X1438357Y929307I1J-1301D01*
G03X1438897I270J294D01*
G02X1439777Y929649I879J-959D01*
G02X1440657Y929307I1J-1301D01*
G03X1441197I270J294D01*
G02X1442077Y929649I879J-959D01*
G02X1442957Y929307I1J-1301D01*
G37*
G36*
G01X1452747Y931386D02*
G03X1453239Y931706I98J388D01*
G02X1454522Y932789I1283J-218D01*
G02Y930187I0J-1301D01*
G02X1454201Y930227I-1J1301D01*
G03X1453709Y929907I-98J-388D01*
G02X1452426Y928824I-1283J218D01*
G02Y931426I0J1301D01*
G02X1452747Y931386I1J-1301D01*
G37*
G36*
G01X1429285Y932238D02*
G03Y932778I-294J270D01*
G02X1428943Y933658I959J879D01*
G02X1431545I1301J0D01*
G02X1431203Y932778I-1301J-1D01*
G03Y932238I294J-270D01*
G02X1431545Y931358I-959J-879D01*
G02X1428943I-1301J0D01*
G02X1429285Y932238I1301J1D01*
G37*
G36*
G01X1702010Y748702D02*
G02X1701808Y749455I1300J752D01*
G02X1704812I1502J0D01*
G02X1703563Y747974I-1503J0D01*
G03X1703368Y747278I67J-394D01*
G02X1704614Y744554I-2355J-2724D01*
G02X1701012Y740952I-3602J0D01*
G01X1696112D01*
G02Y748156I0J3602D01*
G01X1701012D01*
G02X1701599Y748107I-5J-3602D01*
G03X1702010Y748702I65J395D01*
G37*
G36*
G01X1515266Y797872D02*
G02X1514438Y799215I675J1343D01*
G02X1517442I1502J0D01*
G02X1516614Y797872I-1503J0D01*
G03Y797158I179J-357D01*
G02X1517442Y795815I-675J-1343D01*
G02X1514438I-1502J0D01*
G02X1515266Y797158I1503J0D01*
G03Y797872I-179J357D01*
G37*
G36*
G01X1451362Y946234D02*
G03Y946774I-294J270D01*
G02X1451020Y947654I959J879D01*
G02X1453622I1301J0D01*
G02X1453280Y946774I-1301J-1D01*
G03Y946234I294J-270D01*
G02X1453553Y945772I-960J-879D01*
G03X1454070Y945525I379J128D01*
G02X1454520Y945605I449J-1221D01*
G02Y943003I0J-1301D01*
G02X1453288Y943886I0J1301D01*
G03X1452771Y944133I-379J-128D01*
G02X1452321Y944053I-449J1221D01*
G02X1451020Y945354I0J1301D01*
G02X1451362Y946234I1301J1D01*
G37*
G36*
G01X1451467Y965505D02*
G03Y966045I-294J270D01*
G02X1451125Y966925I959J879D01*
G02X1453727I1301J0D01*
G02X1453385Y966045I-1301J-1D01*
G03Y965505I294J-270D01*
G02X1453661Y965036I-959J-880D01*
G03X1454153Y964778I380J126D01*
G02X1454520Y964831I368J-1248D01*
G02Y962229I0J-1301D01*
G02X1454176Y962275I-1J1301D01*
G03X1453684Y961992I-106J-386D01*
G02X1453385Y961445I-1258J332D01*
G03Y960905I294J-270D01*
G02X1453727Y960025I-959J-879D01*
G02X1451125I-1301J0D01*
G02X1451467Y960905I1301J1D01*
G03Y961445I-294J270D01*
G02X1451125Y962325I959J879D01*
G02X1451467Y963205I1301J1D01*
G03Y963745I-294J270D01*
G02X1451125Y964625I959J879D01*
G02X1451467Y965505I1301J1D01*
G37*
G36*
G01X1453239Y976118D02*
G03X1452725Y976428I-393J-71D01*
G02X1452333Y976368I-391J1241D01*
G02Y978970I0J1301D01*
G02X1453614Y977898I0J-1301D01*
G03X1454128Y977588I393J71D01*
G02X1454520Y977648I391J-1241D01*
G02Y975046I0J-1301D01*
G02X1453239Y976118I0J1301D01*
G37*
G36*
G01X1451467Y988505D02*
G03Y989045I-294J270D01*
G02X1451125Y989925I959J879D01*
G02X1453727I1301J0D01*
G02X1453385Y989045I-1301J-1D01*
G03Y988505I294J-270D01*
G02X1453727Y987625I-959J-879D01*
G02X1451125I-1301J0D01*
G02X1451467Y988505I1301J1D01*
G37*
G36*
G01Y995405D02*
G03Y995945I-294J270D01*
G02X1451125Y996825I959J879D01*
G02X1453727I1301J0D01*
G02X1453385Y995945I-1301J-1D01*
G03Y995405I294J-270D01*
G02X1453727Y994525I-959J-879D01*
G02X1451125I-1301J0D01*
G02X1451467Y995405I1301J1D01*
G37*
G36*
G01X1453249Y982479D02*
G02X1453219Y982756I1271J278D01*
G02X1454520Y981455I1301J0D01*
G02X1454228Y981488I-1J1301D01*
G03X1453747Y981013I-90J-390D01*
G02X1453777Y980736I-1271J-278D01*
G02X1452476Y982037I-1301J0D01*
G02X1452768Y982004I1J-1301D01*
G03X1453249Y982479I90J390D01*
G37*
G36*
G01X1451467Y1005145D02*
G02X1451125Y1006025I959J879D01*
G02X1453727I1301J0D01*
G02X1453385Y1005145I-1301J-1D01*
G03Y1004605I294J-270D01*
G02X1453647Y1004174I-960J-879D01*
G03X1454241Y1003977I375J138D01*
G02X1454953Y1004189I712J-1090D01*
G02Y1001587I0J-1301D01*
G02X1453732Y1002439I0J1301D01*
G03X1453138Y1002636I-375J-138D01*
G02X1452426Y1002424I-712J1090D01*
G02X1451125Y1003725I0J1301D01*
G02X1451467Y1004605I1301J1D01*
G03Y1005145I-294J270D01*
G37*
G36*
G01X1448550Y1035232D02*
G03X1448026Y1035373I-338J-213D01*
G02X1447424Y1035225I-603J1153D01*
G02Y1037827I0J1301D01*
G02X1448523Y1037222I0J-1301D01*
G03X1449047Y1037081I338J213D01*
G02X1449649Y1037229I603J-1153D01*
G02Y1034627I0J-1301D01*
G02X1448550Y1035232I0J1301D01*
G37*
G36*
G01X1697153Y38081D02*
G03X1697054Y38685I-304J260D01*
G02X1696322Y39974I769J1289D01*
G02X1699326I1502J0D01*
G02X1698966Y38999I-1502J1D01*
G03X1699065Y38395I304J-260D01*
G02X1699797Y37106I-769J-1289D01*
G02X1696793I-1502J0D01*
G02X1697153Y38081I1502J-1D01*
G37*
G36*
G01X1560637Y38257D02*
G03Y38869I-258J306D01*
G02X1560100Y40020I965J1151D01*
G02X1563104I1502J0D01*
G02X1562567Y38869I-1502J0D01*
G03Y38257I258J-306D01*
G02X1563104Y37106I-965J-1151D01*
G02X1560100I-1502J0D01*
G02X1560637Y38257I1502J0D01*
G37*
G36*
G01X1567723D02*
G03Y38869I-258J306D01*
G02X1567186Y40020I965J1151D01*
G02X1570190I1502J0D01*
G02X1569653Y38869I-1502J0D01*
G03Y38257I258J-306D01*
G02X1570190Y37106I-965J-1151D01*
G02X1567186I-1502J0D01*
G02X1567723Y38257I1502J0D01*
G37*
G36*
G01X1574810D02*
G03Y38869I-258J306D01*
G02X1574273Y40020I965J1151D01*
G02X1577277I1502J0D01*
G02X1576740Y38869I-1502J0D01*
G03Y38257I258J-306D01*
G02X1577277Y37106I-965J-1151D01*
G02X1574273I-1502J0D01*
G02X1574810Y38257I1502J0D01*
G37*
G36*
G01X1581897D02*
G03Y38869I-258J306D01*
G02X1581360Y40020I965J1151D01*
G02X1584364I1502J0D01*
G02X1583827Y38869I-1502J0D01*
G03Y38257I258J-306D01*
G02X1584364Y37106I-965J-1151D01*
G02X1581360I-1502J0D01*
G02X1581897Y38257I1502J0D01*
G37*
G36*
G01X1588983D02*
G03Y38869I-258J306D01*
G02X1588446Y40020I965J1151D01*
G02X1591450I1502J0D01*
G02X1590913Y38869I-1502J0D01*
G03Y38257I258J-306D01*
G02X1591450Y37106I-965J-1151D01*
G02X1588446I-1502J0D01*
G02X1588983Y38257I1502J0D01*
G37*
G36*
G01X1596070D02*
G03Y38869I-258J306D01*
G02X1595533Y40020I965J1151D01*
G02X1598537I1502J0D01*
G02X1598000Y38869I-1502J0D01*
G03Y38257I258J-306D01*
G02X1598537Y37106I-965J-1151D01*
G02X1595533I-1502J0D01*
G02X1596070Y38257I1502J0D01*
G37*
G36*
G01X1603157D02*
G03Y38869I-258J306D01*
G02X1602620Y40020I965J1151D01*
G02X1605624I1502J0D01*
G02X1605087Y38869I-1502J0D01*
G03Y38257I258J-306D01*
G02X1605624Y37106I-965J-1151D01*
G02X1602620I-1502J0D01*
G02X1603157Y38257I1502J0D01*
G37*
G36*
G01X1624849D02*
G03Y38869I-258J306D01*
G02X1624312Y40020I965J1151D01*
G02X1627316I1502J0D01*
G02X1626779Y38869I-1502J0D01*
G03Y38257I258J-306D01*
G02X1627316Y37106I-965J-1151D01*
G02X1624312I-1502J0D01*
G02X1624849Y38257I1502J0D01*
G37*
G36*
G01X1631936D02*
G03Y38869I-258J306D01*
G02X1631399Y40020I965J1151D01*
G02X1634403I1502J0D01*
G02X1633866Y38869I-1502J0D01*
G03Y38257I258J-306D01*
G02X1634403Y37106I-965J-1151D01*
G02X1631399I-1502J0D01*
G02X1631936Y38257I1502J0D01*
G37*
G36*
G01X1639023D02*
G03Y38869I-258J306D01*
G02X1638486Y40020I965J1151D01*
G02X1641490I1502J0D01*
G02X1640953Y38869I-1502J0D01*
G03Y38257I258J-306D01*
G02X1641490Y37106I-965J-1151D01*
G02X1638486I-1502J0D01*
G02X1639023Y38257I1502J0D01*
G37*
G36*
G01X1646109D02*
G03Y38869I-258J306D01*
G02X1645572Y40020I965J1151D01*
G02X1648576I1502J0D01*
G02X1648039Y38869I-1502J0D01*
G03Y38257I258J-306D01*
G02X1648576Y37106I-965J-1151D01*
G02X1645572I-1502J0D01*
G02X1646109Y38257I1502J0D01*
G37*
G36*
G01X1653196D02*
G03Y38869I-258J306D01*
G02X1652659Y40020I965J1151D01*
G02X1655663I1502J0D01*
G02X1655126Y38869I-1502J0D01*
G03Y38257I258J-306D01*
G02X1655663Y37106I-965J-1151D01*
G02X1652659I-1502J0D01*
G02X1653196Y38257I1502J0D01*
G37*
G36*
G01X1668983D02*
G03Y38869I-258J306D01*
G02X1668446Y40020I965J1151D01*
G02X1671450I1502J0D01*
G02X1670913Y38869I-1502J0D01*
G03Y38257I258J-306D01*
G02X1671450Y37106I-965J-1151D01*
G02X1668446I-1502J0D01*
G02X1668983Y38257I1502J0D01*
G37*
G36*
G01X1676070D02*
G03Y38869I-258J306D01*
G02X1675533Y40020I965J1151D01*
G02X1678537I1502J0D01*
G02X1678000Y38869I-1502J0D01*
G03Y38257I258J-306D01*
G02X1678537Y37106I-965J-1151D01*
G02X1675533I-1502J0D01*
G02X1676070Y38257I1502J0D01*
G37*
G36*
G01X1683157D02*
G03Y38869I-258J306D01*
G02X1682620Y40020I965J1151D01*
G02X1685624I1502J0D01*
G02X1685087Y38869I-1502J0D01*
G03Y38257I258J-306D01*
G02X1685624Y37106I-965J-1151D01*
G02X1682620I-1502J0D01*
G02X1683157Y38257I1502J0D01*
G37*
G36*
G01X1690243D02*
G03Y38869I-258J306D01*
G02X1689706Y40020I965J1151D01*
G02X1692710I1502J0D01*
G02X1692173Y38869I-1502J0D01*
G03Y38257I258J-306D01*
G02X1692710Y37106I-965J-1151D01*
G02X1689706I-1502J0D01*
G02X1690243Y38257I1502J0D01*
G37*
G36*
G01X1698273Y50222D02*
G03X1698668Y50627I-5J400D01*
G01Y50649D01*
G02X1700170Y52152I1502J1D01*
G01X1703570D01*
G02X1705072Y50649I-1J-1503D01*
G01Y50626D01*
G03X1705453Y50220I400J-6D01*
G02X1706883Y48720I-72J-1500D01*
G02X1703879I-1502J0D01*
G02X1703893Y48924I1502J-1D01*
G03X1703680Y49151I-198J27D01*
G02X1703570Y49146I-123J1497D01*
G01X1700170D01*
G02X1700003Y49156I6J1503D01*
G03X1699782Y48929I-23J-199D01*
G02X1699797Y48720I-1487J-212D01*
G02X1696793I-1502J0D01*
G02X1698273Y50222I1502J0D01*
G37*
G36*
G01X1559967Y70800D02*
G03X1560347Y71324I0J400D01*
G02X1560272Y71793I1427J469D01*
G02X1563276I1502J0D01*
G02X1563198Y71316I-1502J1D01*
G03X1563619Y70791I379J-127D01*
G02X1563774Y70799I155J-1494D01*
G02Y67795I0J-1502D01*
G02X1563619Y67803I0J1502D01*
G03X1563198Y67278I-42J-398D01*
G02X1563276Y66801I-1424J-478D01*
G02X1560272I-1502J0D01*
G02X1560347Y67270I1502J0D01*
G03X1559967Y67794I-380J124D01*
G01X1558625D01*
G03X1558245Y67270I0J-400D01*
G02X1558320Y66801I-1427J-469D01*
G02X1555316I-1502J0D01*
G02X1555394Y67278I1502J-1D01*
G03X1554973Y67803I-379J127D01*
G02X1554818Y67795I-155J1494D01*
G02Y70799I0J1502D01*
G02X1554973Y70791I0J-1502D01*
G03X1555394Y71316I42J398D01*
G02X1555316Y71793I1424J478D01*
G02X1558320I1502J0D01*
G02X1558245Y71324I-1502J0D01*
G03X1558625Y70800I380J-124D01*
G01X1559967D01*
G37*
G36*
G01X1581967D02*
G03X1582347Y71324I0J400D01*
G02X1582272Y71793I1427J469D01*
G02X1585276I1502J0D01*
G02X1585198Y71316I-1502J1D01*
G03X1585619Y70791I379J-127D01*
G02X1585774Y70799I155J-1494D01*
G02Y67795I0J-1502D01*
G02X1585619Y67803I0J1502D01*
G03X1585198Y67278I-42J-398D01*
G02X1585276Y66801I-1424J-478D01*
G02X1582272I-1502J0D01*
G02X1582347Y67270I1502J0D01*
G03X1581967Y67794I-380J124D01*
G01X1580625D01*
G03X1580245Y67270I0J-400D01*
G02X1580320Y66801I-1427J-469D01*
G02X1577316I-1502J0D01*
G02X1577394Y67278I1502J-1D01*
G03X1576973Y67803I-379J127D01*
G02X1576818Y67795I-155J1494D01*
G02Y70799I0J1502D01*
G02X1576973Y70791I0J-1502D01*
G03X1577394Y71316I42J398D01*
G02X1577316Y71793I1424J478D01*
G02X1580320I1502J0D01*
G02X1580245Y71324I-1502J0D01*
G03X1580625Y70800I380J-124D01*
G01X1581967D01*
G37*
G36*
G01X1603967D02*
G03X1604347Y71324I0J400D01*
G02X1604272Y71793I1427J469D01*
G02X1607276I1502J0D01*
G02X1607198Y71316I-1502J1D01*
G03X1607619Y70791I379J-127D01*
G02X1607774Y70799I155J-1494D01*
G02Y67795I0J-1502D01*
G02X1607619Y67803I0J1502D01*
G03X1607198Y67278I-42J-398D01*
G02X1607276Y66801I-1424J-478D01*
G02X1604272I-1502J0D01*
G02X1604347Y67270I1502J0D01*
G03X1603967Y67794I-380J124D01*
G01X1602625D01*
G03X1602245Y67270I0J-400D01*
G02X1602320Y66801I-1427J-469D01*
G02X1599316I-1502J0D01*
G02X1599394Y67278I1502J-1D01*
G03X1598973Y67803I-379J127D01*
G02X1598818Y67795I-155J1494D01*
G02Y70799I0J1502D01*
G02X1598973Y70791I0J-1502D01*
G03X1599394Y71316I42J398D01*
G02X1599316Y71793I1424J478D01*
G02X1602320I1502J0D01*
G02X1602245Y71324I-1502J0D01*
G03X1602625Y70800I380J-124D01*
G01X1603967D01*
G37*
G36*
G01X1570967Y76800D02*
G03X1571347Y77324I0J400D01*
G02X1571272Y77793I1427J469D01*
G02X1574276I1502J0D01*
G02X1574198Y77316I-1502J1D01*
G03X1574619Y76791I379J-127D01*
G02X1574774Y76799I155J-1494D01*
G02Y73795I0J-1502D01*
G02X1574619Y73803I0J1502D01*
G03X1574198Y73278I-42J-398D01*
G02X1574276Y72801I-1424J-478D01*
G02X1571272I-1502J0D01*
G02X1571347Y73270I1502J0D01*
G03X1570967Y73794I-380J124D01*
G01X1569625D01*
G03X1569245Y73270I0J-400D01*
G02X1569320Y72801I-1427J-469D01*
G02X1566316I-1502J0D01*
G02X1566394Y73278I1502J-1D01*
G03X1565973Y73803I-379J127D01*
G02X1565818Y73795I-155J1494D01*
G02Y76799I0J1502D01*
G02X1565973Y76791I0J-1502D01*
G03X1566394Y77316I42J398D01*
G02X1566316Y77793I1424J478D01*
G02X1569320I1502J0D01*
G02X1569245Y77324I-1502J0D01*
G03X1569625Y76800I380J-124D01*
G01X1570967D01*
G37*
G36*
G01X1592967D02*
G03X1593347Y77324I0J400D01*
G02X1593272Y77793I1427J469D01*
G02X1596276I1502J0D01*
G02X1596198Y77316I-1502J1D01*
G03X1596619Y76791I379J-127D01*
G02X1596774Y76799I155J-1494D01*
G02Y73795I0J-1502D01*
G02X1596619Y73803I0J1502D01*
G03X1596198Y73278I-42J-398D01*
G02X1596276Y72801I-1424J-478D01*
G02X1593272I-1502J0D01*
G02X1593347Y73270I1502J0D01*
G03X1592967Y73794I-380J124D01*
G01X1591625D01*
G03X1591245Y73270I0J-400D01*
G02X1591320Y72801I-1427J-469D01*
G02X1588316I-1502J0D01*
G02X1588394Y73278I1502J-1D01*
G03X1587973Y73803I-379J127D01*
G02X1587818Y73795I-155J1494D01*
G02Y76799I0J1502D01*
G02X1587973Y76791I0J-1502D01*
G03X1588394Y77316I42J398D01*
G02X1588316Y77793I1424J478D01*
G02X1591320I1502J0D01*
G02X1591245Y77324I-1502J0D01*
G03X1591625Y76800I380J-124D01*
G01X1592967D01*
G37*
G36*
G01X1544885Y158087D02*
G02X1544261Y159305I877J1218D01*
G02X1547265I1502J0D01*
G02X1546392Y157941I-1502J0D01*
G03X1546325Y157253I167J-364D01*
G02X1546949Y156035I-877J-1218D01*
G02X1543945I-1502J0D01*
G02X1544818Y157399I1502J0D01*
G03X1544885Y158087I-167J364D01*
G37*
G36*
G01X1651518Y559464D02*
X1676008D01*
X1676151Y559320D01*
X1676601Y559770D01*
G02X1677309Y560064I709J-708D01*
G01X1686185D01*
X1708318Y582197D01*
Y615704D01*
G02X1708612Y616412I1002J-1D01*
G01X1726658Y634459D01*
Y660115D01*
X1717463Y669310D01*
X1715510D01*
G02X1714802Y669604I1J1002D01*
G01X1700788Y683618D01*
G02X1700494Y684326I708J709D01*
G01Y686279D01*
X1676323Y710450D01*
X1658496D01*
G02X1657788Y710744I1J1002D01*
G01X1655723Y712809D01*
X1655639D01*
G02X1654430Y713417I-2J1502D01*
G03X1653788I-321J-239D01*
G02X1652581Y712809I-1207J894D01*
G02X1651079Y714311I0J1502D01*
G02X1652583Y715813I1502J0D01*
G01X1652667D01*
X1653934Y717080D01*
G02X1654642Y717374I709J-708D01*
G01X1657230D01*
G02X1657938Y717080I-1J-1002D01*
G01X1661065Y713954D01*
X1677360D01*
G02X1678068Y713660I-1J-1002D01*
G01X1703704Y688024D01*
G02X1703998Y687316I-708J-709D01*
G01Y685363D01*
X1716547Y672814D01*
X1718500D01*
G02X1719208Y672520I-1J-1002D01*
G01X1729868Y661860D01*
G02X1730162Y661152I-708J-709D01*
G01Y633422D01*
G02X1729868Y632714I-1002J1D01*
G01X1711872Y614718D01*
Y581139D01*
G02X1711579Y580431I-1002J0D01*
G01X1687192Y556044D01*
G02X1686484Y555750I-709J708D01*
G01X1679979D01*
G02X1678860Y555250I-1119J1002D01*
G01X1678859D01*
G02X1678293Y555361I1J1502D01*
G03X1677742Y554991I-151J-370D01*
G01Y546044D01*
X1676168Y544470D01*
X1668928D01*
X1668692Y544234D01*
Y519960D01*
X1653166D01*
G02X1651890Y519138I-1276J579D01*
G02X1650488Y520540I0J1402D01*
G02X1651518Y521892I1402J0D01*
G01Y522814D01*
G02Y525328I619J1257D01*
G01Y526056D01*
G02Y528594I594J1269D01*
G01Y530585D01*
X1651381Y530630D01*
G02Y533484I471J1427D01*
G01X1651518Y533529D01*
Y534731D01*
G02Y537411I413J1340D01*
G01Y538731D01*
G02Y541411I413J1340D01*
G01Y543670D01*
G03X1651117Y544070I-400J0D01*
G01X1651112D01*
G02Y547074I0J1502D01*
G01X1651117D01*
G03X1651518Y547474I1J400D01*
G01Y559464D01*
G37*
G36*
G01X1706366Y533272D02*
G03X1705793Y533367I-332J-224D01*
G02X1704886Y533062I-907J1196D01*
G02Y536066I0J1502D01*
G02X1706130Y535405I0J-1501D01*
G03X1706703Y535310I332J224D01*
G02X1707610Y535615I907J-1196D01*
G02Y532611I0J-1502D01*
G02X1706366Y533272I0J1501D01*
G37*
G36*
G01X1688559Y538229D02*
G03X1688504Y538763I-322J237D01*
G02X1688004Y539882I1002J1119D01*
G02X1691008I1502J0D01*
G02X1690716Y538992I-1502J0D01*
G03X1690771Y538458I322J-237D01*
G02X1691271Y537339I-1002J-1119D01*
G02X1691231Y536996I-1502J1D01*
G03X1691584Y536507I389J-91D01*
G02X1692947Y535011I-139J-1496D01*
G02X1689943I-1502J0D01*
G02X1689983Y535354I1502J-1D01*
G03X1689630Y535843I-389J91D01*
G02X1688267Y537339I139J1496D01*
G02X1688559Y538229I1502J0D01*
G37*
G36*
G01X1657225Y593245D02*
G03X1657751I263J302D01*
G02X1659725I987J-1131D01*
G03X1660251I263J302D01*
G02X1661238Y593615I987J-1131D01*
G02Y590611I0J-1502D01*
G02X1660251Y590981I0J1501D01*
G03X1659725I-263J-302D01*
G02X1657751I-987J1131D01*
G03X1657225I-263J-302D01*
G02X1656238Y590611I-987J1131D01*
G02Y593615I0J1502D01*
G02X1657225Y593245I0J-1501D01*
G37*
G36*
G01X1670998Y596461D02*
Y596462D01*
G02X1674002I1502J0D01*
G02X1672581Y594962I-1502J0D01*
G03X1672202Y594563I21J-399D01*
G01Y594562D01*
G02X1669198I-1502J0D01*
G02X1670619Y596062I1502J0D01*
G03X1670998Y596461I-21J399D01*
G37*
G36*
G01X1662398Y608786D02*
G03X1661827I-286J-280D01*
G02X1660754Y608335I-1073J1051D01*
G02Y611339I0J1502D01*
G02X1661827Y610888I0J-1502D01*
G03X1662398I285J280D01*
G02X1663471Y611339I1073J-1051D01*
G02Y608335I0J-1502D01*
G02X1662398Y608786I0J1502D01*
G37*
G36*
G01X1644568Y634153D02*
G03X1644407Y634652I-368J157D01*
G02X1643700Y635907I760J1255D01*
G02X1646634I1467J0D01*
G02X1646516Y635331I-1467J0D01*
G03X1646677Y634832I368J-157D01*
G02Y632322I-760J-1255D01*
G03X1646516Y631823I207J-342D01*
G02X1646634Y631247I-1349J-576D01*
G02X1646516Y630671I-1467J0D01*
G03X1646677Y630172I368J-157D01*
G02X1647234Y629562I-761J-1254D01*
G03X1647850Y629431I359J176D01*
G02X1648811Y629779I961J-1153D01*
G02X1649956Y629249I0J-1502D01*
G03X1650566I305J259D01*
G02X1651711Y629779I1145J-972D01*
G02X1653213Y628277I0J-1502D01*
G02X1651909Y626788I-1502J0D01*
G03X1651567Y626333I53J-396D01*
G02X1651583Y626111I-1486J-219D01*
G02X1651569Y625905I-1502J-1D01*
G03X1651863Y625464I396J-54D01*
G02X1652983Y624011I-383J-1453D01*
G02X1651481Y622509I-1502J0D01*
G02X1650336Y623039I0J1502D01*
G03X1649726I-305J-259D01*
G02X1647436I-1145J972D01*
G03X1646826I-305J-259D01*
G02X1645681Y622509I-1145J972D01*
G02X1644179Y624011I0J1502D01*
G02X1645311Y625467I1502J0D01*
G03X1645606Y625929I-98J388D01*
G02X1645579Y626211I1475J284D01*
G02X1645762Y626929I1502J0D01*
G03X1645519Y627505I-352J191D01*
G02X1644450Y628917I398J1412D01*
G02X1644568Y629493I1467J0D01*
G03X1644407Y629992I-368J157D01*
G02Y632502I760J1255D01*
G03X1644568Y633001I-207J342D01*
G02X1644450Y633577I1349J576D01*
G02X1644568Y634153I1467J0D01*
G37*
G36*
G01X1651819Y640977D02*
G03X1652022Y641553I-142J374D01*
G02X1651817Y642310I1297J758D01*
G01Y642311D01*
G02X1654821I1502J0D01*
G02X1653851Y640907I-1501J0D01*
G03X1653648Y640331I142J-374D01*
G02X1653829Y639839I-1298J-757D01*
G03X1654346Y639530I394J71D01*
G02X1654808Y639603I463J-1429D01*
G01X1654809D01*
G02Y636599I0J-1502D01*
G02X1653331Y637835I0J1502D01*
G03X1652814Y638144I-394J-71D01*
G02X1652352Y638071I-463J1429D01*
G01X1652351D01*
G02X1650849Y639573I0J1502D01*
G02X1651819Y640977I1501J0D01*
G37*
G36*
G01X1642595Y651469D02*
G03X1642069I-263J-302D01*
G02X1641082Y651099I-987J1131D01*
G02Y654103I0J1502D01*
G02X1642069Y653733I0J-1501D01*
G03X1642595I263J302D01*
G02X1643582Y654103I987J-1131D01*
G02Y651099I0J-1502D01*
G02X1642595Y651469I0J1501D01*
G37*
G36*
G01X1675548Y653772D02*
G03Y654318I-292J273D01*
G02X1675142Y655345I1096J1027D01*
G02X1676644Y656847I1502J0D01*
G02X1677671Y656441I0J-1502D01*
G03X1678217I273J292D01*
G02X1679244Y656847I1027J-1096D01*
G02X1680303Y656410I0J-1502D01*
G03X1680854Y656398I282J284D01*
G02X1681864Y656788I1010J-1113D01*
G02X1683366Y655286I0J-1502D01*
G02X1682960Y654259I-1502J0D01*
G03Y653713I292J-273D01*
G02Y651659I-1096J-1027D01*
G03Y651113I292J-273D01*
G02Y649059I-1096J-1027D01*
G03Y648513I292J-273D01*
G02Y646459I-1096J-1027D01*
G03Y645913I292J-273D01*
G02Y643859I-1096J-1027D01*
G03Y643313I292J-273D01*
G02X1683366Y642286I-1096J-1027D01*
G02X1681864Y640784I-1502J0D01*
G02X1680805Y641221I0J1502D01*
G03X1680254Y641233I-282J-284D01*
G02X1679244Y640843I-1010J1113D01*
G02X1678185Y641280I0J1502D01*
G03X1677634Y641292I-282J-284D01*
G02X1676624Y640902I-1010J1113D01*
G02X1675122Y642404I0J1502D01*
G02X1675514Y643416I1502J0D01*
G03X1675518Y643950I-295J269D01*
G02X1675142Y644943I1126J994D01*
G01Y644945D01*
G02X1675548Y645972I1502J0D01*
G03Y646518I-292J273D01*
G02Y648572I1096J1027D01*
G03Y649118I-292J273D01*
G02Y651172I1096J1027D01*
G03Y651718I-292J273D01*
G02Y653772I1096J1027D01*
G37*
G36*
G01X1697179Y656271D02*
G03X1697194Y656826I-280J285D01*
G02X1696800Y657840I1108J1014D01*
G02X1698302Y659342I1502J0D01*
G02X1699361Y658905I0J-1502D01*
G03X1699912Y658893I282J284D01*
G02X1700922Y659283I1010J-1113D01*
G02X1702424Y657781I0J-1502D01*
G02X1701975Y656710I-1502J0D01*
G03X1701960Y656155I280J-285D01*
G02X1702354Y655141I-1108J-1014D01*
G02X1701948Y654114I-1502J0D01*
G03Y653568I292J-273D01*
G02X1701999Y653510I-1102J-1020D01*
G03X1702305I153J130D01*
G02X1703452Y654043I1147J-968D01*
G02X1704954Y652541I0J-1502D01*
G02X1704548Y651514I-1502J0D01*
G03Y650968I292J-273D01*
G02Y648914I-1096J-1027D01*
G03Y648368I292J-273D01*
G02Y646314I-1096J-1027D01*
G03Y645768I292J-273D01*
G02X1704954Y644741I-1096J-1027D01*
G02X1704486Y643651I-1503J0D01*
G03Y643071I275J-290D01*
G02X1704954Y641981I-1035J-1090D01*
G02X1704548Y640954I-1502J0D01*
G03Y640408I292J-273D01*
G02X1704954Y639381I-1096J-1027D01*
G02X1703452Y637879I-1502J0D01*
G02X1702425Y638285I0J1502D01*
G03X1701879I-273J-292D01*
G02X1700852Y637879I-1027J1096D01*
G02X1699793Y638316I0J1502D01*
G03X1699242Y638328I-282J-284D01*
G02X1698232Y637938I-1010J1113D01*
G02X1696730Y639440I0J1502D01*
G02X1697136Y640467I1502J0D01*
G03Y641013I-292J273D01*
G02X1696730Y642040I1096J1027D01*
G02X1697198Y643130I1503J0D01*
G03Y643710I-275J290D01*
G02X1696730Y644800I1035J1090D01*
G02X1697136Y645827I1502J0D01*
G03Y646373I-292J273D01*
G02Y648427I1096J1027D01*
G03Y648973I-292J273D01*
G02Y651027I1096J1027D01*
G03Y651573I-292J273D01*
G02Y653627I1096J1027D01*
G03Y654173I-292J273D01*
G02X1696730Y655200I1096J1027D01*
G02X1697179Y656271I1502J0D01*
G37*
G36*
G01X1644568Y668153D02*
G03X1644407Y668652I-368J157D01*
G02X1643700Y669907I760J1255D01*
G02X1646634I1467J0D01*
G02X1646516Y669331I-1467J0D01*
G03X1646677Y668832I368J-157D01*
G02Y666322I-760J-1255D01*
G03X1646516Y665823I207J-342D01*
G02X1646634Y665247I-1349J-576D01*
G02X1646516Y664671I-1467J0D01*
G03X1646677Y664172I368J-157D01*
G02X1647234Y663562I-761J-1254D01*
G03X1647850Y663431I359J176D01*
G02X1648811Y663779I961J-1153D01*
G02X1649956Y663249I0J-1502D01*
G03X1650566I305J259D01*
G02X1651711Y663779I1145J-972D01*
G02X1653213Y662277I0J-1502D01*
G02X1651909Y660788I-1502J0D01*
G03X1651567Y660333I53J-396D01*
G02X1651583Y660111I-1486J-219D01*
G02X1651569Y659905I-1502J-1D01*
G03X1651863Y659464I396J-54D01*
G02X1652983Y658011I-383J-1453D01*
G02X1651481Y656509I-1502J0D01*
G02X1650336Y657039I0J1502D01*
G03X1649726I-305J-259D01*
G02X1647436I-1145J972D01*
G03X1646826I-305J-259D01*
G02X1645681Y656509I-1145J972D01*
G02X1644179Y658011I0J1502D01*
G02X1645311Y659467I1502J0D01*
G03X1645606Y659929I-98J388D01*
G02X1645579Y660211I1475J284D01*
G02X1645762Y660929I1502J0D01*
G03X1645519Y661505I-352J191D01*
G02X1644450Y662917I398J1412D01*
G02X1644568Y663493I1467J0D01*
G03X1644407Y663992I-368J157D01*
G02Y666502I760J1255D01*
G03X1644568Y667001I-207J342D01*
G02X1644450Y667577I1349J576D01*
G02X1644568Y668153I1467J0D01*
G37*
G36*
G01X1651819Y674977D02*
G03X1652022Y675553I-142J374D01*
G02X1651817Y676310I1297J758D01*
G01Y676311D01*
G02X1654821I1502J0D01*
G02X1653851Y674907I-1501J0D01*
G03X1653648Y674331I142J-374D01*
G02X1653829Y673839I-1298J-757D01*
G03X1654346Y673530I394J71D01*
G02X1654808Y673603I463J-1429D01*
G01X1654809D01*
G02Y670599I0J-1502D01*
G02X1653331Y671835I0J1502D01*
G03X1652814Y672144I-394J-71D01*
G02X1652352Y672071I-463J1429D01*
G01X1652351D01*
G02X1650849Y673573I0J1502D01*
G02X1651819Y674977I1501J0D01*
G37*
G36*
G01X1654336Y679549D02*
G03X1653804Y679439I-207J-342D01*
G02X1652581Y678809I-1223J872D01*
G02Y681813I0J1502D01*
G01X1652583D01*
G02X1653358Y681597I-1J-1502D01*
G03X1653890Y681707I207J342D01*
G02X1655113Y682337I1223J-872D01*
G02Y679333I0J-1502D01*
G01X1655111D01*
G02X1654336Y679549I1J1502D01*
G37*
G36*
G01X1642595Y685469D02*
G03X1642069I-263J-302D01*
G02X1641082Y685099I-987J1131D01*
G02Y688103I0J1502D01*
G02X1642069Y687733I0J-1501D01*
G03X1642595I263J302D01*
G02X1643582Y688103I987J-1131D01*
G02Y685099I0J-1502D01*
G02X1642595Y685469I0J1501D01*
G37*
G36*
G01X1644568Y702153D02*
G03X1644407Y702652I-368J157D01*
G02X1643700Y703907I760J1255D01*
G02X1646634I1467J0D01*
G02X1646516Y703331I-1467J0D01*
G03X1646677Y702832I368J-157D01*
G02Y700322I-760J-1255D01*
G03X1646516Y699823I207J-342D01*
G02X1646634Y699247I-1349J-576D01*
G02X1646516Y698671I-1467J0D01*
G03X1646677Y698172I368J-157D01*
G02X1647234Y697562I-761J-1254D01*
G03X1647850Y697431I359J176D01*
G02X1648811Y697779I961J-1153D01*
G02X1649956Y697249I0J-1502D01*
G03X1650566I305J259D01*
G02X1651711Y697779I1145J-972D01*
G02X1653213Y696277I0J-1502D01*
G02X1651909Y694788I-1502J0D01*
G03X1651567Y694333I53J-396D01*
G02X1651583Y694111I-1486J-219D01*
G02X1651569Y693905I-1502J-1D01*
G03X1651863Y693464I396J-54D01*
G02X1652983Y692011I-383J-1453D01*
G02X1651481Y690509I-1502J0D01*
G02X1650336Y691039I0J1502D01*
G03X1649726I-305J-259D01*
G02X1647436I-1145J972D01*
G03X1646826I-305J-259D01*
G02X1645681Y690509I-1145J972D01*
G02X1644179Y692011I0J1502D01*
G02X1645311Y693467I1502J0D01*
G03X1645606Y693929I-98J388D01*
G02X1645579Y694211I1475J284D01*
G02X1645762Y694929I1502J0D01*
G03X1645519Y695505I-352J191D01*
G02X1644450Y696917I398J1412D01*
G02X1644568Y697493I1467J0D01*
G03X1644407Y697992I-368J157D01*
G02Y700502I760J1255D01*
G03X1644568Y701001I-207J342D01*
G02X1644450Y701577I1349J576D01*
G02X1644568Y702153I1467J0D01*
G37*
G36*
G01X1651819Y708977D02*
G03X1652022Y709553I-142J374D01*
G02X1651817Y710310I1297J758D01*
G01Y710311D01*
G02X1654821I1502J0D01*
G02X1653851Y708907I-1501J0D01*
G03X1653648Y708331I142J-374D01*
G02X1653829Y707839I-1298J-757D01*
G03X1654346Y707530I394J71D01*
G02X1654808Y707603I463J-1429D01*
G01X1654809D01*
G02Y704599I0J-1502D01*
G02X1653331Y705835I0J1502D01*
G03X1652814Y706144I-394J-71D01*
G02X1652352Y706071I-463J1429D01*
G01X1652351D01*
G02X1650849Y707573I0J1502D01*
G02X1651819Y708977I1501J0D01*
G37*
G36*
G01X1642595Y719469D02*
G03X1642069I-263J-302D01*
G02X1641082Y719099I-987J1131D01*
G02Y722103I0J1502D01*
G02X1642069Y721733I0J-1501D01*
G03X1642595I263J302D01*
G02X1643582Y722103I987J-1131D01*
G02Y719099I0J-1502D01*
G02X1642595Y719469I0J1501D01*
G37*
G36*
G01X1708440Y515573D02*
G02X1708342Y516106I1404J534D01*
G02X1709844Y514604I1502J0D01*
G02X1709568Y514630I2J1502D01*
G03X1709120Y514095I-74J-393D01*
G02X1709218Y513562I-1404J-534D01*
G02X1707716Y515064I-1502J0D01*
G02X1707992Y515038I-2J-1502D01*
G03X1708440Y515573I74J393D01*
G37*
G36*
G01X1668920Y619138D02*
X1670257D01*
G02X1671317Y618699I-1J-1501D01*
G01X1685162Y604854D01*
G02X1685602Y603792I-1062J-1062D01*
G01Y577862D01*
G02X1685162Y576800I-1502J0D01*
G01X1680662Y572300D01*
G02X1679600Y571860I-1062J1062D01*
G01X1641042D01*
X1628282Y559100D01*
Y516908D01*
X1663509Y481681D01*
G02X1663948Y480621I-1062J-1061D01*
G01Y480619D01*
G02X1662447Y479118I-1501J0D01*
G01X1662445D01*
G02X1661385Y479557I1J1501D01*
G01X1625718Y515224D01*
G02X1625278Y516286I1062J1062D01*
G01Y559722D01*
G02X1625718Y560784I1502J0D01*
G01X1639358Y574424D01*
G02X1640420Y574864I1062J-1062D01*
G01X1678978D01*
X1682598Y578484D01*
Y603170D01*
X1671576Y614193D01*
G03X1670894Y613943I-283J-283D01*
G02X1669397Y612562I-1497J121D01*
G02Y615566I0J1502D01*
G01X1669399D01*
G02X1669716Y615532I-1J-1502D01*
G01X1669823Y615509D01*
X1670041Y615727D01*
X1669633Y616136D01*
X1668920D01*
G02Y619138I0J1501D01*
G37*
G36*
G01X1654612Y649344D02*
X1657230D01*
G02X1657938Y649050I-1J-1002D01*
G01X1661035Y645954D01*
X1666122D01*
G02X1666830Y645660I-1J-1002D01*
G01X1676038Y636452D01*
G02X1676332Y635744I-708J-709D01*
G01Y620107D01*
X1678806Y617632D01*
G03X1679488Y617942I283J283D01*
G02X1679480Y618174I3394J233D01*
G02X1682882Y614772I3402J0D01*
G02X1682650Y614780I1J3402D01*
G03X1682340Y614098I-27J-399D01*
G01X1690028Y606410D01*
G02X1690322Y605702I-708J-709D01*
G01Y575082D01*
G02X1690028Y574374I-1002J1D01*
G01X1683799Y568144D01*
G03X1683932Y567491I283J-282D01*
G02X1684871Y566098I-564J-1393D01*
G02X1684043Y564755I-1503J0D01*
G03Y564041I179J-357D01*
G02X1684871Y562698I-675J-1343D01*
G02X1681867I-1502J0D01*
G02X1682695Y564041I1503J0D01*
G03Y564755I-179J357D01*
G02X1681976Y565535I674J1343D01*
G03X1681323Y565668I-371J-150D01*
G01X1679508Y563854D01*
G02X1678800Y563560I-709J708D01*
G01X1641547D01*
X1637332Y559345D01*
Y532057D01*
X1659425Y509964D01*
X1698900D01*
G02X1699300Y509880I-2J-1002D01*
G01X1699338Y509864D01*
X1702122D01*
Y507852D01*
X1702376D01*
G02X1703084Y507559I0J-1002D01*
G01X1705402Y505241D01*
G02X1705619Y504916I-708J-708D01*
G01X1705799Y504483D01*
G03X1706459Y504361I370J153D01*
G02X1706878Y504674I1095J-1029D01*
G03Y505388I-179J357D01*
G02X1706050Y506731I675J1343D01*
G02X1709054I1502J0D01*
G02X1708226Y505388I-1503J0D01*
G03Y504674I179J-357D01*
G02X1709054Y503331I-675J-1343D01*
G02X1707954Y501884I-1502J0D01*
G01X1707904Y501870D01*
X1707725Y501691D01*
X1707908Y501508D01*
G02X1708202Y500800I-708J-709D01*
G01Y500081D01*
G02X1708702Y498962I-1002J-1119D01*
G02X1705698I-1502J0D01*
G02X1706140Y500026I1502J0D01*
G01X1706198Y500084D01*
Y500385D01*
X1704853Y501731D01*
G02X1704636Y502056I708J708D01*
G01X1703845Y503966D01*
X1702804Y505006D01*
G03X1702122Y504724I-282J-283D01*
G01Y502795D01*
X1702262Y502751D01*
G02Y499885I-451J-1433D01*
G01X1702122Y499841D01*
Y498604D01*
X1702241Y498551D01*
G02X1703137Y497177I-606J-1374D01*
G02X1701635Y495675I-1502J0D01*
G01X1701634D01*
G02X1700974Y495828I0J1502D01*
G01X1700846Y495891D01*
X1697734Y492780D01*
X1695913D01*
X1694566Y491432D01*
Y477577D01*
X1699226Y472916D01*
Y468839D01*
X1697848Y467460D01*
X1674798D01*
Y506460D01*
X1658388D01*
G02X1657680Y506754I1J1002D01*
G01X1634122Y530312D01*
G02X1633828Y531020I708J709D01*
G01Y560382D01*
G02X1634122Y561090I1002J-1D01*
G01X1639802Y566770D01*
G02X1640510Y567064I709J-708D01*
G01X1677763D01*
X1686818Y576119D01*
Y604665D01*
X1673122Y618362D01*
G02X1672828Y619070I708J709D01*
G01Y634707D01*
X1665085Y642450D01*
X1658466D01*
G02X1657758Y642744I1J1002D01*
G01X1655694Y644808D01*
X1655613Y644809D01*
G02X1654430Y645417I24J1502D01*
G03X1653788I-321J-239D01*
G02X1652581Y644809I-1207J894D01*
G02X1651079Y646311I0J1502D01*
G02X1652583Y647813I1502J0D01*
G01X1652667D01*
X1653904Y649050D01*
G02X1654612Y649344I709J-708D01*
G37*
G36*
G01X1650186Y651441D02*
G02X1650133Y651836I1449J395D01*
G02X1651635Y650334I1502J0D01*
G01X1651634D01*
G02X1651290Y650374I0J1502D01*
G03X1650812Y649880I-92J-389D01*
G02X1650865Y649485I-1449J-395D01*
G02X1649363Y650987I-1502J0D01*
G01X1649364D01*
G02X1649708Y650947I0J-1502D01*
G03X1650186Y651441I92J389D01*
G37*
G36*
G01Y685441D02*
G02X1650133Y685836I1449J395D01*
G02X1651635Y684334I1502J0D01*
G01X1651634D01*
G02X1651290Y684374I0J1502D01*
G03X1650812Y683880I-92J-389D01*
G02X1650865Y683485I-1449J-395D01*
G02X1649363Y684987I-1502J0D01*
G01X1649364D01*
G02X1649708Y684947I0J-1502D01*
G03X1650186Y685441I92J389D01*
G37*
G36*
G01X1696979Y704607D02*
G02X1696546Y705662I1069J1055D01*
G02X1698048Y707164I1502J0D01*
G02X1699336Y706434I0J-1501D01*
G03X1700024Y706438I343J206D01*
G02X1701320Y707180I1296J-761D01*
G02Y704176I0J-1502D01*
G02X1700032Y704906I0J1501D01*
G03X1699344Y704902I-343J-206D01*
G02X1699095Y704585I-1295J761D01*
G03X1699089Y704017I279J-287D01*
G02X1699522Y702962I-1069J-1055D01*
G02X1696518I-1502J0D01*
G02X1696973Y704039I1502J0D01*
G03X1696979Y704607I-279J287D01*
G37*
G36*
G01X1650186Y719441D02*
G02X1650133Y719836I1449J395D01*
G02X1651635Y718334I1502J0D01*
G01X1651634D01*
G02X1651290Y718374I0J1502D01*
G03X1650812Y717880I-92J-389D01*
G02X1650865Y717485I-1449J-395D01*
G02X1649363Y718987I-1502J0D01*
G01X1649364D01*
G02X1649708Y718947I0J-1502D01*
G03X1650186Y719441I92J389D01*
G37*
G36*
G01X1646178Y409909D02*
G03Y410435I-302J263D01*
G02X1645808Y411422I1131J987D01*
G02X1647310Y412924I1502J0D01*
G02X1648368Y412488I0J-1502D01*
G03X1648938Y412494I282J284D01*
G02X1650020Y412954I1082J-1043D01*
G02X1651522Y411452I0J-1502D01*
G02X1651152Y410465I-1501J0D01*
G03Y409939I302J-263D01*
G02X1651522Y408952I-1131J-987D01*
G02X1650020Y407450I-1502J0D01*
G02X1648962Y407886I0J1502D01*
G03X1648392Y407880I-282J-284D01*
G02X1647310Y407420I-1082J1043D01*
G02X1645808Y408922I0J1502D01*
G02X1646178Y409909I1501J0D01*
G37*
G36*
G01X1705368Y414349D02*
G03Y414875I-302J263D01*
G02X1704998Y415862I1131J987D01*
G02X1706500Y417364I1502J0D01*
G02X1707487Y416994I0J-1501D01*
G03X1708013I263J302D01*
G02X1709000Y417364I987J-1131D01*
G02X1710502Y415862I0J-1502D01*
G02X1710132Y414875I-1501J0D01*
G03Y414349I302J-263D01*
G02X1710502Y413362I-1131J-987D01*
G02X1709402Y411915I-1502J0D01*
G03X1709146Y411363I108J-385D01*
G02X1709282Y410738I-1366J-625D01*
G02X1706278I-1502J0D01*
G02X1706409Y411352I1502J0D01*
G03X1706140Y411904I-365J164D01*
G02X1704998Y413362I360J1458D01*
G02X1705368Y414349I1501J0D01*
G37*
G36*
G01X1635877Y437167D02*
G03Y437797I-246J315D01*
G02X1635298Y438982I923J1185D01*
G02X1636800Y440484I1502J0D01*
G02X1637985Y439905I0J-1502D01*
G03X1638615I315J246D01*
G02X1639800Y440484I1185J-923D01*
G02X1641302Y438982I0J-1502D01*
G02X1640723Y437797I-1502J0D01*
G03Y437167I246J-315D01*
G02Y434797I-923J-1185D01*
G03Y434167I246J-315D01*
G02Y431797I-923J-1185D01*
G03Y431167I246J-315D01*
G02Y428797I-923J-1185D01*
G03Y428167I246J-315D01*
G02X1641302Y426982I-923J-1185D01*
G02X1639800Y425480I-1502J0D01*
G02X1638615Y426059I0J1502D01*
G03X1637985I-315J-246D01*
G02X1636800Y425480I-1185J923D01*
G02X1635298Y426982I0J1502D01*
G02X1635877Y428167I1502J0D01*
G03Y428797I-246J315D01*
G02Y431167I923J1185D01*
G03Y431797I-246J315D01*
G02Y434167I923J1185D01*
G03Y434797I-246J315D01*
G02Y437167I923J1185D01*
G37*
G36*
G01X1701121Y403254D02*
G02X1699809Y402483I-1312J731D01*
G02Y405487I0J1502D01*
G02X1700985Y404920I0J-1503D01*
G03X1701647Y404974I313J249D01*
G02X1702959Y405745I1312J-731D01*
G02Y402741I0J-1502D01*
G02X1701783Y403308I0J1503D01*
G03X1701121Y403254I-313J-249D01*
G37*
G36*
G01X1695772Y406031D02*
G02X1695659Y406602I1389J572D01*
G02X1698663I1502J0D01*
G02X1697301Y405107I-1501J0D01*
G03X1696968Y404556I37J-398D01*
G02X1697081Y403985I-1389J-572D01*
G02X1695579Y402483I-1502J0D01*
G02X1694335Y403143I0J1502D01*
G03X1693673I-331J-224D01*
G02X1692429Y402483I-1244J842D01*
G02Y405487I0J1502D01*
G02X1693673Y404827I0J-1502D01*
G03X1694335I331J224D01*
G02X1695439Y405480I1243J-842D01*
G03X1695772Y406031I-37J398D01*
G37*
G36*
G01X1720579Y189381D02*
G03X1720208Y189753I-399J-27D01*
G02X1718808Y191252I103J1499D01*
G02X1720310Y192754I1502J0D01*
G02X1721809Y191354I0J-1503D01*
G03X1722180Y190982I399J27D01*
G02X1723580Y189483I-103J-1499D01*
G02X1722078Y187981I-1502J0D01*
G02X1720579Y189381I0J1503D01*
G37*
G36*
G01X1746415Y208139D02*
G03X1745785I-315J-246D01*
G02X1744600Y207560I-1185J923D01*
G02Y210564I0J1502D01*
G02X1745785Y209985I0J-1502D01*
G03X1746415I315J246D01*
G02X1747600Y210564I1185J-923D01*
G02Y207560I0J-1502D01*
G02X1746415Y208139I0J1502D01*
G37*
G36*
G01X1777646Y220415D02*
G03Y220941I-302J263D01*
G02X1777276Y221928I1131J987D01*
G02X1780280I1502J0D01*
G02X1779910Y220941I-1501J0D01*
G03Y220415I302J-263D01*
G02Y218441I-1131J-987D01*
G03Y217915I302J-263D01*
G02X1780280Y216928I-1131J-987D01*
G02X1777276I-1502J0D01*
G02X1777646Y217915I1501J0D01*
G03Y218441I-302J263D01*
G02Y220415I1131J987D01*
G37*
G36*
G01X1782746Y225415D02*
G03Y225941I-302J263D01*
G02X1782376Y226928I1131J987D01*
G02X1785380I1502J0D01*
G02X1785010Y225941I-1501J0D01*
G03Y225415I302J-263D01*
G02Y223441I-1131J-987D01*
G03Y222915I302J-263D01*
G02Y220941I-1131J-987D01*
G03Y220415I302J-263D01*
G02Y218441I-1131J-987D01*
G03Y217915I302J-263D01*
G02X1785380Y216928I-1131J-987D01*
G02X1782376I-1502J0D01*
G02X1782746Y217915I1501J0D01*
G03Y218441I-302J263D01*
G02Y220415I1131J987D01*
G03Y220941I-302J263D01*
G02Y222915I1131J987D01*
G03Y223441I-302J263D01*
G02Y225415I1131J987D01*
G37*
G36*
G01X1736577Y225147D02*
G03Y225777I-246J315D01*
G02X1735998Y226962I923J1185D01*
G02X1737500Y228464I1502J0D01*
G02X1738685Y227885I0J-1502D01*
G03X1739315I315J246D01*
G02X1740500Y228464I1185J-923D01*
G02X1742002Y226962I0J-1502D01*
G02X1741423Y225777I-1502J0D01*
G03Y225147I246J-315D01*
G02Y222777I-923J-1185D01*
G03Y222147I246J-315D01*
G02Y219777I-923J-1185D01*
G03Y219147I246J-315D01*
G02Y216777I-923J-1185D01*
G03Y216147I246J-315D01*
G02Y213777I-923J-1185D01*
G03Y213147I246J-315D01*
G02Y210777I-923J-1185D01*
G03Y210147I246J-315D01*
G02X1742002Y208962I-923J-1185D01*
G02X1740500Y207460I-1502J0D01*
G02X1739315Y208039I0J1502D01*
G03X1738685I-315J-246D01*
G02X1737500Y207460I-1185J923D01*
G02X1735998Y208962I0J1502D01*
G02X1736577Y210147I1502J0D01*
G03Y210777I-246J315D01*
G02Y213147I923J1185D01*
G03Y213777I-246J315D01*
G02Y216147I923J1185D01*
G03Y216777I-246J315D01*
G02Y219147I923J1185D01*
G03Y219777I-246J315D01*
G02Y222147I923J1185D01*
G03Y222777I-246J315D01*
G02Y225147I923J1185D01*
G37*
G36*
G01X1833322Y235029D02*
G03X1833868I273J292D01*
G02X1834895Y235435I1027J-1096D01*
G02X1836080Y234856I0J-1502D01*
G03X1836710I315J246D01*
G02X1837895Y235435I1185J-923D01*
G02X1839397Y233933I0J-1502D01*
G02X1839027Y232946I-1501J0D01*
G03Y232420I302J-263D01*
G02Y230446I-1131J-987D01*
G03Y229920I302J-263D01*
G02X1839397Y228933I-1131J-987D01*
G02X1838991Y227906I-1502J0D01*
G03Y227360I292J-273D01*
G02Y225306I-1096J-1027D01*
G03Y224760I292J-273D01*
G02X1839397Y223733I-1096J-1027D01*
G02X1837895Y222231I-1502J0D01*
G02X1836710Y222810I0J1502D01*
G03X1836080I-315J-246D01*
G02X1834895Y222231I-1185J923D01*
G02X1833868Y222637I0J1502D01*
G03X1833322I-273J-292D01*
G02X1831268I-1027J1096D01*
G03X1830722I-273J-292D01*
G02X1828668I-1027J1096D01*
G03X1828122I-273J-292D01*
G02X1827095Y222231I-1027J1096D01*
G02X1825910Y222810I0J1502D01*
G03X1825280I-315J-246D01*
G02X1824095Y222231I-1185J923D01*
G02X1822593Y223733I0J1502D01*
G02X1822999Y224760I1502J0D01*
G03Y225306I-292J273D01*
G02Y227360I1096J1027D01*
G03Y227906I-292J273D01*
G02X1822593Y228933I1096J1027D01*
G02X1822963Y229920I1501J0D01*
G03Y230446I-302J263D01*
G02Y232420I1131J987D01*
G03Y232946I-302J263D01*
G02X1822593Y233933I1131J987D01*
G02X1824095Y235435I1502J0D01*
G02X1825280Y234856I0J-1502D01*
G03X1825910I315J246D01*
G02X1827095Y235435I1185J-923D01*
G02X1828122Y235029I0J-1502D01*
G03X1828668I273J292D01*
G02X1830722I1027J-1096D01*
G03X1831268I273J292D01*
G02X1833322I1027J-1096D01*
G37*
G36*
G01X1785092Y286518D02*
G03X1784560I-266J-299D01*
G02X1783563Y286139I-997J1122D01*
G02Y289143I0J1502D01*
G02X1784560Y288764I0J-1501D01*
G03X1785092I266J299D01*
G02X1786089Y289143I997J-1122D01*
G02Y286139I0J-1502D01*
G02X1785092Y286518I0J1501D01*
G37*
G36*
G01X1792272D02*
G03X1791740I-266J-299D01*
G02X1790743Y286139I-997J1122D01*
G02Y289143I0J1502D01*
G02X1791740Y288764I0J-1501D01*
G03X1792272I266J299D01*
G02X1793269Y289143I997J-1122D01*
G02Y286139I0J-1502D01*
G02X1792272Y286518I0J1501D01*
G37*
G36*
G01X1790622Y293318D02*
G03X1790090I-266J-299D01*
G02X1789093Y292939I-997J1122D01*
G02Y295943I0J1502D01*
G02X1790090Y295564I0J-1501D01*
G03X1790622I266J299D01*
G02X1791619Y295943I997J-1122D01*
G02Y292939I0J-1502D01*
G02X1790622Y293318I0J1501D01*
G37*
G36*
G01X1706027Y224093D02*
G02X1705657Y225080I1131J987D01*
G02X1708661I1502J0D01*
G02X1708291Y224093I-1501J0D01*
G03Y223567I302J-263D01*
G02Y221593I-1131J-987D01*
G03Y221067I302J-263D01*
G02Y219093I-1131J-987D01*
G03Y218567I302J-263D01*
G02Y216593I-1131J-987D01*
G03Y216067I302J-263D01*
G02X1708661Y215080I-1131J-987D01*
G02X1707159Y213578I-1502J0D01*
G02X1706057Y214060I0J1501D01*
G03X1705448Y214034I-293J-272D01*
G02X1705285Y213856I-1186J922D01*
G03X1705276Y213278I272J-293D01*
G02X1705725Y212207I-1053J-1071D01*
G02X1705355Y211220I-1501J0D01*
G03Y210694I302J-263D01*
G02X1705425Y210608I-1129J-991D01*
G03X1705770Y210652I160J120D01*
G02X1707159Y211582I1389J-572D01*
G02Y208578I0J-1502D01*
G02X1706119Y208997I1J1502D01*
G03X1705501Y208918I-277J-289D01*
G02X1704223Y208205I-1278J789D01*
G02X1703000Y208835I0J1502D01*
G03X1702357Y208845I-325J-233D01*
G02X1701164Y208256I-1193J914D01*
G02X1700161Y208640I0J1502D01*
G03X1699615Y208629I-267J-298D01*
G02X1698566Y208202I-1049J1075D01*
G02X1697579Y208572I0J1501D01*
G03X1697053I-263J-302D01*
G02X1696066Y208202I-987J1131D01*
G02X1695123Y208535I0J1502D01*
G03X1694576Y208493I-251J-312D01*
G02X1693466Y208002I-1111J1011D01*
G02X1691964Y209504I0J1502D01*
G02X1692408Y210570I1502J0D01*
G03Y211138I-282J284D01*
G02X1691964Y212204I1058J1066D01*
G02X1692334Y213191I1501J0D01*
G03Y213717I-302J263D01*
G02X1691964Y214704I1131J987D01*
G02X1692522Y215872I1501J0D01*
G03X1692576Y216441I-251J311D01*
G02X1692223Y217409I1149J967D01*
G02X1692593Y218396I1501J0D01*
G03Y218922I-302J263D01*
G02X1692223Y219909I1131J987D01*
G02X1693725Y221411I1502J0D01*
G02X1694712Y221041I0J-1501D01*
G03X1695238I263J302D01*
G02X1697212I987J-1131D01*
G03X1697738I263J302D01*
G02X1698725Y221411I987J-1131D01*
G02X1699706Y221046I0J-1501D01*
G03X1700240Y221057I261J303D01*
G02X1701264Y221460I1024J-1099D01*
G02X1702449Y220881I0J-1502D01*
G03X1703079I315J246D01*
G02X1703197Y221015I1184J-924D01*
G03X1703180Y221594I-284J281D01*
G02X1702683Y222710I1004J1116D01*
G02X1704185Y224212I1502J0D01*
G02X1705400Y223593I0J-1502D01*
G03X1706026Y223566I324J235D01*
G01X1706027Y223567D01*
G03Y224093I-302J263D01*
G37*
G36*
G01X1750946Y225741D02*
G02X1750576Y226728I1131J987D01*
G02X1753580I1502J0D01*
G02X1753210Y225741I-1501J0D01*
G03Y225215I302J-263D01*
G02X1753355Y225019I-1131J-988D01*
G03X1753707Y225042I170J105D01*
G02X1755078Y225930I1371J-614D01*
G02X1756580Y224428I0J-1502D01*
G02X1756210Y223441I-1501J0D01*
G03Y222915I302J-263D01*
G02Y220941I-1131J-987D01*
G03Y220415I302J-263D01*
G02Y218441I-1131J-987D01*
G03Y217915I302J-263D01*
G02X1756580Y216928I-1131J-987D01*
G02X1755078Y215426I-1502J0D01*
G02X1753955Y215931I0J1501D01*
G03X1753324Y215889I-299J-265D01*
G02X1752078Y215226I-1246J839D01*
G02X1750576Y216728I0J1502D01*
G02X1750946Y217715I1501J0D01*
G03Y218241I-302J263D01*
G02Y220215I1131J987D01*
G03Y220741I-302J263D01*
G02Y222715I1131J987D01*
G03Y223241I-302J263D01*
G02Y225215I1131J987D01*
G03Y225741I-302J263D01*
G37*
G36*
G01X1828421Y1499228D02*
G03Y1499777I-291J274D01*
G02X1828012Y1500807I1092J1030D01*
G02X1829514Y1502309I1502J0D01*
G02X1830541Y1501903I0J-1502D01*
G03X1831087I273J292D01*
G02X1832114Y1502309I1027J-1096D01*
G02X1833616Y1500807I0J-1502D01*
G02X1833207Y1499777I-1501J0D01*
G03Y1499228I291J-275D01*
G02X1833616Y1498198I-1092J-1030D01*
G02X1832114Y1496696I-1502J0D01*
G02X1831087Y1497102I0J1502D01*
G03X1830541I-273J-292D01*
G02X1829514Y1496696I-1027J1096D01*
G02X1828012Y1498198I0J1502D01*
G02X1828421Y1499228I1501J0D01*
G37*
G36*
G01X1746492Y1506465D02*
G03X1745862I-315J-246D01*
G02X1744677Y1505886I-1185J923D01*
G02Y1508890I0J1502D01*
G02X1745862Y1508311I0J-1502D01*
G03X1746492I315J246D01*
G02X1747677Y1508890I1185J-923D01*
G02Y1505886I0J-1502D01*
G02X1746492Y1506465I0J1502D01*
G37*
G36*
G01X1730495Y1521874D02*
G03X1731125I315J246D01*
G02X1733495I1185J-923D01*
G03X1734125I315J246D01*
G02X1735310Y1522453I1185J-923D01*
G02Y1519449I0J-1502D01*
G02X1734125Y1520028I0J1502D01*
G03X1733495I-315J-246D01*
G02X1731125I-1185J923D01*
G03X1730495I-315J-246D01*
G02X1728125I-1185J923D01*
G03X1727495I-315J-246D01*
G02X1726310Y1519449I-1185J923D01*
G02Y1522453I0J1502D01*
G02X1727495Y1521874I0J-1502D01*
G03X1728125I315J246D01*
G02X1730495I1185J-923D01*
G37*
G36*
G01X1746119Y1524053D02*
G03X1745489I-315J-246D01*
G02X1744304Y1523474I-1185J923D01*
G02Y1526478I0J1502D01*
G02X1745489Y1525899I0J-1502D01*
G03X1746119I315J246D01*
G02X1747304Y1526478I1185J-923D01*
G02Y1523474I0J-1502D01*
G02X1746119Y1524053I0J1502D01*
G37*
G36*
G01X1730495Y1531368D02*
G03X1731125I315J246D01*
G02X1733495I1185J-923D01*
G03X1734125I315J246D01*
G02X1735310Y1531947I1185J-923D01*
G02Y1528943I0J-1502D01*
G02X1734125Y1529522I0J1502D01*
G03X1733495I-315J-246D01*
G02X1731125I-1185J923D01*
G03X1730495I-315J-246D01*
G02X1728125I-1185J923D01*
G03X1727495I-315J-246D01*
G02X1726310Y1528943I-1185J923D01*
G02Y1531947I0J1502D01*
G02X1727495Y1531368I0J-1502D01*
G03X1728125I315J246D01*
G02X1730495I1185J-923D01*
G37*
G36*
G01X1725843Y1504984D02*
G02X1724649Y1504393I-1194J911D01*
G02Y1507397I0J1502D01*
G02X1725843Y1506806I0J-1502D01*
G03X1726480I319J242D01*
G02X1727674Y1507397I1194J-911D01*
G02Y1504393I0J-1502D01*
G02X1726480Y1504984I0J1502D01*
G03X1725843I-318J-242D01*
G37*
G36*
G01Y1513034D02*
G02X1724649Y1512443I-1194J911D01*
G02Y1515447I0J1502D01*
G02X1725843Y1514856I0J-1502D01*
G03X1726480I319J242D01*
G02X1727674Y1515447I1194J-911D01*
G02Y1512443I0J-1502D01*
G02X1726480Y1513034I0J1502D01*
G03X1725843I-318J-242D01*
G37*
G36*
G01X1773356Y61232D02*
G03Y61842I-259J305D01*
G02X1772826Y62987I972J1145D01*
G02X1775830I1502J0D01*
G02X1775300Y61842I-1502J0D01*
G03Y61232I259J-305D01*
G02X1775830Y60087I-972J-1145D01*
G02X1772826I-1502J0D01*
G02X1773356Y61232I1502J0D01*
G37*
G36*
G01X1778806Y71172D02*
G03Y71782I-259J305D01*
G02X1778276Y72927I972J1145D01*
G02X1781280I1502J0D01*
G02X1780750Y71782I-1502J0D01*
G03Y71172I259J-305D01*
G02X1781280Y70027I-972J-1145D01*
G02X1778276I-1502J0D01*
G02X1778806Y71172I1502J0D01*
G37*
G36*
G01X1787090Y83260D02*
G03X1786995Y83857I-306J257D01*
G02X1786288Y85132I796J1275D01*
G02X1789292I1502J0D01*
G02X1788938Y84164I-1502J0D01*
G03X1789033Y83567I306J-257D01*
G02X1789740Y82292I-796J-1275D01*
G02X1786736I-1502J0D01*
G02X1787090Y83260I1502J0D01*
G37*
G36*
G01X1754882Y109454D02*
G03Y110000I-292J273D01*
G02X1754476Y111027I1096J1027D01*
G02X1757480I1502J0D01*
G02X1757074Y110000I-1502J0D01*
G03Y109454I292J-273D01*
G02X1757480Y108427I-1096J-1027D01*
G02X1754476I-1502J0D01*
G02X1754882Y109454I1502J0D01*
G37*
G36*
G01X1736010Y110650D02*
G03Y111204I-288J277D01*
G02X1735618Y112177I1010J972D01*
G02X1738422I1402J0D01*
G02X1738030Y111204I-1402J-1D01*
G03Y110650I288J-277D01*
G02X1738422Y109677I-1010J-972D01*
G02X1735618I-1402J0D01*
G02X1736010Y110650I1402J1D01*
G37*
G36*
G01X1739553D02*
G03Y111204I-288J277D01*
G02X1739161Y112177I1010J972D01*
G02X1741965I1402J0D01*
G02X1741573Y111204I-1402J-1D01*
G03Y110650I288J-277D01*
G02X1741965Y109677I-1010J-972D01*
G02X1739161I-1402J0D01*
G02X1739553Y110650I1402J1D01*
G37*
G36*
G01X1743096D02*
G03Y111204I-288J277D01*
G02X1742704Y112177I1010J972D01*
G02X1745508I1402J0D01*
G02X1745116Y111204I-1402J-1D01*
G03Y110650I288J-277D01*
G02X1745508Y109677I-1010J-972D01*
G02X1742704I-1402J0D01*
G02X1743096Y110650I1402J1D01*
G37*
G36*
G01X1746640D02*
G03Y111204I-288J277D01*
G02X1746248Y112177I1010J972D01*
G02X1749052I1402J0D01*
G02X1748660Y111204I-1402J-1D01*
G03Y110650I288J-277D01*
G02X1749052Y109677I-1010J-972D01*
G02X1746248I-1402J0D01*
G02X1746640Y110650I1402J1D01*
G37*
G36*
G01X1768261Y112033D02*
G03Y112621I-270J294D01*
G02X1767776Y113727I1017J1105D01*
G02X1770780I1502J0D01*
G02X1770295Y112621I-1502J-1D01*
G03Y112033I270J-294D01*
G02X1770780Y110927I-1017J-1105D01*
G02X1770250Y109782I-1502J0D01*
G03Y109172I259J-305D01*
G02X1770780Y108027I-972J-1145D01*
G02X1767776I-1502J0D01*
G02X1768306Y109172I1502J0D01*
G03Y109782I-259J305D01*
G02X1767776Y110927I972J1145D01*
G02X1768261Y112033I1502J1D01*
G37*
G36*
G01X1783161Y112233D02*
G03Y112821I-270J294D01*
G02X1782676Y113927I1017J1105D01*
G02X1785680I1502J0D01*
G02X1785195Y112821I-1502J-1D01*
G03Y112233I270J-294D01*
G02X1785680Y111127I-1017J-1105D01*
G02X1785150Y109982I-1502J0D01*
G03Y109372I259J-305D01*
G02X1785680Y108227I-972J-1145D01*
G02X1782676I-1502J0D01*
G02X1783206Y109372I1502J0D01*
G03Y109982I-259J305D01*
G02X1782676Y111127I972J1145D01*
G02X1783161Y112233I1502J1D01*
G37*
G36*
G01X1759793Y115804D02*
G03X1759163I-315J-246D01*
G02X1757978Y115225I-1185J923D01*
G02Y118229I0J1502D01*
G02X1759163Y117650I0J-1502D01*
G03X1759793I315J246D01*
G02X1760978Y118229I1185J-923D01*
G02Y115225I0J-1502D01*
G02X1759793Y115804I0J1502D01*
G37*
G36*
G01X1787396Y76818D02*
G02X1786736Y78062I842J1244D01*
G02X1789740I1502J0D01*
G02X1789080Y76818I-1502J0D01*
G03Y76156I224J-331D01*
G02X1789740Y74912I-842J-1244D01*
G02X1788238Y73410I-1502J0D01*
G02X1786760Y74647I0J1501D01*
G03X1786109Y74882I-394J-71D01*
G02X1785142Y74530I-966J1150D01*
G02Y77534I0J1502D01*
G02X1786620Y76297I0J-1501D01*
G03X1787271Y76062I394J71D01*
G02X1787396Y76156I964J-1152D01*
G03Y76818I-224J331D01*
G37*
G36*
G01X1761742Y105315D02*
G02X1760478Y104625I-1264J813D01*
G02Y107629I0J1502D01*
G02X1761742Y106939I0J-1503D01*
G03X1762414I336J216D01*
G02X1763678Y107629I1264J-813D01*
G02Y104625I0J-1502D01*
G02X1762414Y105315I0J1503D01*
G03X1761742I-336J-216D01*
G37*
G54D34*
X67681Y360702D03*
X55190Y360862D03*
X87654Y376026D03*
X87520Y386502D03*
X164000Y415362D03*
X172507Y417205D03*
X195050Y417465D03*
X149371Y419383D03*
X85826Y420319D03*
X164000Y420362D03*
X177871Y421383D03*
X71772Y421746D03*
X199139Y422882D03*
X149371Y423383D03*
X85826Y424319D03*
X163926Y425383D03*
X177871D03*
X187371D03*
X149371Y427383D03*
X85826Y428319D03*
X199047Y428626D03*
X191305Y430216D03*
X163926Y430883D03*
X177871D03*
X187371D03*
X149371Y431383D03*
X101317Y431727D03*
X75490Y432519D03*
X194440Y433895D03*
X152826Y434362D03*
X64150Y434972D03*
X149371Y435383D03*
X163926D03*
X53800Y435451D03*
X184550Y435712D03*
X75516Y436519D03*
X180740Y437562D03*
X30680Y438142D03*
X84410Y438519D03*
X149371Y439383D03*
X152826Y439397D03*
X163926D03*
X194440Y439565D03*
X163926Y443319D03*
X149371Y443383D03*
X177871D03*
X68365Y443677D03*
X54762Y444993D03*
X196215Y447565D03*
X94439Y450081D03*
X197650Y455712D03*
X72981Y466385D03*
X199720Y732862D03*
X59500Y738700D03*
X211220Y740362D03*
X58658Y754145D03*
X73759Y754726D03*
X253057Y755345D03*
X245487Y755435D03*
X259510Y757822D03*
X110527Y758869D03*
X73759Y759246D03*
X81966D03*
X85877Y759275D03*
X93295Y762019D03*
X73865Y763164D03*
X68315Y765664D03*
X46994Y1663165D03*
X56799Y1544094D03*
X81038Y1536899D03*
X96251Y1577532D03*
X56799Y1524094D03*
Y1528094D03*
X161321Y1540858D03*
X153271Y1540961D03*
X56799Y1548094D03*
Y1532094D03*
X84048Y1578008D03*
X103902Y1584337D03*
X100620Y1596367D03*
X116798Y1598572D03*
X65520Y1615972D03*
X65120Y1609909D03*
X77040Y1601102D03*
X53333Y1671862D03*
X90713Y1585852D03*
Y1589852D03*
Y1593867D03*
X54535Y1658447D03*
X54478Y1663669D03*
X54333Y1604359D03*
X48269Y1672771D03*
X44833Y1659909D03*
X91538Y1539399D03*
X112749Y1548594D03*
X56799Y1556094D03*
Y1552094D03*
X112749Y1540594D03*
Y1536594D03*
Y1560594D03*
Y1544594D03*
X127366Y1535855D03*
X112749Y1564594D03*
X185895Y1535462D03*
Y1552875D03*
X159107Y1571364D03*
X127366Y1541874D03*
Y1547935D03*
X185895Y1544029D03*
X72774Y1549669D03*
X185895Y1548487D03*
Y1539723D03*
Y1557875D03*
X140104Y1560136D03*
X129670Y1563160D03*
X123230Y1597350D03*
X161374Y1549073D03*
X153138Y1549032D03*
X74100Y1613300D03*
X116171Y485041D03*
X153737Y514893D03*
X149472Y506810D03*
X139153Y516453D03*
X131737Y496295D03*
X136982Y497090D03*
X141220Y498810D03*
X141325Y503806D03*
X131295Y487822D03*
X135006Y487753D03*
X124124Y495883D03*
X125013Y491829D03*
X125070Y486736D03*
X151378Y526924D03*
X207140Y693636D03*
X203179Y693626D03*
X203199Y690006D03*
X200018Y677492D03*
X207129Y690027D03*
X95725Y654540D03*
X80123Y664031D03*
X83208Y646436D03*
X83165Y652564D03*
X81285Y689804D03*
X99880Y526300D03*
X103397Y667272D03*
X102420Y697262D03*
X84035Y697604D03*
X107419Y487807D03*
X80300Y641862D03*
X91610Y721414D03*
X102120Y688650D03*
X83250Y665428D03*
X84470Y668702D03*
X80135Y667933D03*
X104875Y490980D03*
X99021Y663732D03*
X131330Y665740D03*
X95860Y659622D03*
X110689Y498271D03*
X122575Y671930D03*
X91078Y649584D03*
X91027Y643276D03*
X83004Y705141D03*
X97295Y699786D03*
X86433Y688160D03*
X224900Y713293D03*
X287607Y754962D03*
X304602Y727968D03*
X227430Y719772D03*
X264000Y726262D03*
X266700Y730962D03*
X270100Y727262D03*
X238940Y716652D03*
X290077Y739735D03*
X299427Y768265D03*
X283350Y728483D03*
X316397Y776125D03*
X317967Y746985D03*
X319557Y736225D03*
X287820Y727962D03*
X317967Y771875D03*
X338667Y772452D03*
X289137Y735275D03*
X284358Y732562D03*
X290680Y745312D03*
X336446Y746486D03*
X297087Y721249D03*
X293027Y755985D03*
X341527Y778362D03*
X285046Y746702D03*
X289047Y760245D03*
X285046Y737964D03*
X281046Y746702D03*
X140142Y1392545D03*
X180977Y1396173D03*
X159858Y1409361D03*
X152684Y1403451D03*
X147307Y1404745D03*
X188211Y1406691D03*
X219587Y1443402D03*
X190827Y1403451D03*
X165500Y1440362D03*
X219587Y1435402D03*
Y1439402D03*
X140142Y1396275D03*
X244822Y111543D03*
X275797Y129592D03*
X269191Y121092D03*
X275797Y120245D03*
X263550Y120922D03*
X253910Y115722D03*
X253878Y111771D03*
X244822Y115543D03*
X305247Y71567D03*
X310459Y75892D03*
X301600Y82457D03*
X302310Y75673D03*
X307820Y95724D03*
X313457Y96803D03*
X323040Y73122D03*
X292942Y71499D03*
X238297Y129703D03*
X295357Y88903D03*
X265910Y125492D03*
X248097Y92143D03*
X247720Y75862D03*
X284482Y569548D03*
X344446Y739434D03*
X331339Y709313D03*
X354100Y720743D03*
X348880Y703442D03*
X352879Y728657D03*
X349187Y715485D03*
X335467Y725335D03*
X360990Y726862D03*
X358902Y743035D03*
X331760Y705882D03*
X335677Y715215D03*
X328120Y710862D03*
X360470Y705965D03*
X483030Y1170070D03*
Y1153370D03*
Y1161570D03*
X470987Y1409965D03*
X505777Y1425579D03*
X509246Y1420002D03*
X470890Y1435838D03*
X484921Y1413246D03*
X474983Y1400385D03*
X485141Y1405430D03*
X483560Y1401712D03*
X456619Y1431189D03*
X458441Y1414893D03*
X459550Y1401348D03*
X465947Y1398355D03*
X451080Y1433740D03*
X451048Y1404914D03*
X478449Y1448158D03*
X443715Y1436052D03*
X443850Y1423404D03*
X440164Y1433982D03*
X445723Y1419730D03*
X446230Y1407722D03*
X445230Y1411719D03*
X438458Y1402169D03*
X448020Y1391862D03*
X443424Y1397869D03*
X439391Y1398266D03*
X448114Y1396812D03*
X441369Y1394260D03*
X447110Y1403812D03*
X443842Y1389106D03*
X439030Y1383692D03*
X463140Y1451562D03*
X433954Y1439029D03*
X433897Y1434670D03*
X436467Y1391687D03*
X436780Y1387387D03*
X732226Y1396212D03*
X711620Y1409386D03*
X701830Y1407326D03*
X704446Y1403476D03*
X694596Y1396198D03*
X566510Y1352217D03*
X666303Y1403476D03*
X570645Y1361358D03*
X571620Y1424492D03*
X663687Y1407279D03*
X571555Y1352487D03*
X555057Y1449395D03*
X576220Y1423862D03*
X499435Y1338799D03*
X528929Y1364212D03*
X531563Y1361597D03*
X653761Y1396300D03*
X661100Y1451012D03*
X653690Y1392362D03*
X422320Y1383862D03*
X435179Y1325373D03*
X426320Y1383862D03*
X496319Y1341264D03*
X419861Y1429718D03*
X416926Y1426471D03*
X411162Y1414126D03*
X403051Y1325373D03*
X432628Y1327845D03*
X410912Y1418177D03*
X401244Y1440773D03*
X467307Y1325373D03*
X410074Y1424993D03*
X422708Y1437560D03*
X382489Y1428478D03*
X368391Y1328161D03*
X430320Y1383862D03*
X433539Y1430613D03*
X400073Y1327653D03*
X400888Y1395508D03*
X338795Y1338799D03*
X336179Y1342753D03*
X425030Y1434292D03*
X403125Y1425008D03*
X392517Y1419015D03*
X390914Y1412991D03*
X306667Y1361597D03*
X304051Y1365453D03*
X390687Y1431713D03*
X396822Y1439340D03*
X400991Y1417264D03*
X419302Y1434700D03*
X418320Y1383862D03*
X414333Y1385292D03*
X410933Y1384648D03*
X414909Y1395658D03*
X464191Y1327793D03*
X412416Y1431645D03*
X400924Y1408227D03*
X401079Y1399208D03*
X370923Y1325373D03*
X400926Y1404707D03*
X386827Y1429525D03*
X385667Y1433425D03*
X775317Y764025D03*
X783507Y761875D03*
X822442Y762369D03*
X836847Y762495D03*
X844957Y763065D03*
X854237Y1250358D03*
X884747Y871745D03*
X884619Y916477D03*
X881372Y920655D03*
X894897Y871745D03*
X897000Y891895D03*
X916974Y962108D03*
X923403Y983327D03*
X917980Y974952D03*
X923930Y976652D03*
X923322Y990227D03*
X924440Y996852D03*
X914838Y985989D03*
X931496Y962082D03*
X930233Y983298D03*
X930274Y990237D03*
X932310Y996812D03*
X975900Y1265062D03*
X706720Y100462D03*
X712290Y106722D03*
X712340Y128093D03*
X729933Y108388D03*
X707008Y125804D03*
X677978Y119668D03*
X774059Y68912D03*
X769474Y75360D03*
X785135Y267822D03*
X853828Y265057D03*
Y269043D03*
X867700Y268262D03*
X813900Y269698D03*
X829680Y264580D03*
X808800Y267900D03*
X835400Y268800D03*
X774982Y446908D03*
X874295Y163862D03*
X875169Y185113D03*
X873200Y194262D03*
X877971Y196652D03*
X878220Y192055D03*
X877724Y200837D03*
X908620Y188899D03*
X927133Y189386D03*
X936424Y184190D03*
X871580Y183370D03*
X949560Y981392D03*
X990115Y173039D03*
X985499Y168753D03*
X985431Y181058D03*
X1006220Y160799D03*
X996415Y172579D03*
X1002920Y174799D03*
X999220Y185299D03*
X1002720D03*
X1006220D03*
X1008120Y198293D03*
X990195Y216823D03*
X1000610Y211039D03*
X1005640Y210969D03*
X1009720Y160799D03*
X1010005Y208424D03*
X1011320Y202169D03*
X1001101Y165510D03*
X1025862Y291727D03*
X1015520Y302862D03*
X1020720Y310937D03*
X1021118Y294290D03*
X1080323Y265438D03*
X1083823D03*
X1076823D03*
X1032317Y291284D03*
X1037618Y261200D03*
X994322Y404090D03*
X1005123Y414662D03*
X997225Y419162D03*
X1010420Y416062D03*
X1015420Y410862D03*
X1021239Y416974D03*
X1015096Y373758D03*
X1017163Y367963D03*
X1009883Y367955D03*
X1084146Y67102D03*
X1097794Y67881D03*
X1102561Y78461D03*
X1110977Y55505D03*
X1113594Y69862D03*
X1109020Y80592D03*
X1132856Y52926D03*
X1145603Y73679D03*
X1189393Y60183D03*
X1213026Y56742D03*
X1123379Y1443583D03*
X1133169Y1445690D03*
X1125995Y1439780D03*
X1154288Y1432502D03*
X1161522Y1443630D03*
X1164138Y1439780D03*
X1191918Y1432516D03*
X1257672Y1351008D03*
X1282928Y1361833D03*
X1314936Y1338799D03*
X1312650Y1342572D03*
X1344532Y1328161D03*
X1347397Y1325320D03*
X1378417Y1415292D03*
X1370891Y1410306D03*
X1368980Y1457122D03*
X1396311Y1385712D03*
X1398680Y1380582D03*
X1390474Y1385142D03*
X1387074Y1384272D03*
X1390513Y1395452D03*
X1387470Y1418302D03*
X1381066Y1425008D03*
X1393630Y1426562D03*
X1388557Y1431645D03*
X1395907Y1430227D03*
X1395443Y1434700D03*
X1398569Y1437860D03*
X1383429Y1427652D03*
X1401655Y1384676D03*
X1406461Y1383862D03*
X1415171Y1383692D03*
X1412961Y1387387D03*
X1401371Y1434592D03*
X1410477Y1440117D03*
X1418990Y1387452D03*
X1422594Y1383301D03*
X1421864Y1419730D03*
X1437443Y1406289D03*
X1444997Y1392885D03*
X1434312Y1415197D03*
X1443112Y1417929D03*
X1445020Y1412672D03*
X1443676Y1432624D03*
X1433750Y1429208D03*
X1439742Y1436924D03*
X1434720Y1454862D03*
X1440440Y1454892D03*
X1459968Y1402765D03*
X1451176Y1399026D03*
X1461062Y1413246D03*
X1455006Y1447938D03*
X1485387Y1420002D03*
X1481918Y1425579D03*
X1613047Y1415669D03*
X1614927Y1426076D03*
Y1429896D03*
X1627469Y1437072D03*
X1624853Y1440875D03*
X1655762Y1429794D03*
X1665612Y1437072D03*
X1662996Y1440922D03*
X1672786Y1442982D03*
X1693392Y1429808D03*
X1387066Y1401734D03*
X1451198Y1403047D03*
X1290293Y247562D03*
X1256093Y143462D03*
Y149462D03*
X1266715Y244692D03*
X1265065Y249982D03*
X1267150Y305998D03*
X1281093Y144516D03*
X1278320Y239292D03*
X1271150Y305792D03*
X1291478Y137745D03*
X1292293Y143162D03*
X1295053Y140181D03*
X1285710Y249182D03*
X1288637Y240448D03*
X1286611Y260908D03*
X1290005Y290268D03*
X1302964Y124633D03*
X1315156Y130656D03*
X1314920Y135361D03*
X1301993Y140462D03*
X1330273Y128373D03*
X1326493Y249562D03*
X1323912Y245111D03*
X1339280Y126175D03*
X1332497Y133931D03*
X1343034Y141698D03*
X1348620Y136162D03*
X1458911Y1161569D03*
Y1170069D03*
X1571577Y747145D03*
X1590915Y755793D03*
X1699110Y727452D03*
X1713450Y728222D03*
X1411115Y1420289D03*
Y1412789D03*
X1458200Y1565037D03*
X1453600Y1595662D03*
X1451580Y1627990D03*
X1666198Y1565557D03*
X1526675Y140117D03*
X1526083Y146225D03*
X1535520Y151562D03*
X1535450Y155262D03*
X1554239Y138263D03*
X1556049Y147711D03*
X1604122Y48720D03*
X1542401Y141561D03*
X1568688Y48720D03*
X1632901D03*
X1669948D03*
X1677035D03*
X1684122D03*
X1691208D03*
X1554515D03*
X1582862D03*
X1597035D03*
X1639988D03*
X1647074D03*
X1705381Y37106D03*
X1589948Y48720D03*
X1654161D03*
X1575775D03*
X1561602D03*
X1715711Y474399D03*
X1716134Y478443D03*
X1713977Y457137D03*
X1708977Y458542D03*
X1721936Y469263D03*
X1716148Y483720D03*
X1716156Y487685D03*
X1716278Y491676D03*
X1649833Y594946D03*
X1653794Y594956D03*
X1653774Y598576D03*
X1649844Y598555D03*
X1656955Y611090D03*
X1653220Y620662D03*
X1664970Y472112D03*
X1664197Y602191D03*
X1669222Y604490D03*
X1660660Y602273D03*
X1645530Y549160D03*
X1642720Y560862D03*
X1702127Y468719D03*
X1721220Y458362D03*
X1713977Y470804D03*
X1708977D03*
X1675664Y513802D03*
X1683702Y514687D03*
X1676600Y523902D03*
X1679941Y552222D03*
X1716480Y691410D03*
X1712824Y696476D03*
X1713920Y700962D03*
X1739316Y480939D03*
X1725522Y482869D03*
X1730954Y478062D03*
X1733354Y486869D03*
Y490869D03*
X1690999Y513107D03*
X1699553D03*
X1699265Y521507D03*
X1690999Y525507D03*
X1688768Y518107D03*
X1699251Y533642D03*
X1691104Y530503D03*
X1699107Y555783D03*
X1746720Y464862D03*
X1702930Y526102D03*
X1701726Y518107D03*
X1699666Y541507D03*
X1716110Y532632D03*
X1717987Y569705D03*
X1689544Y543874D03*
X1657755Y517910D03*
X1684940Y463030D03*
X1689095Y462640D03*
X1710122Y703509D03*
X1716087Y495665D03*
X1696402Y709533D03*
X1645300Y612202D03*
X1709828Y719283D03*
X1654110Y434177D03*
X1690208Y421855D03*
X1701124Y423802D03*
X1694050Y416643D03*
X1695455Y422287D03*
X1707544Y431745D03*
X1707568Y420370D03*
X1690140Y434160D03*
X1713720Y381152D03*
Y391652D03*
Y384652D03*
Y388152D03*
X1717220Y391652D03*
Y388152D03*
Y384652D03*
X1754234Y190836D03*
X1751800Y206762D03*
X1746484Y279682D03*
X1749450Y293862D03*
X1756204Y301695D03*
X1752000Y306562D03*
X1761500Y214062D03*
X1765000D03*
X1768500D03*
X1761936Y310709D03*
X1769230Y310478D03*
X1772000Y214062D03*
X1777354Y295489D03*
X1783018Y301729D03*
X1760104Y301648D03*
X1702490Y204780D03*
X1726149Y1496270D03*
X1726120Y1490262D03*
X1800450Y1505230D03*
X1795561Y1524729D03*
X1818289Y1501591D03*
X1811494Y1505349D03*
X1813994Y1507891D03*
X1824995Y1502201D03*
X1813700Y1494762D03*
X1807150Y1505675D03*
X1720895Y68062D03*
X1729620Y57262D03*
X1729520Y61762D03*
X1725320Y67962D03*
X1730820Y76362D03*
X1726918Y101967D03*
X1723018Y101667D03*
X1723218Y93267D03*
X1712520Y117862D03*
X1712720Y111862D03*
X1719943Y112667D03*
Y116667D03*
X1728999Y112895D03*
X1729080Y118132D03*
X1739720Y120892D03*
X1745010Y122952D03*
X1750820Y119972D03*
X1758063Y72623D03*
X1767170Y83607D03*
X1767990Y76797D03*
X1760478Y90027D03*
X1770368Y72691D03*
X1758300Y128242D03*
X1775580Y73330D03*
X1781485Y88192D03*
X1773611Y88293D03*
X1778578Y97927D03*
X1778478Y90627D03*
G54D46*
X1317621Y867401D03*
Y873810D03*
G54D37*
X150113Y488487D03*
X994743Y289843D03*
G54D49*
X1423251Y1403812D03*
G54D36*
X347029Y870606D03*
X345179Y873810D03*
X348879D03*
X356278D03*
X363678D03*
X371078D03*
X354429Y877014D03*
X358129D03*
X361829D03*
X365529D03*
X369229D03*
X372929D03*
X376629D03*
X380329D03*
X374779Y880219D03*
X382179D03*
X389579D03*
X378478Y886627D03*
X385878D03*
X387729Y889832D03*
X391429D03*
X389579Y893036D03*
X393279D03*
X391428Y896240D03*
X395129D03*
X393278Y899445D03*
X396978D03*
X395129Y902649D03*
X398828D03*
X400678Y905853D03*
X404378D03*
X402529Y909057D03*
X406229D03*
X409929D03*
X404378Y912262D03*
X408078D03*
X402529Y915466D03*
X406229D03*
X404378Y918670D03*
X408078D03*
X402529Y921875D03*
X406229D03*
X432129Y902649D03*
X402529Y877014D03*
X417329Y915466D03*
X393278Y860993D03*
X391429Y864197D03*
X418229Y926896D03*
X374779Y854584D03*
X419178Y918670D03*
X396979Y867401D03*
X422878Y893036D03*
X382179Y854584D03*
X422878Y912262D03*
X413629Y896240D03*
X415478Y893036D03*
X409929Y896240D03*
X417329D03*
X384029Y864197D03*
X389579Y854584D03*
X433978Y905853D03*
X406229Y896240D03*
X430279Y925079D03*
X415478Y886627D03*
X424729Y921875D03*
X359979Y854584D03*
X402529Y889832D03*
X428429Y915466D03*
X367379Y854584D03*
X426578Y912262D03*
X428429Y909057D03*
Y902649D03*
X424729Y915466D03*
X433978Y899445D03*
X428429Y896240D03*
X426578Y899445D03*
X421029Y896240D03*
X432129D03*
X430278Y893036D03*
X424729Y896240D03*
X430278Y886627D03*
X422878D03*
X433979Y893036D03*
X421029Y889832D03*
X424729D03*
X426579Y893036D03*
X428429Y889832D03*
X432129D03*
X426579Y880219D03*
X433979D03*
X415479Y918670D03*
X385878Y860993D03*
X404378Y893036D03*
X400678Y873810D03*
X417329Y889832D03*
X398829Y877014D03*
X419179Y893036D03*
X411779D03*
X378478Y860993D03*
X432128Y909057D03*
X424728D03*
X421029D03*
X409929Y889832D03*
X345178Y854584D03*
X341478D03*
X426578Y918670D03*
X356278Y860993D03*
X406229Y889832D03*
X348879Y860993D03*
X343327Y851380D03*
X408079Y893036D03*
X419179Y880219D03*
X415478Y912262D03*
X395129Y864197D03*
X347029Y857789D03*
X345179Y860993D03*
X343327Y857789D03*
X426578Y905853D03*
X387729Y864197D03*
X417329Y921875D03*
X432129Y915466D03*
X408078Y886627D03*
X422878Y918670D03*
X430278Y905853D03*
X419178Y912262D03*
X421029Y921875D03*
X404379Y880219D03*
X417329Y909057D03*
X432129Y921875D03*
X406229Y877014D03*
X430278Y918670D03*
X428429Y921875D03*
X413629Y889832D03*
X409929Y877014D03*
X363678Y860993D03*
X371078D03*
X430278Y912262D03*
X411779Y880219D03*
X389579Y867401D03*
X433979Y912262D03*
X421029Y915466D03*
X433979Y918670D03*
X422878Y905853D03*
X417762Y1076587D03*
X454761Y1089403D03*
X460311Y1086200D03*
X451060Y1082995D03*
X462161Y1095812D03*
X458461D03*
X454761D03*
X456612Y1092607D03*
X414062Y1070178D03*
X447361Y1082995D03*
X419611Y1047749D03*
X458462Y1102221D03*
X456611Y1099017D03*
X460312Y1105426D03*
X417762Y1063770D03*
X452911Y1073383D03*
X451061Y1076587D03*
X410362Y1070178D03*
X447361Y1121447D03*
X415911Y1066974D03*
X460312Y1099016D03*
X419611Y1060565D03*
Y1073383D03*
X447361Y1115039D03*
Y1127856D03*
X415911Y1047749D03*
X412211D03*
X408511Y1041340D03*
Y1047749D03*
X421462Y1057361D03*
X434411Y1060565D03*
X451062Y1050952D03*
X425162Y1044544D03*
X447361Y1063770D03*
Y1108630D03*
Y1057361D03*
X446930Y973144D03*
Y979553D03*
X458462Y1044544D03*
X423311Y1047749D03*
X427011D03*
X456611Y1086200D03*
X430712Y1047749D03*
X452911Y1086200D03*
X432561Y1057361D03*
X421462Y1063770D03*
X449213Y1060565D03*
X434411Y1028524D03*
X451062Y1089404D03*
X452911Y1099017D03*
X415911Y1054157D03*
X458462Y1115039D03*
X408511Y1054157D03*
X434411D03*
Y1009298D03*
X448779Y937897D03*
X458460Y1050952D03*
X458462Y1134264D03*
X446930Y966736D03*
Y953918D03*
Y960327D03*
Y947510D03*
X446929Y941101D03*
X441379Y937897D03*
X445079D03*
X437679D03*
X430711Y1066974D03*
X428862Y1070178D03*
X425162D03*
X421462D03*
X434411Y1066974D03*
Y1073383D03*
X423311Y1066974D03*
X427011D03*
X434412Y1002889D03*
X427011Y1073383D03*
X430711D03*
X421462Y1076587D03*
X432560Y1070178D03*
X423311Y1073383D03*
X430711Y1060565D03*
X428861Y1063770D03*
X423311Y1060565D03*
X421462Y1050952D03*
X433980Y982757D03*
X414062Y1044544D03*
X428862D03*
X471412Y1137469D03*
X447362Y1018911D03*
X462162Y1076587D03*
X406662Y1050952D03*
X462162Y1070178D03*
X412211Y1041340D03*
X460311D03*
X462161Y1089403D03*
X456611Y1066974D03*
X458462Y1076587D03*
X434412Y1034932D03*
X456611Y1047749D03*
X428862Y1050952D03*
X433980Y950714D03*
X417762Y1057361D03*
X425162D03*
X419611Y1041340D03*
X433980Y957123D03*
X460311Y1073383D03*
X421462Y1044544D03*
X427011Y1054157D03*
X414060Y1050952D03*
X456612Y1079791D03*
X412211Y1066974D03*
X452911Y1041340D03*
X417762Y1070178D03*
X451062Y1057361D03*
X458462Y1121447D03*
X414062Y1063770D03*
X454762Y1057361D03*
X415911Y1060565D03*
X430711Y1054157D03*
X408511Y1066974D03*
X447362Y1031728D03*
X449212Y1086200D03*
X449211Y1066974D03*
X452911D03*
X451062Y1070178D03*
Y1095813D03*
X423312Y1041340D03*
X462162Y1102221D03*
X419611Y1066974D03*
X433980Y963531D03*
X425162Y1050952D03*
X454761Y1063770D03*
X447362Y1006094D03*
X417761Y1050952D03*
X447362Y999685D03*
X434411Y1022115D03*
X410361Y1050952D03*
X476961Y1140973D03*
X449211Y1054157D03*
X447362Y1012502D03*
X469561Y1140973D03*
X417762Y1044544D03*
X462162Y1108630D03*
X432561Y1050952D03*
X423311Y1054157D03*
X460311Y1092608D03*
X412211Y1060565D03*
X408511D03*
X458461Y1082995D03*
X410362Y1063770D03*
X427012Y1041340D03*
X414062Y1057361D03*
X410362D03*
X456611Y1060565D03*
X462161Y1063770D03*
X454762Y1038136D03*
X447361Y1134264D03*
X406662Y1057361D03*
X412211Y1054157D03*
X406662Y1063770D03*
X460311Y1066974D03*
Y1047750D03*
X451061Y1063770D03*
X454762Y1050952D03*
X408511Y1073383D03*
X452911Y1092608D03*
X447360Y1038136D03*
X452911Y1047749D03*
X451061Y1044544D03*
X449211Y1047749D03*
X415911Y1041340D03*
X454762Y1070178D03*
X406662Y1044544D03*
X433980Y944305D03*
X433979Y937897D03*
X460312Y1079791D03*
X458460Y1070178D03*
X456611Y1073383D03*
X428861Y1057361D03*
X427011Y1060565D03*
X425162Y1063770D03*
X454761Y1076587D03*
X433980Y976348D03*
X460311Y1060565D03*
X434412Y1015706D03*
X452911Y1060565D03*
X447361Y1050952D03*
X433980Y969940D03*
X410362Y1044544D03*
X462161Y1057361D03*
X458462Y1063770D03*
X458461Y1089403D03*
X454760Y1082995D03*
X447361Y1076587D03*
X449211Y1073383D03*
X447362Y1025319D03*
X419611Y1054157D03*
X415911Y1073383D03*
X458462Y1127856D03*
X449211Y1079791D03*
X462162Y1050952D03*
X406662Y1070178D03*
X454762Y1044544D03*
X462162D03*
X456611Y1041340D03*
X460312Y1054157D03*
X458462Y1057361D03*
X456611Y1054157D03*
X452911Y1079791D03*
X447361Y1070178D03*
X412211Y1073383D03*
X452911Y1054157D03*
X464011Y1041340D03*
X462162Y1082995D03*
X432129Y864197D03*
X428429D03*
X419179Y854584D03*
X421029Y864197D03*
X417329D03*
X409929Y870606D03*
X433979Y867401D03*
X406229Y864197D03*
X404379Y854584D03*
X413629Y864197D03*
X411779Y854584D03*
X409929Y864197D03*
X426579Y867401D03*
X419179D03*
X411779D03*
X433979Y854584D03*
X426579D03*
X424729Y864197D03*
X400678Y957122D03*
X396978D03*
X401111Y1015705D03*
X398829Y947509D03*
X402962Y1012501D03*
Y999684D03*
X401111Y1009297D03*
X404986Y1022427D03*
X399261Y1018910D03*
X399262Y1012501D03*
X401111Y1002888D03*
X400678Y963530D03*
X399262Y1006093D03*
X396979Y950713D03*
X402529Y960326D03*
X398828D03*
X483929Y889832D03*
X443229Y896240D03*
X441379Y854584D03*
X452479Y893036D03*
X476529Y889832D03*
X465429Y864197D03*
X470979Y867401D03*
X483928Y902649D03*
X480229Y915466D03*
X445078Y899445D03*
X443229Y902649D03*
X441379Y905853D03*
X450629Y902649D03*
X448779Y867401D03*
X446929Y902649D03*
Y864197D03*
X443228Y851380D03*
X448778Y899445D03*
X443229Y889832D03*
Y915466D03*
X458029Y889832D03*
X445079Y905853D03*
X450630Y909057D03*
Y896240D03*
X446929Y915466D03*
X476529Y864197D03*
X448779Y905853D03*
X443229Y864197D03*
X472829D03*
X446929Y909057D03*
X478379Y854584D03*
X470979D03*
X483929Y864197D03*
X456179Y854584D03*
X480229Y864197D03*
X469129D03*
X456179Y867401D03*
X463578Y918670D03*
X469129Y921875D03*
X458029Y864197D03*
X463579Y867401D03*
Y854584D03*
X474678Y899445D03*
X480228Y909057D03*
X472829D03*
X476529D03*
X480229Y928283D03*
X458029Y877014D03*
X450629Y921875D03*
X448779Y880219D03*
X478379Y893036D03*
X472829Y902649D03*
X485778Y918670D03*
X489478Y925079D03*
Y918670D03*
X485778Y925079D03*
X493179Y854584D03*
X495029Y864197D03*
X491329D03*
X498729D03*
X485779Y854584D03*
X498729Y896240D03*
X472829Y889832D03*
X470979Y893036D03*
X487629Y915466D03*
X485778Y912262D03*
X491329Y902649D03*
X487629D03*
X489478Y912262D03*
Y905853D03*
X485778D03*
X487629Y909057D03*
Y921875D03*
Y928283D03*
X491329Y896240D03*
X478379Y918670D03*
X478380Y912262D03*
X470979Y880219D03*
Y873810D03*
X472829Y877014D03*
X472828Y870606D03*
X483929Y877014D03*
X478379Y880219D03*
X476529Y877014D03*
X474678Y918670D03*
X476528Y921875D03*
X480229D03*
Y877014D03*
X482078Y918670D03*
X483929Y928283D03*
X478378Y925079D03*
X474678Y893036D03*
X482078Y899445D03*
Y925079D03*
X465429Y909057D03*
X469129Y915466D03*
X456178Y912262D03*
X469129Y902649D03*
X454329Y909057D03*
X465429Y915466D03*
X454329Y902649D03*
X489479Y893036D03*
X493178Y899445D03*
X496878Y893036D03*
X470978Y918670D03*
X435830Y928283D03*
X483928Y921875D03*
X467278Y893036D03*
X461729Y896240D03*
X454329Y921875D03*
X467278Y918670D03*
X456178D03*
X461729Y909057D03*
Y915466D03*
X459878Y905853D03*
X458029Y909057D03*
X446929Y877014D03*
X443229D03*
X441379Y880219D03*
X448779Y893036D03*
X482078D03*
X483929Y896240D03*
X437679Y925079D03*
X439530Y928283D03*
X445079Y925079D03*
X448780D03*
X450630Y928283D03*
X445078Y873810D03*
X452479D03*
X450629Y877014D03*
X463578Y912262D03*
X456179Y893036D03*
X485778D03*
X495029Y877014D03*
X474678Y912262D03*
X480229Y902649D03*
X441378Y899445D03*
X500579Y854584D03*
Y867401D03*
X485779Y880219D03*
X493179Y867401D03*
X470978Y899445D03*
X485779Y867401D03*
X469129Y909057D03*
X470980Y912262D03*
X454329Y864197D03*
X461729D03*
X459878Y912262D03*
X498729Y877014D03*
X463578Y905853D03*
X459878Y918670D03*
X461729Y921875D03*
X458029Y915466D03*
X452479Y905853D03*
X448780Y912262D03*
X450629Y864197D03*
X443229Y909057D03*
X487629Y864197D03*
X448779Y854584D03*
X441380Y912262D03*
X458029Y896240D03*
X446930Y928283D03*
X446929Y921875D03*
X476529Y915466D03*
X456178Y899445D03*
X483929Y909057D03*
X472829Y921875D03*
X463578Y899445D03*
X465429Y896240D03*
X469129Y889832D03*
Y896240D03*
X459878Y893036D03*
X465429Y889832D03*
X454329D03*
X463579Y893036D03*
X470978Y905853D03*
X456178D03*
X458029Y902649D03*
X476529Y896240D03*
X500579Y893036D03*
X465429Y921875D03*
X458029D03*
X491329Y889832D03*
X495029D03*
X487629D03*
X476529Y902649D03*
X478378Y905853D03*
X495029Y896240D03*
X498729Y889832D03*
X487629Y877014D03*
X474678Y905853D03*
X446929Y896240D03*
X485778Y899445D03*
X472828Y915466D03*
X465429Y902649D03*
X463579Y880219D03*
X469129Y877014D03*
X456179Y880219D03*
X493178Y893036D03*
X441378Y918670D03*
X500579Y880219D03*
X467278Y912262D03*
X487629Y896240D03*
X489478Y899445D03*
X493179Y880219D03*
X450629Y889832D03*
X461729Y902649D03*
Y889832D03*
X491329Y877014D03*
X483929Y915466D03*
X441379Y893036D03*
X472829Y896240D03*
X480229Y889832D03*
X515379Y854584D03*
X446929Y889832D03*
X480228Y896240D03*
X478378Y899445D03*
X454329Y896240D03*
X467278Y905853D03*
X454329Y877014D03*
X450629Y915466D03*
X445078Y893036D03*
X443230Y928283D03*
X461729Y877014D03*
X452479Y860993D03*
X441379Y925079D03*
X443229Y921875D03*
X452478Y918670D03*
X454329Y915466D03*
X465429Y877014D03*
X445078Y918670D03*
X445080Y912262D03*
X445078Y860993D03*
X441379Y867401D03*
X448779Y918670D03*
X452478Y912262D03*
X504278Y860993D03*
X482079Y912262D03*
X478379Y867401D03*
X524629Y877014D03*
X520929D03*
X522779Y867401D03*
X519078Y873810D03*
X526479D03*
X524629Y864197D03*
X522779Y880219D03*
X526479Y860993D03*
X519078D03*
Y886627D03*
X520929Y864197D03*
X507979Y854584D03*
X504278Y886627D03*
X517229Y864197D03*
X506129Y889832D03*
Y877014D03*
X517229D03*
X507979Y880219D03*
X502429Y889832D03*
X509829Y864197D03*
X515379Y880219D03*
X509829Y877014D03*
X506129Y864197D03*
X515379Y867401D03*
X511678Y860993D03*
Y886627D03*
Y873810D03*
X502429Y864197D03*
X504278Y873810D03*
X513529Y877014D03*
X507979Y867401D03*
X502429Y877014D03*
X513529Y864197D03*
X480229Y973143D03*
X483929D03*
X480662Y999684D03*
Y1025318D03*
X482511Y1022114D03*
X480229Y966735D03*
X480228Y960326D03*
X482078Y957122D03*
X482079Y950713D03*
X483928Y960326D03*
X483929Y953917D03*
X480229Y979552D03*
X484362Y1025318D03*
X476285Y1017526D03*
X482079Y969939D03*
X482078Y976347D03*
Y963529D03*
X483929Y966735D03*
X482078Y982756D03*
X478379Y969939D03*
X484362Y1044544D03*
X467711Y1047750D03*
X475111Y1060565D03*
X484362Y1050952D03*
X482511Y1060565D03*
X484361Y1057361D03*
X471411Y1054157D03*
X480662Y1050952D03*
X484362Y1063770D03*
X473262Y1044544D03*
X480662D03*
X478811Y1041340D03*
X480662Y1038136D03*
X478811Y1034931D03*
X469562Y1044544D03*
X475111Y1047749D03*
X471411Y1041340D03*
X482511Y1047749D03*
X471411D03*
X484361Y1038136D03*
X482512Y1034931D03*
X482511Y1041340D03*
X475111D03*
X484361Y1031727D03*
X486211Y1041340D03*
X488062Y1038136D03*
Y1063770D03*
Y1031727D03*
Y1044544D03*
X486211Y1047749D03*
X489911D03*
X486211Y1034931D03*
X489911D03*
Y1041340D03*
X488062Y1050952D03*
X486211Y1060565D03*
X489911Y1054157D03*
Y1060565D03*
X486211Y1054157D03*
X488062Y1057361D03*
X1314184Y849978D03*
X1313920Y854584D03*
X1312266Y857972D03*
X1319469Y851380D03*
X1317620Y854584D03*
X1315770Y857789D03*
X1323171Y864197D03*
X1321321Y860993D03*
X1319469Y857789D03*
X1328721Y867401D03*
X1325021D03*
X1321320Y854584D03*
X1323171Y870606D03*
X1321321Y873810D03*
X1325020D03*
X1343521Y867401D03*
X1336121D03*
X1339820Y873810D03*
X1332420D03*
X1347220D03*
X1350921Y867401D03*
X1358321Y880219D03*
X1356471Y877014D03*
X1352771D03*
X1350921Y880219D03*
X1349071Y877014D03*
X1354620Y873810D03*
X1362020Y886627D03*
X1365721Y880219D03*
X1369420Y899445D03*
X1371271Y896240D03*
Y889832D03*
X1367571D03*
X1373120Y899445D03*
X1376820D03*
X1369421Y893036D03*
X1373121D03*
X1374971Y896240D03*
X1369420Y886627D03*
X1373120Y905853D03*
X1371271Y909057D03*
Y902649D03*
X1369420Y905853D03*
Y912262D03*
X1374971Y909057D03*
X1374970Y902649D03*
X1373121Y912262D03*
X1371271Y915466D03*
X1376820Y905853D03*
X1378671Y915466D03*
Y909057D03*
X1376820Y912262D03*
X1378671Y902649D03*
X1373120Y925079D03*
X1371271Y921875D03*
Y928283D03*
X1369420Y925079D03*
Y918670D03*
X1378671Y928283D03*
X1376820Y925079D03*
X1374971Y928283D03*
X1374970Y921875D03*
X1373120Y918670D03*
X1378671Y921875D03*
X1380520Y912262D03*
Y905853D03*
X1386071Y909057D03*
Y915466D03*
X1382371Y909057D03*
Y915466D03*
X1384220Y918670D03*
Y912262D03*
X1380520Y918670D03*
X1386071Y921875D03*
X1382371D03*
X1442003Y1089403D03*
X1430902Y1082995D03*
X1427202D03*
X1434603Y1095812D03*
X1438303D03*
X1442003D03*
X1434603Y1089403D03*
X1436454Y1086199D03*
X1432754Y1092607D03*
X1430903Y1095812D03*
X1390234Y942097D03*
X1393904Y1044544D03*
X1384653Y1041340D03*
X1388353Y1047749D03*
Y1041340D03*
X1392053D03*
X1395753D03*
Y1047749D03*
X1392053D03*
X1386504Y1044544D03*
X1384653Y1047749D03*
X1390204Y1044544D03*
X1393904Y1050952D03*
X1392053Y1060565D03*
Y1054157D03*
X1388353Y1060565D03*
X1386504Y1050952D03*
X1384653Y1054157D03*
X1386504Y1057361D03*
X1390204Y1050952D03*
X1393904Y1057361D03*
X1395753Y1054157D03*
X1384653Y1060565D03*
X1386504Y1063770D03*
X1388353Y1054157D03*
X1390204Y1057361D03*
X1393904Y1063770D03*
X1390204D03*
X1395753Y1060565D03*
X1384653Y1073383D03*
X1395753D03*
X1392053Y1066974D03*
X1386504Y1070178D03*
X1384653Y1066974D03*
X1388353Y1073383D03*
X1392053D03*
X1390204Y1070178D03*
X1393904D03*
X1388353Y1066974D03*
X1395753D03*
X1410121Y944304D03*
Y957122D03*
Y950713D03*
Y963530D03*
Y976347D03*
Y969939D03*
Y982756D03*
X1410553Y1009297D03*
Y1002888D03*
Y1028523D03*
Y1022114D03*
Y1015705D03*
X1405004Y1044544D03*
X1410553Y1034931D03*
X1406854Y1047749D03*
X1399453D03*
X1403153D03*
X1403154Y1041340D03*
X1399454D03*
X1401304Y1044544D03*
X1397604D03*
X1403153Y1054157D03*
X1406853D03*
X1408703Y1050952D03*
X1401304Y1057361D03*
X1410553Y1060565D03*
Y1054157D03*
X1397604Y1063770D03*
X1405003Y1057361D03*
X1408703D03*
Y1063770D03*
X1397604Y1057361D03*
X1401304Y1050952D03*
X1399453Y1054157D03*
X1405004Y1050952D03*
X1397604D03*
X1401304Y1063770D03*
X1399453Y1060565D03*
X1403153D03*
X1405003Y1063770D03*
X1406853Y1060565D03*
X1403153Y1066974D03*
X1399453D03*
X1410553Y1073383D03*
Y1066974D03*
X1408702Y1070178D03*
X1399453Y1073383D03*
X1397604Y1070178D03*
X1401304D03*
X1405004D03*
X1406853Y1066974D03*
X1410553Y1124651D03*
X1410554Y1137769D03*
X1410553Y1131060D03*
X1423070Y941100D03*
X1423071Y947509D03*
Y960326D03*
Y953917D03*
Y966735D03*
Y979552D03*
Y973143D03*
X1423503Y1006093D03*
Y999684D03*
Y1012501D03*
Y1025318D03*
Y1018910D03*
Y1031727D03*
X1429053Y1041340D03*
X1427203Y1044544D03*
X1423503Y1038136D03*
X1425353Y1047749D03*
X1429053D03*
Y1060565D03*
X1423503Y1057361D03*
Y1050952D03*
Y1063770D03*
X1425353Y1054157D03*
X1425355Y1060565D03*
X1427203Y1063770D03*
X1429053Y1054157D03*
X1427203Y1050952D03*
X1427204Y1057361D03*
X1425353Y1073383D03*
X1423503Y1076587D03*
Y1070178D03*
X1429053Y1079791D03*
X1425353D03*
X1429053Y1073383D03*
X1427203Y1076587D03*
X1429053Y1066974D03*
X1425353D03*
X1427204Y1070178D03*
X1429053Y1092608D03*
X1427204Y1089404D03*
X1425354Y1086200D03*
X1423503Y1082995D03*
X1427203Y1095812D03*
X1429053Y1086200D03*
Y1099017D03*
X1423503Y1108630D03*
Y1102221D03*
Y1121447D03*
Y1115039D03*
Y1127856D03*
Y1134264D03*
X1432753Y1073383D03*
X1430903Y1076587D03*
X1430904Y1070178D03*
X1432754Y1079791D03*
X1434604Y1076587D03*
X1434603Y1082995D03*
X1432753Y1086200D03*
X1436453Y1092608D03*
X1440153Y1086200D03*
X1438304Y1082995D03*
X1436454Y1105426D03*
X1434604Y1102221D03*
X1432753Y1099017D03*
X1442003Y1108630D03*
Y1102221D03*
X1440154Y1105426D03*
Y1099017D03*
X1438304Y1108630D03*
X1440154Y1111834D03*
X1438304Y1102221D03*
X1434604Y1121447D03*
Y1115039D03*
X1442004Y1121447D03*
Y1115039D03*
X1434604Y1127856D03*
Y1134264D03*
X1445703Y1140973D03*
X1453103D03*
X1447554Y1137469D03*
X1460503Y1140973D03*
X1475303D03*
X1467903D03*
X1490103D03*
X1482703D03*
X1497503D03*
X1430903Y1089403D03*
X1436454Y1099016D03*
X1438303Y1089403D03*
X1440154Y1092607D03*
X1343521Y854584D03*
X1336121D03*
X1360171Y864197D03*
X1358321Y854584D03*
X1350921D03*
X1363871Y864197D03*
X1371271D03*
X1367571D03*
X1365721Y854584D03*
X1373121Y867401D03*
X1365721D03*
X1378671Y877014D03*
X1374971D03*
X1376820Y873810D03*
X1380521Y880219D03*
Y854584D03*
X1395321D03*
X1393471Y864197D03*
X1389771D03*
X1387921Y854584D03*
X1386071Y864197D03*
X1382371D03*
X1387921Y867401D03*
X1386071Y870606D03*
X1374971Y947509D03*
X1376820Y957122D03*
X1374970Y960326D03*
X1373120Y957122D03*
X1373121Y950713D03*
X1376820Y963530D03*
X1378671Y960326D03*
X1375404Y1012501D03*
Y1006093D03*
X1379104Y999684D03*
X1377253Y1009297D03*
X1379104Y1012501D03*
X1375403Y1018910D03*
X1377253Y1015705D03*
X1381128Y1022427D03*
X1395320Y912262D03*
X1395321Y905853D03*
X1393471Y909057D03*
X1399020Y905853D03*
X1391620D03*
Y912262D03*
X1393471Y915466D03*
X1391621Y918670D03*
X1395187Y926265D03*
X1395320Y918670D03*
X1393471Y921875D03*
X1391550Y925219D03*
X1399020Y912262D03*
X1400871Y915466D03*
X1402720Y912262D03*
X1404571Y909057D03*
Y915466D03*
X1406420Y912262D03*
X1408271Y915466D03*
X1397171Y909057D03*
X1411971D03*
Y915466D03*
X1408270Y909057D03*
X1410120Y905853D03*
X1400870Y909057D03*
X1406420Y905853D03*
X1402720D03*
X1397171Y915466D03*
X1410121Y912262D03*
X1406420Y918670D03*
X1410121Y931488D03*
Y925079D03*
X1404571Y921875D03*
X1408271D03*
X1410121Y918670D03*
X1411971Y921875D03*
X1400871D03*
X1399020Y918670D03*
X1397171Y921875D03*
X1402720Y918670D03*
X1411971Y934691D03*
X1406420Y925079D03*
X1408271Y928283D03*
X1406420Y931488D03*
X1411971Y928283D03*
X1408271Y934691D03*
X1413820Y912262D03*
X1413821Y905853D03*
X1423071Y909057D03*
Y915466D03*
X1419371Y909057D03*
X1415671Y915466D03*
X1421221Y905853D03*
X1417521D03*
X1430471Y909057D03*
X1426772D03*
X1428621Y905853D03*
X1424921D03*
X1424922Y912262D03*
X1417522D03*
X1415671Y909057D03*
X1421222Y912262D03*
X1419371Y915466D03*
X1426771D03*
X1428620Y912262D03*
X1424921Y918670D03*
X1430471Y915466D03*
X1415671Y921875D03*
X1417520Y931488D03*
Y925079D03*
X1423071Y928283D03*
X1413820Y918670D03*
X1423071Y921875D03*
X1417520Y918670D03*
X1426771Y921875D03*
X1421220Y918670D03*
X1419371Y921875D03*
X1428620Y918670D03*
X1424921Y931488D03*
X1419371Y928283D03*
X1413820Y931488D03*
X1424921Y925079D03*
X1419371Y934691D03*
X1421220Y931488D03*
Y925079D03*
X1415671Y928283D03*
X1413820Y925079D03*
X1426771Y928283D03*
X1423071Y934691D03*
X1415671D03*
X1432320Y912262D03*
X1441571Y915466D03*
X1437871D03*
X1443420Y912262D03*
X1445271Y915466D03*
X1434171D03*
X1436020Y918670D03*
X1439720Y912262D03*
X1436020D03*
X1437871Y921875D03*
X1432320Y918670D03*
X1430471Y921875D03*
X1443420Y918670D03*
X1445271Y921875D03*
X1439720Y918670D03*
X1441571Y921875D03*
X1434171D03*
X1460071Y896240D03*
X1458220Y899445D03*
X1460071Y915466D03*
X1456371Y902649D03*
X1460071Y909057D03*
X1458221Y912262D03*
X1450820D03*
X1460070Y902649D03*
X1456371Y915466D03*
X1447122Y912262D03*
X1454521Y918670D03*
X1452671Y915466D03*
X1454522Y912262D03*
X1456370Y909057D03*
X1458220Y905853D03*
X1448970Y915466D03*
X1454520Y905853D03*
X1452671Y909057D03*
X1456371Y928283D03*
X1454520Y925079D03*
X1458220D03*
X1460071Y928283D03*
X1458220Y918670D03*
X1456371Y921875D03*
X1460070D03*
X1452670D03*
X1450820Y918670D03*
X1458220Y931488D03*
X1448971Y921875D03*
X1447120Y918670D03*
X1460071Y934691D03*
X1452426Y934725D03*
X1456371Y934691D03*
X1474871Y864197D03*
X1476721Y854584D03*
Y867401D03*
X1471171Y877014D03*
X1476721Y880219D03*
X1474871Y877014D03*
X1469321Y880219D03*
X1467471Y877014D03*
X1473020Y873810D03*
X1471171Y896240D03*
X1473020Y893036D03*
X1463771Y896240D03*
X1467471D03*
X1461920Y893036D03*
X1469320D03*
Y899445D03*
X1461920D03*
X1474871Y889832D03*
X1465621Y893036D03*
X1476721D03*
X1474871Y896240D03*
X1471171Y889832D03*
X1467471D03*
X1463771D03*
X1465620Y899445D03*
X1473020Y886627D03*
X1465620D03*
X1467471Y915466D03*
X1463771D03*
X1467471Y909057D03*
X1469320Y912262D03*
X1463771Y909057D03*
X1467471Y902649D03*
X1463771D03*
X1461920Y912262D03*
Y905853D03*
X1465620Y912262D03*
Y905853D03*
X1469321D03*
X1463771Y921875D03*
Y928283D03*
X1469320Y931488D03*
X1467471Y928283D03*
Y921875D03*
X1469320Y918670D03*
X1461920Y931488D03*
Y918670D03*
Y925079D03*
X1469321D03*
X1465620D03*
Y918670D03*
Y931488D03*
X1467471Y934691D03*
X1463771D03*
X1491521Y841467D03*
X1484121D03*
X1478571Y851380D03*
X1482271D03*
X1489671D03*
X1485971D03*
X1493371D03*
X1487820Y848176D03*
X1480420D03*
X1478571Y864197D03*
X1491521Y854584D03*
X1489671Y864197D03*
X1485971D03*
X1482271D03*
X1493371D03*
X1491521Y867401D03*
X1484121D03*
X1487820Y860993D03*
X1480420D03*
X1478571Y877014D03*
X1491521Y880219D03*
X1485971Y877014D03*
X1484121Y880219D03*
X1489671Y877014D03*
X1482271D03*
X1493371D03*
X1487820Y873810D03*
X1480420D03*
X1478571Y889832D03*
X1482271D03*
X1489671D03*
X1485971D03*
X1493371D03*
X1480420Y886627D03*
X1487820D03*
X1504471Y844671D03*
X1498921Y841467D03*
X1504471Y851380D03*
X1500771D03*
X1497071D03*
X1495220Y848176D03*
X1504471Y864197D03*
X1500771D03*
X1497071D03*
X1506321Y854584D03*
X1498921D03*
Y867401D03*
X1495220Y860993D03*
X1502621D03*
X1498921Y880219D03*
X1497071Y877014D03*
X1500771D03*
X1495220Y873810D03*
X1502621D03*
X1500771Y889832D03*
X1497071D03*
X1495220Y886627D03*
X1502621D03*
X1511871Y844671D03*
X1484121Y854584D03*
X1458221Y944304D03*
X1458220Y957122D03*
X1458221Y950713D03*
X1456371Y966735D03*
X1458220Y963529D03*
X1456370Y960326D03*
X1458221Y969939D03*
X1458220Y976347D03*
X1456371Y979552D03*
Y973143D03*
X1456804Y999684D03*
X1460504Y1025318D03*
X1452426Y1017525D03*
X1458653Y1028523D03*
Y1022114D03*
X1460503Y1018910D03*
X1456804Y1025318D03*
X1458653Y1015705D03*
X1462353Y1022114D03*
X1458220Y982756D03*
X1454521Y969939D03*
X1443541Y1036914D03*
X1442003Y1044544D03*
X1443853Y1041340D03*
X1445704Y1044544D03*
X1443853Y1047750D03*
X1442004Y1057361D03*
X1442002Y1050952D03*
X1460504Y1044544D03*
X1458653Y1041340D03*
X1458654Y1034931D03*
X1451253Y1041340D03*
X1460503Y1038136D03*
X1458653Y1047749D03*
X1447553D03*
Y1041340D03*
X1451253Y1047749D03*
X1454953Y1034931D03*
X1456804Y1038136D03*
X1454953Y1041340D03*
X1456804Y1044544D03*
X1449404D03*
X1460504Y1063770D03*
X1460503Y1057361D03*
X1458653Y1060565D03*
X1456804Y1050952D03*
X1451253Y1060565D03*
X1447553Y1054157D03*
X1460504Y1050952D03*
G54D38*
X174393Y678354D03*
X174685Y647210D03*
X159474Y1320753D03*
X195316Y1430034D03*
X183847Y1320778D03*
X208247D03*
X270252Y700414D03*
X275289Y631889D03*
Y607735D03*
Y583576D03*
Y656043D03*
X461019Y1242785D03*
X436619D03*
X387897D03*
X412297D03*
X485419D03*
X458600Y1379662D03*
X673093Y1320778D03*
X472700Y1353962D03*
X721866Y1320803D03*
X383224Y1354446D03*
X412990D03*
X708795Y1429579D03*
X526478Y1449795D03*
X443326Y1354446D03*
X697466Y1320803D03*
X1419467Y1353946D03*
X1359365D03*
X1389131D03*
X1449233D03*
X1168627Y1466363D03*
X1683032Y1354399D03*
X1502956Y1449373D03*
X1634259Y1354374D03*
X1658632Y1354399D03*
X1670101Y1463655D03*
X1434200Y1379362D03*
X1388438Y1242785D03*
X1364038D03*
X1437160D03*
X1461560D03*
X1412760D03*
X1577000Y599762D03*
Y624262D03*
Y648762D03*
Y722162D03*
Y673162D03*
Y697662D03*
X1682882Y628017D03*
Y678952D03*
X1826405Y269763D03*
X1769790Y204632D03*
X1826405Y299056D03*
X1799350Y204632D03*
G54D47*
X1422371Y1407722D03*
G54D43*
X549236Y1441207D03*
X569236D03*
G54D42*
X479646Y1421784D03*
X1455787D03*
X1710550Y691327D03*
G54D40*
X159474Y1328627D03*
X183847Y1328652D03*
X278126Y700414D03*
X275289Y599861D03*
Y624015D03*
Y575702D03*
Y648169D03*
X468893Y1242785D03*
X444493D03*
X493293D03*
X395771D03*
X420171D03*
X673093Y1328652D03*
X697466Y1328677D03*
X1634259Y1362248D03*
X1683032Y1362273D03*
X1179900Y1364962D03*
X1658632Y1362273D03*
X1155500Y1364962D03*
X1371912Y1242785D03*
X1469434D03*
X1396312D03*
X1445034D03*
X1420634D03*
X1577000Y591888D03*
Y640888D03*
Y665288D03*
Y714288D03*
Y689788D03*
G54D35*
X116567Y766775D03*
X43841Y766798D03*
X52541D03*
X57299D03*
X73541D03*
X82241D03*
X86999D03*
X103241D03*
X111941D03*
X251741D03*
X260441D03*
X57399Y770144D03*
X66099D03*
X82241D03*
X87099D03*
X95799D03*
X43841Y773491D03*
X52541D03*
X66099D03*
X73541D03*
X82241D03*
X103241D03*
X36399Y776837D03*
X57399D03*
X66099D03*
X82241D03*
X87099D03*
X95799D03*
X43841Y780184D03*
X52541D03*
X66099D03*
X73541D03*
X82241D03*
X103241D03*
X677980Y1262074D03*
X661400Y1263522D03*
X680046Y1264964D03*
X664630Y1259442D03*
X647690Y1260812D03*
X709977Y1264985D03*
X723700Y1258727D03*
X726141Y1262074D03*
X726107Y1265420D03*
X737580Y1262074D03*
X739697Y1265420D03*
X755797D03*
X769399Y766798D03*
X767080Y1262074D03*
X769399Y1265420D03*
X794241Y766798D03*
X783130Y1259372D03*
X796880Y1262074D03*
X785541Y1265420D03*
Y1262074D03*
X797417Y767345D03*
X812440Y1258727D03*
X799099Y1265420D03*
X823941Y766798D03*
X826750Y1262074D03*
X815241Y1265420D03*
Y1262074D03*
X828699Y766798D03*
X828799Y1265420D03*
X853641Y766798D03*
Y1245341D03*
X844941Y1252034D03*
Y1265420D03*
Y1262074D03*
X1002070Y1256942D03*
X1003841Y1265420D03*
Y1262074D03*
X1012543Y1257198D03*
X1019983Y1255381D03*
Y1262074D03*
Y1265420D03*
X1030830Y1261302D03*
X1030270Y1256042D03*
X1042331Y1257488D03*
X1049683Y1262074D03*
X1061330D03*
X1071991Y1257262D03*
X1079383Y1262074D03*
X1074480Y1263742D03*
X1091000Y1262074D03*
X1103530Y1263602D03*
X1044930Y1263492D03*
X1329062Y164849D03*
X1297012Y157449D03*
X1300774Y155288D03*
X1309832Y161149D03*
X1303417D03*
X1309832Y168549D03*
Y157449D03*
X1306626Y162999D03*
Y159299D03*
X1313037Y162999D03*
X1309832Y164849D03*
X1313037Y159299D03*
X1303417Y157449D03*
X1300217Y159299D03*
X1313033Y166699D03*
X1313037Y170399D03*
X1316242Y209249D03*
X1313033Y222199D03*
X1309100Y236477D03*
X1319452Y162999D03*
X1316242Y168549D03*
X1319442Y159299D03*
X1316241Y157449D03*
X1322652Y161149D03*
X1316242D03*
X1319452Y166699D03*
X1329062Y168549D03*
X1316242Y164849D03*
X1322652D03*
X1329062Y157449D03*
X1318502Y176574D03*
X1319442Y170399D03*
X1329062Y172249D03*
X1316237D03*
X1319442Y218499D03*
X1325852Y214799D03*
X1329062Y209249D03*
Y216649D03*
X1325852Y211099D03*
X1329062Y212949D03*
X1319442Y211099D03*
X1325857Y218499D03*
X1322652Y216649D03*
X1319442Y222199D03*
X1329061Y224049D03*
X1329062Y220349D03*
X1325856Y222199D03*
X1322652Y224049D03*
Y220349D03*
X1321986Y236726D03*
X1326377Y235784D03*
X1339727Y161149D03*
X1335472D03*
X1346137Y168549D03*
X1342907Y166699D03*
X1332268D03*
X1346137Y164849D03*
X1339727D03*
X1335472Y168549D03*
X1332268Y162999D03*
X1342903Y170399D03*
X1339727Y168549D03*
X1335472Y164849D03*
X1346140Y161149D03*
X1342937Y162999D03*
X1335472Y157449D03*
X1342937Y177799D03*
X1346137Y179649D03*
Y175949D03*
X1342937Y185199D03*
Y181499D03*
X1339727Y179649D03*
X1339568Y176028D03*
X1346137Y172249D03*
X1335472D03*
X1332268Y170399D03*
X1339727Y183349D03*
X1346137D03*
X1342937Y188899D03*
X1339727Y190749D03*
X1346137D03*
Y194449D03*
X1339727Y187049D03*
X1342937Y192599D03*
X1346137Y187049D03*
X1346147Y201849D03*
Y198149D03*
X1336527Y214799D03*
X1339727Y216649D03*
X1346147Y212949D03*
Y216649D03*
X1336527Y218499D03*
X1342937D03*
Y214799D03*
X1346147Y209248D03*
X1332262Y218499D03*
Y214799D03*
Y211099D03*
Y207399D03*
X1339727Y209249D03*
Y220349D03*
X1336527Y222199D03*
X1346147Y220349D03*
X1332285Y226210D03*
X1342937Y222199D03*
X1332267D03*
X1352557Y168548D03*
X1349351Y166698D03*
X1352557Y164848D03*
X1349344Y162999D03*
X1349351Y181498D03*
X1352557Y175948D03*
Y183348D03*
X1355761Y181498D03*
X1349351Y185198D03*
X1355761D03*
X1349351Y177798D03*
Y174098D03*
Y170398D03*
X1352557Y172248D03*
Y179648D03*
X1355765Y199999D03*
X1355771Y196298D03*
X1352561Y198148D03*
X1349351Y196298D03*
X1352561Y194448D03*
X1352551Y190748D03*
X1349345Y188898D03*
X1355761Y192598D03*
X1349351D03*
X1352551Y187048D03*
X1349361Y199998D03*
X1352561Y201848D03*
X1349351Y218498D03*
X1352560Y205549D03*
X1349351Y214798D03*
Y211098D03*
Y222198D03*
X1326918Y161161D03*
X1236583Y773491D03*
G54D45*
X1288258Y145501D03*
X1283781Y149115D03*
X1297605Y145824D03*
X1283781Y155788D03*
X1323958Y146227D03*
X1333811Y235348D03*
X1349704Y145385D03*
G54D39*
X174393Y668511D03*
X174685Y637367D03*
X205159Y1430034D03*
X468443Y1379662D03*
X482543Y1353962D03*
X453169Y1354446D03*
X526478Y1439952D03*
X422833Y1354446D03*
X718638Y1429579D03*
X393067Y1354446D03*
X1459076Y1353946D03*
X1398974D03*
X1679944Y1463655D03*
X1429310Y1353946D03*
X1369208D03*
X1178470Y1466363D03*
X1502956Y1439530D03*
X1444043Y1379362D03*
X1682882Y669109D03*
X1769790Y194789D03*
X1836248Y299056D03*
Y269763D03*
X1799350Y194789D03*
G54D48*
X1414599Y1402169D03*
G54D44*
X1066280Y1704890D03*
G54D41*
X525275Y1171319D03*
X1501417D03*
G54D50*
X1739744Y605413D03*
%LPD*%
G75*
G36*
G01X123948Y532096D02*
X125372D01*
X127677Y529792D01*
X133120D01*
X133429Y529483D01*
Y528821D01*
Y527900D01*
X132928Y527399D01*
Y520107D01*
X131339Y518516D01*
X119047D01*
X117600Y517069D01*
Y497649D01*
X116413Y496462D01*
X113785D01*
G02X113421Y497027I0J400D01*
G03X113691Y498271I-2731J1244D01*
G03X110689Y501273I-3002J0D01*
G03X108355Y500159I0J-3002D01*
G02X107761Y500128I-311J251D01*
G01X105220Y502669D01*
Y504125D01*
G03X104782Y505142I-1401J-1D01*
G01X104720Y505201D01*
Y505547D01*
X104782Y505606D01*
G03X105220Y506623I-963J1018D01*
G01Y520302D01*
X105129Y520527D01*
X105126Y520533D01*
G02X105087Y520727I461J194D01*
G02X105126Y520921I500J0D01*
G01X105129Y520927D01*
X105220Y521152D01*
Y523155D01*
X106927Y524862D01*
X122927D01*
X123688Y525623D01*
Y531836D01*
X123948Y532096D01*
G37*
G36*
G01X115289Y662702D02*
X126313D01*
G02X126708Y662242I0J-400D01*
G03X126691Y662015I1485J-225D01*
G03X127021Y661076I1501J0D01*
G02X126925Y660489I-312J-250D01*
G03X126236Y659226I813J-1263D01*
G03X127738Y657724I1502J0D01*
G03X129240Y659203I0J1502D01*
G02X129923Y659479I400J-6D01*
G01X132500Y656902D01*
Y650226D01*
G02X132041Y649830I-400J0D01*
G03X131925Y649845I-443J-2969D01*
G02X131569Y650237I44J398D01*
G03X130067Y651715I-1502J-24D01*
G03X128816Y651044I0J-1502D01*
G02X128237Y650950I-333J221D01*
G03X127313Y651267I-923J-1185D01*
G03X126109Y650663I0J-1502D01*
G02X125503Y650622I-321J239D01*
G03X124431Y651072I-1072J-1052D01*
G03X124184Y651052I-3J-1502D01*
G02X123732Y651549I-66J394D01*
G03X123782Y651934I-1452J384D01*
G03X123347Y652992I-1502J1D01*
G02X123357Y653565I284J282D01*
G03X123831Y654660I-1028J1095D01*
G03X120827I-1502J0D01*
G03X121262Y653602I1502J-1D01*
G02X121252Y653029I-284J-282D01*
G03X120778Y651934I1028J-1095D01*
G03X122280Y650432I1502J0D01*
G03X122527Y650452I3J1502D01*
G02X122979Y649955I66J-394D01*
G03X122929Y649570I1452J-384D01*
G03X124431Y648068I1502J0D01*
G03X125635Y648672I0J1502D01*
G02X126241Y648713I321J-239D01*
G03X127313Y648263I1072J1052D01*
G03X128564Y648934I0J1502D01*
G02X129143Y649028I333J-221D01*
G03X129192Y648993I897J1204D01*
G02X129233Y648707I-117J-163D01*
G03X128598Y646861I2366J-1846D01*
G03X131600Y643859I3002J0D01*
G03X132041Y643892I-3J3002D01*
G02X132500Y643496I59J-396D01*
G01Y637373D01*
G03X131748Y636992I967J-2842D01*
G02X131211Y637064I-229J328D01*
G03X130057Y637605I-1154J-960D01*
G03X128555Y636103I0J-1502D01*
G03X128607Y635711I1502J0D01*
G01X128637Y635599D01*
X126660Y633622D01*
X122420D01*
X120300Y635742D01*
X116710D01*
X116497Y635955D01*
X116455Y635997D01*
X116442Y636053D01*
G03X115782Y637363I-2930J-655D01*
G03X115053Y637974I-2269J-1967D01*
G01X115009Y638001D01*
X114910Y638172D01*
Y640492D01*
X115159Y640742D01*
X116530Y642113D01*
Y655701D01*
X115159Y657072D01*
X114910Y657322D01*
Y662322D01*
X115289Y662702D01*
G37*
G36*
G01X418874Y1403989D02*
X436074D01*
X436274Y1404189D01*
Y1421389D01*
X436074Y1421589D01*
X420247D01*
X418674Y1420016D01*
Y1404189D01*
X418874Y1403989D01*
G37*
G36*
G01X1652020Y558962D02*
X1675800D01*
X1676150Y558610D01*
X1676151Y558611D01*
X1677240Y557522D01*
Y546252D01*
X1675960Y544972D01*
X1668720D01*
X1668190Y544442D01*
Y520462D01*
X1659336D01*
G03X1656174I-1581J-2552D01*
G01X1653401D01*
X1653388Y520648D01*
G03X1652181Y522013I-1498J-108D01*
G01X1652020Y522045D01*
Y522371D01*
G02X1652210Y522571I200J0D01*
G03X1653640Y524071I-72J1500D01*
G03X1652906Y525362I-1502J0D01*
G02X1652901Y526046I205J344D01*
G03X1653615Y527325I-789J1279D01*
G03X1652937Y528581I-1502J0D01*
G02X1653003Y529285I219J335D01*
G03X1654853Y532057I-1152J2772D01*
G03X1653322Y534674I-3002J0D01*
G02X1653184Y535243I196J349D01*
G03X1653433Y536071I-1252J828D01*
G03X1652186Y537551I-1502J0D01*
G01X1652020Y537580D01*
Y538562D01*
X1652186Y538591D01*
G03Y541551I-255J1480D01*
G01X1652020Y541580D01*
Y542707D01*
X1652151Y542755D01*
G03Y548389I-1040J2817D01*
G01X1652020Y548437D01*
Y558962D01*
G37*
G36*
G01X1668904Y529765D02*
X1683104D01*
X1683304Y529965D01*
Y544165D01*
X1683104Y544365D01*
X1668904D01*
X1668704Y544165D01*
Y529965D01*
X1668904Y529765D01*
G37*
G36*
G01X1697917Y507960D02*
X1698485D01*
X1700303Y506143D01*
G03X1700935Y505852I709J708D01*
G02X1701120Y505653I-15J-199D01*
G01Y504243D01*
X1700976Y504201D01*
G03X1698907Y502079I835J-2883D01*
G02X1698245Y501891I-387J102D01*
G03X1697210Y502304I-1035J-1090D01*
G03X1696116Y501831I0J-1502D01*
G02X1695452Y501962I-291J275D01*
G03X1694050Y502924I-1402J-541D01*
G03X1692986Y502482I0J-1502D01*
G02X1692372Y502540I-283J283D01*
G03X1691129Y503199I-1243J-843D01*
G03Y500195I0J-1502D01*
G03X1692193Y500637I0J1502D01*
G02X1692807Y500579I283J-283D01*
G03X1692958Y500391I1243J843D01*
G02X1692886Y499782I-291J-274D01*
G03X1692209Y498527I825J-1255D01*
G03X1695213I1502J0D01*
G03X1694803Y499558I-1501J0D01*
G02X1694875Y500167I291J274D01*
G03X1695144Y500393I-825J1255D01*
G02X1695808Y500262I291J-275D01*
G03X1697210Y499300I1402J541D01*
G03X1697375Y499309I1J1502D01*
G02X1697814Y498853I43J-397D01*
G03X1697798Y498632I1486J-219D01*
G03X1698635Y497285I1502J0D01*
G03X1698633Y497177I3000J-110D01*
G03X1699025Y495694I3001J0D01*
G01X1699100Y495562D01*
X1697319Y493781D01*
X1695498D01*
X1693564Y491847D01*
Y477162D01*
X1698225Y472501D01*
Y469254D01*
X1697433Y468462D01*
X1685002D01*
G02X1684664Y469076I0J400D01*
G03X1684896Y469878I-1270J802D01*
G03X1681892I-1502J0D01*
G03X1682124Y469076I1502J0D01*
G02X1681786Y468462I-338J-214D01*
G01X1675800D01*
Y490369D01*
G02X1676466Y490668I400J0D01*
G03X1677464Y490288I998J1122D01*
G03Y493292I0J1502D01*
G03X1676466Y492912I0J-1502D01*
G02X1675800Y493211I-266J299D01*
G01Y507960D01*
X1694323D01*
G02X1694701Y507429I0J-400D01*
G03X1694618Y506937I1419J-492D01*
G03X1697622I1502J0D01*
G03X1697539Y507429I-1502J0D01*
G02X1697917Y507960I378J131D01*
G37*
%LPC*%
G75*
G36*
G01X109697Y506666D02*
G02X109478Y507792I2783J1126D01*
G02X110999Y510403I3002J0D01*
G02X110981Y510637I1484J232D01*
G02X113985I1502J0D01*
G02X113966Y510400I-1502J1D01*
G02X115482Y507792I-1485J-2608D01*
G02X112480Y504790I-3002J0D01*
G02X111872Y504852I-1J3002D01*
G02X110464Y503872I-1408J521D01*
G02X108962Y505374I0J1502D01*
G02X109697Y506666I1503J0D01*
G37*
G36*
G01X1660964Y535899D02*
G03X1661046Y536453I-242J319D01*
G02X1660760Y537334I1216J882D01*
G02X1663764I1502J0D01*
G02X1663170Y536138I-1501J0D01*
G03X1663088Y535584I242J-319D01*
G02X1663374Y534703I-1216J-882D01*
G02X1662849Y533562I-1502J0D01*
G02X1663245Y532071I-2606J-1490D01*
G02X1660243Y535073I-3002J0D01*
G02X1660415Y535068I-1J-3002D01*
G02X1660964Y535899I1457J-366D01*
G37*
G36*
G01X1659668Y545843D02*
G02X1659364Y546749I1198J906D01*
G02X1662368I1502J0D01*
G02X1661500Y545387I-1503J0D01*
G03X1661442Y544695I169J-363D01*
G02X1662742Y542222I-1702J-2473D01*
G02X1656738I-3002J0D01*
G02X1659395Y545204I3002J0D01*
G03X1659668Y545843I-46J397D01*
G37*
G36*
G01X1664845Y554441D02*
G02X1663502Y553613I-1343J675D01*
G02Y556617I0J1502D01*
G02X1664845Y555789I0J-1503D01*
G03X1665559I357J179D01*
G02X1666902Y556617I1343J-675D01*
G02Y553613I0J-1502D01*
G02X1665559Y554441I0J1503D01*
G03X1664845I-357J-179D01*
G37*
G36*
G01X1688951Y480432D02*
G03X1689011Y480966I-264J300D01*
G02X1688727Y481845I1218J879D01*
G02X1691731I1502J0D01*
G02X1691221Y480717I-1502J0D01*
G03X1691161Y480183I264J-300D01*
G02X1691445Y479304I-1218J-879D01*
G02X1688441I-1502J0D01*
G02X1688951Y480432I1502J0D01*
G37*
G36*
G01X1683432Y484443D02*
G03X1682853Y484349I-246J-315D01*
G02X1681602Y483678I-1251J831D01*
G02Y486682I0J1502D01*
G02X1682526Y486365I1J-1502D01*
G03X1683105Y486459I246J315D01*
G02X1684356Y487130I1251J-831D01*
G02X1685539Y486554I0J-1503D01*
G03X1686145Y486526I315J246D01*
G02X1687238Y486998I1093J-1030D01*
G02Y483994I0J-1502D01*
G02X1686055Y484570I0J1503D01*
G03X1685449Y484598I-315J-246D01*
G02X1684356Y484126I-1093J1030D01*
G02X1683432Y484443I-1J1502D01*
G37*
G36*
G01X1683145Y475401D02*
G02X1682854Y476290I1211J889D01*
G02X1685858I1502J0D01*
G02X1684872Y474879I-1503J0D01*
G03X1684687Y474267I137J-375D01*
G02X1684978Y473378I-1211J-889D01*
G02X1681974I-1502J0D01*
G02X1682960Y474789I1503J0D01*
G03X1683145Y475401I-137J375D01*
G37*
G54D34*
X111087Y520052D03*
X110060Y515279D03*
X125890Y644163D03*
X121400Y638062D03*
X1668917Y549992D03*
X1681612Y499290D03*
X1691151Y493678D03*
X1685779Y491230D03*
%LPD*%
G75*
G54D10*
G01X321276Y599298D02*
Y597774D01*
X329099Y589951D01*
Y560560D01*
X277578Y509039D01*
G01X581755Y236978D02*
X564403D01*
X554187Y226762D01*
X491500D01*
X488600Y229662D01*
X434800D01*
X430322Y225184D01*
X383340D01*
X380197Y228327D01*
X375016D01*
X371551Y224862D01*
G01X390934Y1404085D02*
Y1407605D01*
G01X442265Y290939D02*
Y290080D01*
X447307Y285038D01*
X524312D01*
X527858Y281492D01*
X592514D01*
X601132Y290110D01*
X631273D01*
X638943Y297780D01*
Y311759D01*
X647521Y320337D01*
X661062D01*
X682946Y342221D01*
X747997D01*
X750052Y344276D01*
X803490D01*
X809730Y350516D01*
Y356114D01*
X831046Y377430D01*
X849800D01*
X857563Y369667D01*
X952568D01*
X956074Y373173D01*
X970598D01*
X974777Y368994D01*
X983228D01*
X996105Y356117D01*
X1030543D01*
X1032123Y357697D01*
X1038894D01*
X1045907Y350684D01*
X1204475D01*
G01X463207Y1547543D02*
Y1548329D01*
X468224Y1553346D01*
X469571D01*
X478577Y1562352D01*
X663450D01*
X665880Y1559922D01*
Y1558632D01*
X667900Y1556612D01*
Y1555150D01*
X674640Y1548410D01*
X681790D01*
X682160Y1548040D01*
G01X715891Y1426832D02*
X718638Y1429579D01*
G01D02*
X721385Y1432326D01*
G01X715891D02*
X718638Y1429579D01*
G01D02*
X721385Y1426832D01*
G01X1032894Y155185D02*
X1031649Y153940D01*
X1008199D01*
X1005176Y156963D01*
X1000809D01*
X999820Y157952D01*
X991261D01*
X986988Y162225D01*
X971821D01*
X967548Y157952D01*
X956130D01*
X949073Y165009D01*
X937373D01*
X935085Y167297D01*
X922866D01*
X906398Y150829D01*
X879949D01*
X867682Y138562D01*
X854200D01*
G01X1719727Y1472088D02*
X1698931Y1492884D01*
Y1542343D01*
X1693369Y1547905D01*
X1678740D01*
X1677047Y1546212D01*
X1671606D01*
X1668825Y1548993D01*
X1666287D01*
X1657944Y1557336D01*
X1454822D01*
X1452283Y1559875D01*
X1442731D01*
X1434259Y1551403D01*
X1395084D01*
X1387415Y1543734D01*
X1196142D01*
X1192757Y1540349D01*
X1186832D01*
X1183620Y1537137D01*
Y1523380D01*
X1172108Y1511868D01*
X1099761D01*
X1091541Y1520088D01*
X1066462D01*
G01X1117407Y1628495D02*
Y1633313D01*
X1112794Y1637926D01*
X1105494D01*
X1101590Y1641830D01*
X1088790D01*
G01D02*
Y1648665D01*
X1094225Y1654100D01*
Y1671710D01*
G01X1175723Y1463616D02*
X1178470Y1466363D01*
G01D02*
X1181217Y1469110D01*
G01X1175723D02*
X1178470Y1466363D01*
G01D02*
X1181217Y1463616D01*
G01X1276800Y276562D02*
X1272804Y280558D01*
X1258883D01*
G01X1322906Y109733D02*
Y106440D01*
X1329891Y99455D01*
G01X1460849Y343327D02*
X1457395Y346781D01*
X1452877D01*
X1450272Y344176D01*
X1436232D01*
G01X1554753Y628860D02*
X1564703Y618910D01*
Y580209D01*
X1545098Y560604D01*
Y433832D01*
X1497385Y386119D01*
X1479408D01*
X1476300Y383011D01*
Y360794D01*
X1464709Y349203D01*
Y345291D01*
X1462745Y343327D01*
X1460849D01*
G01X1456237Y726945D02*
X1455440D01*
X1452412Y729973D01*
Y734703D01*
X1453594Y735885D01*
X1457310D01*
X1457620Y736195D01*
G01X1576589Y300927D02*
X1579932Y304270D01*
Y306795D01*
X1574589Y312138D01*
X1567735D01*
X1528180Y272583D01*
X1498166D01*
X1493289Y277460D01*
Y280027D01*
G01X1617215Y1440822D02*
X1618883Y1439154D01*
Y1423725D01*
X1616399Y1421241D01*
X1615062D01*
G01X1668920Y617637D02*
X1670255D01*
X1684100Y603792D01*
Y577862D01*
X1679600Y573362D01*
X1640420D01*
X1626780Y559722D01*
Y516286D01*
X1662447Y480619D01*
G01X1677197Y1460908D02*
X1679944Y1463655D01*
G01D02*
X1682691Y1466402D01*
G01X1677197D02*
X1679944Y1463655D01*
G01D02*
X1682691Y1460908D01*
X3010Y63308D03*
Y123308D03*
Y163308D03*
Y183308D03*
Y203308D03*
Y223308D03*
Y243308D03*
Y263308D03*
Y283308D03*
Y303308D03*
X10884Y321693D03*
Y341693D03*
Y361693D03*
Y381693D03*
Y401693D03*
Y421693D03*
Y441693D03*
Y461693D03*
Y481693D03*
Y501693D03*
Y521693D03*
Y661693D03*
Y681693D03*
Y701693D03*
Y721693D03*
Y741693D03*
Y781693D03*
Y801693D03*
Y821693D03*
Y841693D03*
Y861693D03*
Y881693D03*
Y901693D03*
Y921693D03*
Y941693D03*
Y961693D03*
Y981693D03*
Y1001693D03*
Y1021693D03*
Y1041693D03*
Y1061693D03*
Y1081693D03*
Y1101693D03*
Y1121693D03*
Y1141693D03*
Y1161693D03*
Y1181693D03*
Y1201693D03*
Y1221693D03*
Y1241693D03*
Y1401693D03*
Y1421693D03*
Y1441693D03*
Y1461693D03*
Y1481693D03*
Y1501693D03*
Y1521693D03*
Y1541693D03*
Y1561693D03*
Y1581693D03*
X17371Y49388D03*
X16925Y203366D03*
X17061Y196368D03*
X24720Y216362D03*
Y232362D03*
Y224362D03*
Y240362D03*
X22223Y388057D03*
X29509Y398132D03*
X26615Y670036D03*
X26500Y672862D03*
Y675862D03*
X20188Y1599396D03*
X28601Y1617541D03*
Y1637541D03*
Y1657541D03*
Y1677541D03*
X37371Y49388D03*
X33500Y200862D03*
X33670Y192862D03*
Y232362D03*
Y240362D03*
X40000Y298707D03*
X36000Y295952D03*
X39410Y384582D03*
X39226Y395346D03*
X33020Y382822D03*
X36524Y398013D03*
X38220Y589862D03*
Y592862D03*
Y595862D03*
X33020Y595232D03*
X32720Y598402D03*
X38470Y688122D03*
Y683122D03*
Y680622D03*
Y685622D03*
Y693122D03*
Y690622D03*
Y695622D03*
X34899Y711400D03*
X45700Y724100D03*
X45800Y726874D03*
X44833Y1656759D03*
X54593Y19183D03*
X59322Y360702D03*
X51114Y360862D03*
X62812Y412708D03*
X62813Y415750D03*
X56799Y1520094D03*
Y1536094D03*
Y1540094D03*
Y1560094D03*
X59833Y1604359D03*
X54333Y1613359D03*
X50333D03*
X57833Y1671809D03*
X69058Y3010D03*
X63429Y360702D03*
X77220Y379022D03*
Y381522D03*
X75516Y420319D03*
Y424319D03*
X63540Y438802D03*
X72610Y441262D03*
Y444762D03*
X77000Y485362D03*
X74550Y487812D03*
X63930Y739300D03*
X76680Y1530482D03*
X72774Y1546519D03*
X77833Y1678902D03*
X73833Y1674252D03*
X89058Y3010D03*
X87520Y395865D03*
Y391391D03*
Y382219D03*
X79400Y482862D03*
X94811Y510173D03*
X80460Y655672D03*
X83100Y649762D03*
X87565Y670441D03*
X94473Y698926D03*
X79451Y699517D03*
X93547Y692260D03*
X82735Y717949D03*
X87865Y714394D03*
X85165D03*
X81225Y715854D03*
X85835Y718049D03*
X82357Y737803D03*
X84623Y741249D03*
X87500Y1567069D03*
X91500D03*
X90713Y1581852D03*
Y1597867D03*
X81008Y1589872D03*
X90788Y1601867D03*
X81833Y1674526D03*
X92895Y1737108D03*
X109058Y3010D03*
X107200Y393562D03*
X113597Y488434D03*
X102060Y493578D03*
X102152Y509374D03*
X102334Y500628D03*
X102359Y497374D03*
X102152Y513374D03*
X105587Y520727D03*
X102269Y634466D03*
X108909Y654926D03*
X102909Y648926D03*
Y642926D03*
Y655102D03*
X108909Y642926D03*
X107045Y661917D03*
X102060Y692100D03*
X98134Y722501D03*
X96626Y736187D03*
X99274Y1529169D03*
X96570Y1546187D03*
X104430Y1628012D03*
X104318Y1637862D03*
X99600Y1668332D03*
X99645Y1663217D03*
X122000Y207362D03*
X116920Y207462D03*
X119457Y392071D03*
X117597Y488434D03*
X127206Y480216D03*
X126225Y504368D03*
X120225D03*
Y510368D03*
X116411Y497707D03*
X126225Y516368D03*
X120225D03*
X129762Y531942D03*
X123257Y547506D03*
X119087D03*
X115060D03*
X114909Y654926D03*
Y648926D03*
Y642926D03*
X114021Y669409D03*
X118021D03*
X118019Y661371D03*
X124737Y735726D03*
X118737D03*
X121737D03*
Y738726D03*
X118737D03*
X124737D03*
X112749Y1532594D03*
Y1528594D03*
Y1552594D03*
Y1556594D03*
X117707Y1553759D03*
X125033Y1589352D03*
X112895Y1737108D03*
X129058Y3010D03*
X141520Y181462D03*
X139720Y179162D03*
X143470Y184012D03*
X132490Y420062D03*
X142166Y490835D03*
X132225Y504368D03*
Y510368D03*
X132401Y516368D03*
X133160Y532002D03*
X131740Y640103D03*
X134205Y643603D03*
X128275Y665515D03*
X129600Y669400D03*
X142960Y690807D03*
X140460D03*
X142754Y698811D03*
X140254D03*
X142778Y706835D03*
X140278D03*
X140326Y721660D03*
X142826D03*
X141470Y1359100D03*
X144263Y1412275D03*
X129627Y1556360D03*
X129586Y1553759D03*
X132895Y1737108D03*
X149058Y3010D03*
X145720Y186462D03*
X154220Y375682D03*
X158110Y376172D03*
X160090Y391170D03*
Y397470D03*
X152171Y490615D03*
X149472Y502810D03*
X149486Y498810D03*
X160000Y510052D03*
X149518Y522810D03*
X149504Y519881D03*
X154647Y521783D03*
X154477Y1360797D03*
X159898Y1360790D03*
X148663Y1378607D03*
X151163D03*
Y1383807D03*
Y1381207D03*
X148663Y1386407D03*
X151163D03*
X148663Y1383807D03*
Y1381207D03*
X152806Y1414175D03*
X155858Y1406669D03*
Y1409390D03*
X147067Y1545985D03*
X157441Y1581932D03*
X152895Y1737108D03*
X169058Y3010D03*
X166986Y575918D03*
X161126Y721660D03*
X161078Y706835D03*
X163626Y721660D03*
X163578Y706835D03*
X162398Y1360790D03*
X164898D03*
X172807Y1360797D03*
X174932Y1378797D03*
Y1381397D03*
X162693Y1411529D03*
X171262Y1443390D03*
X173727Y1452134D03*
Y1448734D03*
X172895Y1737108D03*
X189058Y3010D03*
X187532Y421387D03*
X187490Y568752D03*
X190977Y669718D03*
X190800Y675662D03*
X191976Y684326D03*
X186720Y737862D03*
X180720D03*
X183720D03*
Y734862D03*
X180720D03*
X186720D03*
X184215Y1361072D03*
X181403Y1361115D03*
X192620Y1360797D03*
X188233Y1387027D03*
Y1379227D03*
Y1381827D03*
Y1384427D03*
X183283Y1387987D03*
X185633Y1387027D03*
X180672Y1387987D03*
X185633Y1379227D03*
X180672Y1380187D03*
X183283D03*
X177532Y1378797D03*
X185633Y1384427D03*
Y1381827D03*
X180672Y1382787D03*
Y1385387D03*
X183283Y1382787D03*
Y1385387D03*
X177421Y1383997D03*
X177532Y1381397D03*
X182653Y1404535D03*
X192767Y1413725D03*
X185643Y1413945D03*
X192600Y1557360D03*
X189600Y1566300D03*
X187400Y1568132D03*
X192895Y1737108D03*
X209058Y3010D03*
X199149Y425755D03*
Y420255D03*
Y414755D03*
X204699Y423242D03*
Y428742D03*
X199149Y436755D03*
Y442255D03*
Y431255D03*
Y453255D03*
Y447755D03*
Y468255D03*
X208200Y493510D03*
X196526Y567825D03*
X201392Y574271D03*
X198336D03*
X195888Y581071D03*
X194515Y583433D03*
X197423Y601496D03*
X194059Y604901D03*
X201392Y608271D03*
X198336D03*
X195888Y615071D03*
X194515Y617433D03*
X194059Y638901D03*
X197423Y635496D03*
X194515Y651433D03*
X195888Y649071D03*
X201392Y642271D03*
X199164Y650481D03*
X198336Y642271D03*
X205320Y667562D03*
X198420Y672662D03*
X194858Y684348D03*
X203441Y1360790D03*
X198041D03*
X200941D03*
X201071Y1412173D03*
X193941Y1407029D03*
Y1409750D03*
X195966Y1542863D03*
X209530Y426192D03*
X217770Y428262D03*
X224064Y568113D03*
X221464D03*
X212891Y566632D03*
X224064Y602113D03*
X221464D03*
X223403Y596820D03*
Y594220D03*
X212891Y601981D03*
X223403Y630820D03*
Y628220D03*
X224064Y636113D03*
X221464D03*
X212891Y635981D03*
X223403Y664820D03*
X217510Y668712D03*
X225167Y672006D03*
X222567D03*
X219967D03*
X217367D03*
X211348Y688087D03*
Y685287D03*
X214100Y687376D03*
Y690376D03*
Y684376D03*
Y681376D03*
Y678376D03*
X211348Y690787D03*
Y693587D03*
X214100Y693576D03*
X224506Y698138D03*
Y700738D03*
X221906Y698138D03*
Y700738D03*
X219306D03*
Y698138D03*
X215824Y1361199D03*
X211350Y1360797D03*
X218960Y1388312D03*
X213075Y1381558D03*
X217133Y1384055D03*
X214425Y1384058D03*
X215675Y1381558D03*
X218175D03*
X213075Y1378958D03*
X215675D03*
X218175D03*
X219752Y1405499D03*
Y1401999D03*
Y1398599D03*
X224137Y1414345D03*
X224077Y1416975D03*
X224350Y1432032D03*
X217469Y1454725D03*
X220869D03*
X212895Y1737108D03*
X229058Y3010D03*
X231864Y568113D03*
X229264D03*
X226664D03*
X229264Y602113D03*
X226664D03*
X226003Y594220D03*
Y596820D03*
X228603Y594220D03*
Y596820D03*
X231864Y602113D03*
X231203Y594220D03*
Y596820D03*
X226003Y628220D03*
Y630820D03*
X228603Y628220D03*
Y630820D03*
X231864Y636113D03*
X231203Y628220D03*
Y630820D03*
X229264Y636113D03*
X226664D03*
X228603Y664820D03*
X231203D03*
X226003D03*
X230367Y672006D03*
X227767D03*
X227106Y698138D03*
Y700738D03*
X249058Y3010D03*
X248820Y48962D03*
X252320D03*
X255820D03*
X257520Y51562D03*
X254020D03*
X250520D03*
X252000Y395400D03*
X254713Y518465D03*
X245700Y513262D03*
X250100Y521783D03*
X256885Y574805D03*
X254385D03*
X256855Y571995D03*
X251885Y574805D03*
X249800Y563262D03*
X254355Y589235D03*
X256855D03*
X251855D03*
X256855Y605995D03*
X251885Y608805D03*
X257643Y594220D03*
X255043D03*
Y596820D03*
X257643D03*
X256885Y608805D03*
X254385D03*
X256855Y603495D03*
X251855Y623265D03*
X254355D03*
X256855D03*
Y639995D03*
Y637495D03*
X257643Y628220D03*
X255043D03*
Y630820D03*
X257643D03*
X256885Y642805D03*
X254385D03*
X251855Y657265D03*
X251885Y642805D03*
X254355Y657265D03*
X256855D03*
X257643Y662220D03*
X255043D03*
Y664820D03*
X257643D03*
X253819Y675567D03*
X253849Y678077D03*
X256419Y675567D03*
X256449Y678077D03*
X251219Y675567D03*
X251249Y678077D03*
X248649D03*
X248989Y698827D03*
X249019Y693767D03*
X251589Y698827D03*
X251649Y696277D03*
X254189Y698827D03*
X251619Y693767D03*
X256849Y696277D03*
X256789Y698827D03*
X256819Y693767D03*
X254249Y696277D03*
X254219Y693767D03*
X248300Y703862D03*
X252895Y1737108D03*
X269058Y3010D03*
X275120Y28562D03*
X275900Y48872D03*
X259320Y48962D03*
X261020Y51562D03*
X263520D03*
X261820Y48962D03*
X264740Y49182D03*
X266497Y69536D03*
Y72036D03*
X264720Y56362D03*
Y60362D03*
Y64362D03*
X266597Y77526D03*
Y80026D03*
X263320Y87662D03*
X261420Y100662D03*
X264920D03*
X268420D03*
X262920Y97962D03*
X266420D03*
X269920D03*
X273620Y96662D03*
X272361Y120243D03*
X270364Y118415D03*
X261387Y133783D03*
X258257D03*
X264055Y574505D03*
X264025Y571995D03*
X261555Y574505D03*
X261525Y571995D03*
X264055Y566935D03*
X263995Y569485D03*
X261495D03*
X261555Y566935D03*
X266555Y574505D03*
X266525Y571995D03*
X266495Y569485D03*
X266555Y566935D03*
X269055Y574505D03*
X269025Y571995D03*
X268995Y569485D03*
X269055Y566935D03*
X261465Y592115D03*
X261525Y589565D03*
X264025D03*
X263965Y592115D03*
X266525Y589565D03*
X266465Y592115D03*
X269025Y589565D03*
X268965Y592115D03*
X264025Y605995D03*
X261525D03*
X264055Y608505D03*
X261555D03*
X261435Y597175D03*
X261495Y594625D03*
X263995D03*
X263935Y597175D03*
X266525Y605995D03*
X266555Y608505D03*
X266435Y597175D03*
X266495Y594625D03*
X261525Y603495D03*
X264025D03*
X266525D03*
X269025Y605995D03*
X269055Y608505D03*
X268935Y597175D03*
X268995Y594625D03*
X269025Y603495D03*
X261495Y621055D03*
X263995D03*
X261525Y623565D03*
X264025D03*
X263995Y611055D03*
X261495D03*
X266495Y621055D03*
X266525Y623565D03*
X266495Y611055D03*
X268995Y621055D03*
X269025Y623565D03*
X268995Y611055D03*
X261525Y639995D03*
X264025D03*
X261525Y637495D03*
X266525Y639995D03*
X269025D03*
X264025Y637495D03*
X266525D03*
X269025D03*
X263965Y626115D03*
X261465D03*
X266465D03*
X268965D03*
X261495Y655055D03*
X263995D03*
X261525Y657565D03*
X264025D03*
X263995Y645055D03*
X264055Y642505D03*
X261495Y645055D03*
X261555Y642505D03*
X266495Y655055D03*
X266525Y657565D03*
X266495Y645055D03*
X266555Y642505D03*
X268995Y655055D03*
X269025Y657565D03*
X268995Y645055D03*
X269055Y642505D03*
X261465Y660115D03*
X263965D03*
X266465D03*
X268965D03*
X259049Y678077D03*
X259019Y675567D03*
X259419Y693767D03*
X259389Y698827D03*
X259449Y696277D03*
X272895Y1737108D03*
X289058Y3010D03*
X287000Y20862D03*
X290799Y28362D03*
X289400Y54222D03*
X287800Y60062D03*
X279277Y99183D03*
X289557Y121803D03*
X277578Y509039D03*
X284482Y566022D03*
X286582Y637809D03*
Y634283D03*
X292060Y24472D03*
X292590Y53982D03*
X292942Y67513D03*
X293447Y78573D03*
X293452Y82483D03*
Y85983D03*
X303047Y79373D03*
X299947Y79273D03*
X299657Y92503D03*
X301751Y127466D03*
Y124466D03*
Y121466D03*
X305612Y622530D03*
Y625030D03*
Y627530D03*
X303647Y1307981D03*
X303831Y1318566D03*
X303807Y1342225D03*
X303831Y1344866D03*
X304047Y1368565D03*
X302805Y1379941D03*
Y1376541D03*
X292895Y1737108D03*
X309058Y3010D03*
X318651Y22921D03*
X320057Y85803D03*
Y88803D03*
X311758Y124469D03*
Y121469D03*
Y127469D03*
X321276Y599298D03*
X317386Y623207D03*
X308605Y629525D03*
Y627025D03*
X320578Y1290197D03*
X323028Y1297967D03*
X320428D03*
Y1295467D03*
X323028D03*
Y1292967D03*
X320428D03*
X321119Y1313108D03*
X317119D03*
X313119D03*
X317979Y1371248D03*
X315221Y1372445D03*
X329535Y49388D03*
X328167Y379073D03*
X336270Y402992D03*
X338097Y736235D03*
X335126Y728323D03*
X339148Y1269717D03*
X339088Y1272287D03*
X339028Y1274887D03*
X325688Y1290167D03*
X325718Y1287587D03*
X328078Y1288747D03*
X323178Y1290197D03*
X323208Y1287617D03*
X328168Y1280967D03*
X325748Y1284987D03*
X328108Y1286147D03*
X328138Y1283567D03*
X328018Y1291317D03*
X339035Y1280218D03*
X339040Y1277594D03*
X328065Y1299248D03*
X325538Y1297937D03*
Y1292937D03*
Y1295437D03*
X328058Y1293917D03*
X328070Y1296624D03*
X325119Y1313108D03*
X328915Y1337104D03*
X331515D03*
X328915Y1331904D03*
X331515D03*
X328915Y1329304D03*
X331515D03*
X328915Y1334504D03*
X331515D03*
X328915Y1326704D03*
X331515D03*
X328915Y1339704D03*
X338917Y1349488D03*
X336347Y1348353D03*
X332895Y1737108D03*
X349535Y49388D03*
X340440Y120552D03*
X343450Y131167D03*
X348100Y185162D03*
X345600Y188162D03*
X356295Y219362D03*
X343354Y391643D03*
X347340Y407462D03*
X344264Y1272455D03*
X341754Y1272485D03*
X344252Y1269948D03*
X341742Y1269978D03*
X344258Y1267117D03*
X341748Y1267147D03*
X341754Y1274985D03*
X344264Y1274955D03*
X355036Y1272433D03*
Y1269933D03*
X355378Y1262027D03*
X355318Y1264597D03*
X355258Y1267197D03*
X355036Y1274933D03*
X341605Y1280248D03*
X344115Y1280218D03*
X344264Y1277455D03*
X341754Y1277485D03*
X355048Y1277440D03*
X355025Y1280248D03*
X339769Y1299868D03*
X342769D03*
X348804Y1346877D03*
X350470Y1349030D03*
X352895Y1737108D03*
X361190Y210762D03*
X357303Y213159D03*
X371551Y224862D03*
X364014Y378649D03*
X370200Y409582D03*
X355946Y728800D03*
X359790Y729835D03*
X358902Y739755D03*
Y746405D03*
X371578Y1248967D03*
X371458Y1254137D03*
X371330Y1256687D03*
X371518Y1251537D03*
X371278Y1259257D03*
X360198Y1269777D03*
X357546Y1272403D03*
Y1269903D03*
X360138Y1272347D03*
X357828Y1264567D03*
X357888Y1261997D03*
X360378Y1264627D03*
X360438Y1262057D03*
X357768Y1267167D03*
X360318Y1267227D03*
X357546Y1274903D03*
X360128Y1274957D03*
X371218Y1261857D03*
X371225Y1267188D03*
X371230Y1264564D03*
X357558Y1277410D03*
X357535Y1280218D03*
X360120Y1277654D03*
X361043Y1306506D03*
X361769Y1300008D03*
X363643Y1306506D03*
X364769Y1300008D03*
X367939Y1303319D03*
Y1305919D03*
Y1308519D03*
X361043Y1314306D03*
Y1316906D03*
X362393Y1319406D03*
X361043Y1309106D03*
Y1311706D03*
X363643Y1316906D03*
Y1314306D03*
Y1309106D03*
Y1311706D03*
X370874Y1335876D03*
X367490Y1332568D03*
X366700Y1649000D03*
X370500Y1654362D03*
X370635Y1675820D03*
X369300Y1680400D03*
Y1682900D03*
X376500Y378649D03*
X383060Y403542D03*
X387500Y495362D03*
X389020Y522862D03*
X376638Y1248997D03*
X374088Y1248937D03*
X374028Y1251507D03*
X373823Y1256896D03*
X376333Y1256866D03*
X376518Y1254167D03*
X376578Y1251567D03*
X373968Y1254107D03*
X373835Y1259403D03*
X376345Y1259373D03*
X387478Y1248967D03*
X387358Y1254137D03*
X387117Y1256851D03*
X387418Y1251537D03*
X387117Y1259351D03*
X373835Y1261903D03*
Y1264403D03*
X376345Y1261873D03*
Y1264373D03*
X376285Y1267218D03*
X373735Y1267158D03*
X387117Y1261851D03*
X387129Y1264358D03*
X387125Y1267188D03*
X383239Y1286578D03*
X378069Y1286568D03*
X375069D03*
X386239Y1286578D03*
X380842Y1334095D03*
X383549Y1333998D03*
X383127Y1395610D03*
X381060Y1433622D03*
X374800Y1546400D03*
X380170Y1660002D03*
X372640Y1662112D03*
X380077Y1654049D03*
X372895Y1737108D03*
X396380Y62742D03*
X402100Y62632D03*
X399240Y62722D03*
X404910Y62562D03*
X400080Y472652D03*
X402500Y495362D03*
X394500Y522862D03*
X403738Y1249027D03*
X403618Y1254197D03*
X403498Y1256747D03*
X403678Y1251597D03*
X392538Y1248997D03*
X389928Y1251507D03*
X389988Y1248937D03*
X389868Y1254107D03*
X392298Y1256717D03*
X392418Y1254167D03*
X389627Y1256821D03*
X392478Y1251567D03*
X392238Y1259287D03*
X389627Y1259321D03*
X403438Y1259317D03*
X392220Y1264594D03*
X392228Y1261897D03*
X389627Y1261821D03*
X389639Y1264328D03*
X389635Y1267158D03*
X392185Y1267218D03*
X403385Y1267248D03*
X403378Y1261917D03*
X403390Y1264624D03*
X396139Y1286708D03*
X399139D03*
X395771Y1303480D03*
X393171D03*
X395771Y1300880D03*
X393171D03*
X395771Y1295680D03*
X393171D03*
X395771Y1298280D03*
X393171D03*
X394521Y1305980D03*
X400067Y1303319D03*
Y1300719D03*
Y1295519D03*
Y1298119D03*
Y1305919D03*
Y1308519D03*
X399673Y1332653D03*
X403130Y1335963D03*
X400926Y1402207D03*
X391249Y1401048D03*
X392947Y1397827D03*
X390934Y1404085D03*
X400919Y1411231D03*
X390934Y1407605D03*
X391370Y1424782D03*
X407970Y59612D03*
X407790Y62652D03*
X418540Y392163D03*
X406248Y1248997D03*
X408798Y1249057D03*
X408511Y1256866D03*
X406001Y1256896D03*
X406128Y1254167D03*
X408678Y1254227D03*
X406188Y1251567D03*
X419638Y1248967D03*
X419295Y1256851D03*
X419518Y1254137D03*
X419578Y1251537D03*
X419295Y1259351D03*
X408738Y1251627D03*
X408523Y1259373D03*
X406013Y1259403D03*
X419295Y1261851D03*
X419307Y1264358D03*
X419285Y1267188D03*
X408523Y1264373D03*
X406013Y1264403D03*
Y1261903D03*
X408523Y1261873D03*
X405895Y1267218D03*
X408445Y1267278D03*
X416099Y1335568D03*
X414617Y1333473D03*
X412465Y1393878D03*
X419974Y1405289D03*
Y1412789D03*
X420474Y1420289D03*
X407125Y1424978D03*
X421320Y1671699D03*
X428889Y121515D03*
X428883Y131015D03*
X425720Y319492D03*
X431220Y518133D03*
Y523362D03*
X422148Y1248937D03*
X424698Y1248997D03*
X422088Y1251507D03*
X421805Y1256821D03*
X422028Y1254107D03*
X424458Y1256717D03*
X424578Y1254167D03*
X424638Y1251567D03*
X421805Y1259321D03*
X424398Y1259287D03*
X436068Y1248967D03*
X435828Y1256687D03*
X435948Y1254137D03*
X436008Y1251537D03*
X435768Y1259257D03*
X421805Y1261821D03*
X421817Y1264328D03*
X421795Y1267158D03*
X424345Y1267218D03*
X424380Y1264594D03*
X424388Y1261897D03*
X435715Y1267188D03*
X435720Y1264564D03*
X435708Y1261857D03*
X430999Y1286758D03*
X423229D03*
X426229D03*
X433999D03*
X432195Y1303319D03*
Y1305919D03*
X425299Y1303480D03*
X426649Y1305980D03*
X427899Y1303480D03*
X425299Y1295680D03*
X427899D03*
X432195Y1295519D03*
Y1298119D03*
X427899Y1298280D03*
X425299D03*
X432195Y1300719D03*
X427899Y1300880D03*
X425299D03*
X432195Y1308519D03*
X434983Y1335924D03*
X431578Y1332560D03*
X427474Y1405289D03*
X434974D03*
Y1412789D03*
X427474Y1420289D03*
X434974D03*
X438645Y1426890D03*
X437299Y1436774D03*
X424820Y1552605D03*
X431620Y1541362D03*
X434430Y1567562D03*
X432895Y1737108D03*
X442265Y290939D03*
X439120Y314562D03*
X442220Y323362D03*
X448220Y323582D03*
Y319862D03*
X448276Y1161570D03*
X445776D03*
X443276D03*
X445776Y1153370D03*
X448276D03*
X443276D03*
X448276Y1170069D03*
X445776D03*
X443276D03*
X441128Y1248997D03*
X438578Y1248937D03*
X438518Y1251507D03*
X440858Y1256866D03*
X438348Y1256896D03*
X441008Y1254167D03*
X438458Y1254107D03*
X441068Y1251567D03*
X440870Y1259373D03*
X438360Y1259403D03*
X451642Y1256851D03*
X451878Y1254107D03*
X451642Y1259351D03*
X451938Y1251507D03*
X451998Y1248937D03*
X438360Y1261903D03*
X440870Y1261873D03*
Y1264373D03*
X438360Y1264403D03*
X438225Y1267158D03*
X440775Y1267218D03*
X451642Y1261851D03*
X451654Y1264358D03*
X451645Y1267158D03*
X446944Y1335928D03*
X445153Y1334095D03*
X445339Y1415731D03*
X446258Y1441606D03*
X449778D03*
X448740Y1574862D03*
X454661Y1609235D03*
X449940Y1647412D03*
X447090Y1647472D03*
X452895Y1737108D03*
X466300Y217803D03*
Y225480D03*
X456520Y476337D03*
X461520D03*
X456818Y1256687D03*
X454388Y1254077D03*
X454152Y1256821D03*
X456998Y1251537D03*
X456758Y1259257D03*
X454152Y1259321D03*
X468258Y1249107D03*
X468018Y1256827D03*
X468138Y1254277D03*
X468198Y1251677D03*
X467958Y1259397D03*
X457058Y1248967D03*
X454508Y1248907D03*
X454448Y1251477D03*
X456938Y1254137D03*
X456705Y1267188D03*
X454155Y1267128D03*
X456748Y1261867D03*
X456740Y1264564D03*
X454152Y1261821D03*
X454164Y1264328D03*
X467905Y1267328D03*
X467910Y1264704D03*
X467898Y1261997D03*
X460049Y1286978D03*
X463049D03*
X469019Y1286718D03*
X458327Y1303980D03*
X460927D03*
X464427Y1305380D03*
X460927Y1306580D03*
X458327D03*
Y1301380D03*
X460927D03*
X464427Y1300180D03*
Y1302780D03*
X458327Y1296180D03*
X460927D03*
X464427D03*
X458327Y1298780D03*
X460927D03*
X464423Y1308519D03*
X464738Y1333085D03*
X467644Y1335981D03*
X465749Y1401238D03*
X459321Y1393009D03*
Y1396409D03*
X455576Y1409125D03*
Y1417125D03*
X455602Y1412334D03*
X455576Y1420625D03*
X468880Y1418400D03*
X455576Y1427632D03*
Y1424125D03*
X454450Y1433580D03*
X463207Y1547543D03*
X460200Y1589900D03*
X486800Y259162D03*
X473698Y1161570D03*
X471198D03*
X473698Y1153370D03*
X471198D03*
X473698Y1170070D03*
X471198D03*
X473318Y1249137D03*
X470768Y1249077D03*
X473035Y1256866D03*
X470525Y1256896D03*
X473198Y1254307D03*
X470648Y1254247D03*
X473258Y1251707D03*
X470708Y1251647D03*
X473047Y1259373D03*
X470537Y1259403D03*
X484098Y1248997D03*
X483819Y1256851D03*
X483978Y1254167D03*
X484038Y1251567D03*
X483819Y1259351D03*
X472965Y1267358D03*
X470415Y1267298D03*
X470537Y1261903D03*
X473047Y1261873D03*
Y1264373D03*
X470537Y1264403D03*
X483819Y1261851D03*
X483831Y1264358D03*
X483745Y1267218D03*
X474509Y1286848D03*
X481509D03*
X477509D03*
X484509D03*
X477162Y1334095D03*
X478909Y1336038D03*
X475285Y1395402D03*
X485236Y1417844D03*
X481997Y1409955D03*
X482741Y1438698D03*
X478308Y1439986D03*
X482742Y1441312D03*
X470111Y1548269D03*
X472895Y1737108D03*
X503100Y215244D03*
X496028Y258590D03*
X486608Y1248967D03*
X489158Y1249027D03*
X486329Y1256821D03*
X486488Y1254137D03*
X488918Y1256747D03*
X489038Y1254197D03*
X486548Y1251537D03*
X489098Y1251597D03*
X486329Y1259321D03*
X488858Y1259317D03*
X500228Y1259237D03*
X486329Y1261821D03*
X486341Y1264328D03*
X488840Y1264624D03*
X488848Y1261927D03*
X488805Y1267248D03*
X486255Y1267188D03*
X500138Y1269637D03*
X500150Y1272344D03*
X500198Y1267037D03*
Y1264467D03*
X500168Y1261807D03*
X500150Y1275224D03*
X490759Y1291978D03*
X500150Y1278104D03*
X496451Y1306345D03*
X489555Y1303480D03*
X492155D03*
X490905Y1305980D03*
X492155Y1300880D03*
X489555D03*
X495309Y1300058D03*
X498309D03*
X496220Y1322440D03*
X496451Y1316745D03*
Y1308945D03*
Y1314145D03*
Y1311545D03*
X499458Y1349468D03*
X499818Y1385027D03*
X499859Y1393027D03*
X490307Y1421499D03*
X491156Y1438713D03*
X499541Y1438698D03*
X491142Y1441312D03*
X499542D03*
X492895Y1737108D03*
X512500Y223362D03*
X502260Y397742D03*
X511320Y437962D03*
X505398Y1259377D03*
X502858Y1259257D03*
X502718Y1271417D03*
X505218Y1271447D03*
X505290Y1267254D03*
X505338Y1261947D03*
X505278Y1264547D03*
X502750Y1267134D03*
X502798Y1261827D03*
X502738Y1264427D03*
X502718Y1274114D03*
X505218Y1274144D03*
X515898Y1271447D03*
X515950Y1274144D03*
X505220Y1280054D03*
X502718Y1276994D03*
X505218Y1277024D03*
X502680Y1280054D03*
X515960D03*
X515950Y1277024D03*
X517989Y1300108D03*
X514989D03*
X509382Y1347521D03*
X511149Y1349468D03*
X505055Y1387601D03*
Y1382301D03*
X505018Y1385027D03*
X502418D03*
X505055Y1396001D03*
Y1398601D03*
Y1390201D03*
X508881Y1404880D03*
X506181D03*
X505059Y1393027D03*
X502459D03*
X503559Y1405025D03*
X508775Y1409889D03*
X508828Y1407385D03*
X508802Y1412420D03*
X506075Y1409889D03*
X506128Y1407385D03*
X503572Y1407539D03*
Y1415039D03*
Y1412539D03*
X506102Y1412420D03*
X503572Y1410039D03*
X508001Y1438669D03*
X507942Y1441312D03*
X512895Y1737108D03*
X518606Y23797D03*
X532650Y442376D03*
Y454270D03*
X524720Y525293D03*
Y519743D03*
X521118Y1273097D03*
X518488Y1271477D03*
X521058Y1275667D03*
X518490Y1274144D03*
X521058Y1278277D03*
X521020Y1280974D03*
X518500Y1280054D03*
X518490Y1277024D03*
X530398Y1288557D03*
X530548Y1283377D03*
X530428Y1285947D03*
X530410Y1291254D03*
X532558Y1289967D03*
X532618Y1287367D03*
X532678Y1284797D03*
X530450Y1297014D03*
Y1294134D03*
X532570Y1295554D03*
Y1298434D03*
Y1292674D03*
X523033Y1319406D03*
X527645Y1326076D03*
X528579Y1329143D03*
X528377Y1335982D03*
X528579Y1342143D03*
Y1344743D03*
X528975Y1369724D03*
X532895Y1737108D03*
X542870Y438320D03*
X548464Y456534D03*
X548780Y475932D03*
X548550Y480382D03*
X546210Y519642D03*
X537648Y1290037D03*
X535058Y1290007D03*
X535148Y1287397D03*
X543660Y1302934D03*
X541100D03*
X538560D03*
X535110Y1292704D03*
Y1295584D03*
Y1298464D03*
X537650Y1292704D03*
X540210D03*
X537650Y1298464D03*
Y1295584D03*
X540210Y1298464D03*
Y1295584D03*
X536020Y1302904D03*
X544813Y1322668D03*
X542213D03*
X538293D03*
X535693D03*
X542256Y1369935D03*
X555175Y71436D03*
X558575D03*
X564890Y142173D03*
X554872Y196635D03*
X559400Y201162D03*
X557248Y198909D03*
X564600Y202662D03*
X553402Y231292D03*
X558220Y459362D03*
X566140Y554972D03*
Y551472D03*
X558933Y1323658D03*
X563634Y1334315D03*
X561034D03*
X558933Y1326258D03*
X556563Y1337918D03*
X553963D03*
X558933Y1328938D03*
X556563Y1335318D03*
Y1332718D03*
X558933Y1331538D03*
X553963Y1335318D03*
Y1332718D03*
X555313Y1340418D03*
X555372Y1343037D03*
X561070Y1346174D03*
X565849Y1346968D03*
X552895Y1737108D03*
X567730Y225362D03*
Y221362D03*
X581755Y236978D03*
X569490Y437600D03*
X571110Y446706D03*
X577220Y449462D03*
X583220Y493212D03*
X584173Y498422D03*
X573849Y1346968D03*
X569849D03*
X572895Y1737108D03*
X595220Y140922D03*
X588000D03*
X583820Y314662D03*
X590820Y330962D03*
X590720Y327862D03*
Y324582D03*
X590470Y319192D03*
X599080Y448062D03*
X584100Y477952D03*
X590210Y484132D03*
X587100Y493842D03*
X591070Y504900D03*
X587100Y496342D03*
X591500Y516862D03*
X615220Y76862D03*
X615170Y73812D03*
X601220Y73862D03*
Y76862D03*
X613970Y188752D03*
X614200Y265792D03*
X614220Y462862D03*
X612895Y1737108D03*
X629000Y67362D03*
X617370Y188752D03*
X630040D03*
X626640D03*
X618470Y265732D03*
X623220Y426362D03*
X629220D03*
X625620Y447862D03*
X622220Y442862D03*
Y452862D03*
Y447862D03*
X626400Y462812D03*
X626390Y467882D03*
X626210Y478002D03*
X622220Y462862D03*
X626720Y482880D03*
X629480Y508862D03*
X638500Y57362D03*
X635000D03*
X649870Y181942D03*
X645263Y235689D03*
X643800Y298297D03*
Y302247D03*
X645990Y314482D03*
X643800Y310962D03*
X637220Y411362D03*
Y416362D03*
X640720Y431362D03*
X637220D03*
X640720Y452862D03*
X637220Y467862D03*
Y472862D03*
Y477862D03*
X641235Y477377D03*
X637220Y462862D03*
X640620Y483422D03*
X632895Y1737108D03*
X651943Y33535D03*
X656439Y47264D03*
X659839D03*
X651730Y177212D03*
X651520Y378662D03*
X655820Y452662D03*
X655800Y461432D03*
X662282Y1386432D03*
X663410Y1553982D03*
X664590Y1631620D03*
X652895Y1737108D03*
X678050Y58157D03*
X673987Y87662D03*
X673517Y1360815D03*
X676017D03*
X668096Y1360822D03*
X678517Y1360815D03*
X664782Y1383832D03*
Y1381232D03*
Y1378632D03*
Y1386432D03*
X666425Y1414200D03*
X676312Y1411554D03*
X673477Y1409386D03*
X677619Y1408887D03*
X682160Y1548040D03*
X678900Y1595400D03*
Y1589800D03*
Y1592600D03*
X672895Y1737108D03*
X696800Y42108D03*
X696838Y47940D03*
X694751Y70212D03*
X690027Y70142D03*
X685968Y58157D03*
X694400D03*
X681980D03*
X696700Y72462D03*
X692389Y72692D03*
X687664Y73202D03*
X684953Y104968D03*
X694390Y133682D03*
X687238Y171071D03*
X692400Y404682D03*
X690220Y519662D03*
X696810Y1300162D03*
X692280Y1302532D03*
X686426Y1360822D03*
X695022Y1361990D03*
X696462Y1386122D03*
X691351Y1380922D03*
X688751D03*
X691240Y1383522D03*
X693851D03*
Y1378322D03*
Y1380922D03*
X691351Y1378322D03*
X688751D03*
X693851Y1386122D03*
X696462Y1378322D03*
Y1383522D03*
Y1380922D03*
X696272Y1404560D03*
X685015Y1438475D03*
X696940Y1437955D03*
X701838Y42202D03*
Y47940D03*
X703900Y72112D03*
X701400D03*
X713000Y69662D03*
X697720Y58162D03*
X712500Y79862D03*
X712433Y103308D03*
X706673Y122762D03*
X703520Y122540D03*
X704880Y133643D03*
X707400Y396200D03*
X705780Y411022D03*
X712770Y406822D03*
X698094Y1361947D03*
X706239Y1360822D03*
X712060Y1360815D03*
X699062Y1380922D03*
Y1383522D03*
Y1378322D03*
X701662Y1380922D03*
Y1383522D03*
Y1378322D03*
X699062Y1386122D03*
X701662D03*
X699262Y1413970D03*
X704568Y1414119D03*
X706680Y1437535D03*
X701730Y1437855D03*
X711440Y1436905D03*
X710570Y1629890D03*
X700460Y1660918D03*
X723041Y-13200D03*
Y-9800D03*
X715990Y69662D03*
X721990Y69762D03*
X718900Y69662D03*
X728028Y105468D03*
X724969Y1360822D03*
X714560Y1360815D03*
X717060D03*
X729443Y1361224D03*
X726694Y1381583D03*
Y1378983D03*
X728044Y1384083D03*
X729294Y1381583D03*
Y1378983D03*
X714455Y1411554D03*
X715762Y1408887D03*
X726810Y1652430D03*
X745130Y69508D03*
X735733Y111988D03*
X732700Y351500D03*
X735220Y410842D03*
X745220Y503842D03*
X737784Y1360017D03*
X730752Y1384080D03*
X731794Y1381583D03*
Y1378983D03*
X732238Y1388343D03*
X738810Y1396665D03*
X741540Y1396585D03*
X739170Y1405655D03*
X741670Y1405675D03*
X738170Y1414185D03*
X740760Y1414165D03*
X733336Y1568341D03*
Y1565341D03*
Y1559341D03*
Y1562341D03*
X730336Y1559341D03*
Y1562341D03*
X745336D03*
Y1559341D03*
Y1565341D03*
Y1568341D03*
X742336Y1562341D03*
Y1559341D03*
Y1565341D03*
Y1568341D03*
X739336Y1562341D03*
Y1559341D03*
Y1565341D03*
Y1568341D03*
X736336D03*
Y1565341D03*
Y1559341D03*
Y1562341D03*
X733336Y1574341D03*
Y1571341D03*
X745336Y1574341D03*
Y1571341D03*
X742336Y1574341D03*
Y1571341D03*
X739336Y1574341D03*
Y1571341D03*
X736336D03*
Y1574341D03*
X732705Y1669450D03*
X732895Y1737108D03*
X758606Y23797D03*
X755700Y59942D03*
Y62442D03*
X758200Y59942D03*
Y62442D03*
X760700Y59942D03*
Y62442D03*
X754219Y75707D03*
X755305Y298847D03*
X758390Y295450D03*
X757430Y408212D03*
X752500Y495762D03*
X756650Y526072D03*
X755420Y1426262D03*
Y1422862D03*
X748336Y1562341D03*
Y1559341D03*
Y1565341D03*
Y1568341D03*
X751336D03*
Y1565341D03*
Y1559341D03*
Y1562341D03*
X748336Y1574341D03*
Y1571341D03*
X761716Y1661194D03*
X751620Y1674312D03*
X752875Y1726670D03*
X752895Y1737108D03*
X765606Y44894D03*
X765858Y87340D03*
X762368Y84088D03*
X769284Y103895D03*
X767061Y99959D03*
X767045Y95960D03*
X767028Y91490D03*
X776730Y117479D03*
X773943Y114633D03*
X771131Y111788D03*
X769775Y107977D03*
X771426Y158026D03*
X766320Y264892D03*
X763320D03*
X769860Y302462D03*
X773245Y398212D03*
Y403212D03*
Y408212D03*
X771050Y416940D03*
X768701Y418662D03*
X772365Y454862D03*
Y459862D03*
X769337Y760775D03*
X768520Y1375462D03*
X775375Y1403561D03*
X772208Y1731911D03*
X785095Y49388D03*
X785180Y120947D03*
X792680D03*
X790180D03*
X787680D03*
X783940Y118637D03*
X786440D03*
X788940D03*
X781440D03*
X785220Y284762D03*
X792943Y312642D03*
X784415Y313734D03*
X790120Y354862D03*
X780020Y438287D03*
X787360Y469862D03*
X791140Y761693D03*
X784352Y1568293D03*
Y1565293D03*
Y1559293D03*
Y1562293D03*
X781352Y1568293D03*
Y1565293D03*
Y1559293D03*
Y1562293D03*
X793352D03*
Y1559293D03*
Y1565293D03*
Y1568293D03*
X790352Y1562293D03*
Y1559293D03*
Y1565293D03*
Y1568293D03*
X787352D03*
Y1565293D03*
Y1559293D03*
Y1562293D03*
X784352Y1574293D03*
Y1571293D03*
X781352Y1574293D03*
Y1571293D03*
X793352Y1574293D03*
Y1571293D03*
X790352Y1574293D03*
Y1571293D03*
X787352D03*
Y1574293D03*
X792208Y1731911D03*
X805095Y49388D03*
X803620Y302962D03*
X797900Y354800D03*
X801750Y444330D03*
X798990Y474862D03*
X802865D03*
X801940Y485932D03*
X807000Y757562D03*
X799352Y1562293D03*
Y1559293D03*
Y1565293D03*
Y1568293D03*
X796352Y1562293D03*
Y1559293D03*
Y1565293D03*
Y1568293D03*
X799352Y1574293D03*
Y1571293D03*
X796352Y1574293D03*
Y1571293D03*
X825095Y49388D03*
X819114Y115223D03*
X826300Y311962D03*
X823800D03*
X816400Y472900D03*
X823352Y1565293D03*
Y1562293D03*
Y1559293D03*
Y1568293D03*
X826352Y1565293D03*
Y1562293D03*
Y1559293D03*
Y1568293D03*
X823352Y1571293D03*
Y1574293D03*
X826352Y1571293D03*
Y1574293D03*
X812208Y1731911D03*
X840001Y20200D03*
Y16800D03*
X838220Y163862D03*
X835220D03*
X837320Y175112D03*
X839450Y272662D03*
X827620Y302962D03*
X830417Y311865D03*
X838220Y459562D03*
X828009Y587913D03*
X829420Y758422D03*
X841997Y773085D03*
X829352Y1565293D03*
Y1562293D03*
Y1559293D03*
Y1568293D03*
X832352D03*
Y1565293D03*
Y1559293D03*
Y1562293D03*
X835352Y1568293D03*
Y1565293D03*
Y1559293D03*
Y1562293D03*
X838352Y1568293D03*
Y1565293D03*
Y1559293D03*
Y1562293D03*
X841352Y1568293D03*
Y1565293D03*
Y1559293D03*
Y1562293D03*
X829352Y1574293D03*
Y1571293D03*
X832352D03*
Y1574293D03*
X835352Y1571293D03*
Y1574293D03*
X838352Y1571293D03*
Y1574293D03*
X841352Y1571293D03*
Y1574293D03*
X832208Y1731911D03*
X845095Y49388D03*
X858629Y60293D03*
X854577Y99651D03*
X854200Y138562D03*
X860050Y215310D03*
X847580Y232222D03*
X850610Y444352D03*
X851606Y447927D03*
X854620Y1242125D03*
X852208Y1731911D03*
X865095Y49388D03*
X876124Y66072D03*
Y86072D03*
Y106072D03*
Y126072D03*
X871145Y163862D03*
X871890Y196740D03*
X875543Y266447D03*
Y269347D03*
X868113Y409372D03*
X863415Y445829D03*
X868110Y499142D03*
X865290Y499032D03*
X868352Y1568293D03*
Y1565293D03*
Y1559293D03*
Y1562293D03*
X865352Y1568293D03*
Y1565293D03*
Y1559293D03*
Y1562293D03*
X874352D03*
Y1559293D03*
Y1565293D03*
Y1568293D03*
X871352D03*
Y1565293D03*
Y1559293D03*
Y1562293D03*
X868352Y1574293D03*
Y1571293D03*
X865352Y1574293D03*
Y1571293D03*
X874352Y1574293D03*
Y1571293D03*
X871352D03*
Y1574293D03*
X872208Y1731911D03*
X878327Y183169D03*
X876695Y171362D03*
Y176862D03*
X878220Y187449D03*
X888929Y209223D03*
X891620Y209662D03*
X888929Y206723D03*
X891620Y207162D03*
X879100Y912608D03*
X880102Y923235D03*
X883352Y1562293D03*
Y1559293D03*
Y1565293D03*
Y1568293D03*
X880352Y1562293D03*
Y1559293D03*
Y1565293D03*
Y1568293D03*
X877352Y1562293D03*
Y1559293D03*
Y1565293D03*
Y1568293D03*
X883352Y1574293D03*
Y1571293D03*
X880352Y1574293D03*
Y1571293D03*
X877352Y1574293D03*
Y1571293D03*
X892208Y1731911D03*
X896620Y209662D03*
X894120D03*
Y207162D03*
X896620D03*
X902350Y208294D03*
X907470Y211980D03*
X902350Y204894D03*
X907470Y215380D03*
X902350Y219068D03*
X907470Y226154D03*
X902350Y222468D03*
X907470Y229554D03*
X894965Y917422D03*
X907352Y1568293D03*
Y1565293D03*
Y1559293D03*
Y1562293D03*
Y1574293D03*
Y1571293D03*
X927034Y445594D03*
X921757Y962082D03*
X910352Y1568293D03*
Y1565293D03*
Y1559293D03*
Y1562293D03*
X922352D03*
Y1559293D03*
Y1565293D03*
Y1568293D03*
X919352Y1562293D03*
Y1559293D03*
Y1565293D03*
Y1568293D03*
X916352Y1562293D03*
Y1559293D03*
Y1565293D03*
Y1568293D03*
X913352D03*
Y1565293D03*
Y1559293D03*
Y1562293D03*
X910352Y1574293D03*
Y1571293D03*
X922352Y1574293D03*
Y1571293D03*
X919352Y1574293D03*
Y1571293D03*
X916352Y1574293D03*
Y1571293D03*
X913352D03*
Y1574293D03*
X912208Y1731911D03*
X938160Y173389D03*
X935550Y173329D03*
X940720Y173389D03*
X938160Y176389D03*
X935550Y176329D03*
X940720Y176389D03*
X935770Y191419D03*
X926823Y962082D03*
X940170Y962842D03*
X925352Y1562293D03*
Y1559293D03*
Y1565293D03*
Y1568293D03*
Y1574293D03*
Y1571293D03*
X932208Y1731911D03*
X945720Y173389D03*
X943220D03*
X945720Y176389D03*
X943220D03*
X948400Y176499D03*
X957020Y193299D03*
Y264862D03*
X956487Y394831D03*
X944170Y962842D03*
X946865Y974077D03*
X953235Y972642D03*
X946938Y991162D03*
X951560Y997422D03*
X956980Y1536260D03*
X953980D03*
X950980D03*
X947980D03*
X944980D03*
Y1551260D03*
X947980D03*
X950980D03*
X953980D03*
X956980D03*
X944980Y1548260D03*
X947980D03*
X950980D03*
X953980D03*
X956980D03*
X944980Y1545260D03*
X947980D03*
X950980D03*
X953980D03*
X956980D03*
X944980Y1542260D03*
X947980D03*
X950980D03*
X953980D03*
X956980D03*
Y1539260D03*
X953980D03*
X950980D03*
X947980D03*
X944980D03*
Y1554260D03*
X947980D03*
X950980D03*
X953980D03*
X956980D03*
X956022Y1620730D03*
X953022D03*
Y1632730D03*
X956022D03*
Y1629730D03*
X953022D03*
X956022Y1626730D03*
X953022D03*
Y1623730D03*
X956022D03*
X952208Y1731911D03*
X962604Y165313D03*
X962458Y162398D03*
X965150Y193412D03*
X966720Y198099D03*
X970720D03*
X961120Y193299D03*
X960020Y264862D03*
X963020D03*
X972220Y386251D03*
X961320Y476242D03*
X970788Y501230D03*
X964347Y501262D03*
X969351Y512416D03*
X963610Y981292D03*
X959535Y990477D03*
X969000Y1536262D03*
X971700D03*
X969000Y1548262D03*
X971700D03*
X969000Y1545262D03*
X971700D03*
X969000Y1551262D03*
X971700D03*
Y1542262D03*
X969000D03*
X971700Y1539262D03*
X969000D03*
X965904Y1554364D03*
X971700Y1554262D03*
X962022Y1620730D03*
X959022D03*
Y1632730D03*
X962022D03*
Y1629730D03*
X959022D03*
X962022Y1626730D03*
X959022D03*
Y1623730D03*
X962022D03*
X968022Y1620730D03*
X965022D03*
X971022D03*
X965022Y1632730D03*
X968022Y1629730D03*
X965022D03*
X968022Y1626730D03*
X965022D03*
Y1623730D03*
X968022D03*
X971022Y1626730D03*
Y1623730D03*
Y1629730D03*
Y1632730D03*
X968022D03*
X972208Y1731911D03*
X980899Y-13200D03*
Y-9800D03*
Y20200D03*
Y16800D03*
X981445Y181058D03*
X987320Y194599D03*
Y198099D03*
Y201599D03*
X977220Y201399D03*
X986020Y191099D03*
X987259Y276094D03*
X974791Y339990D03*
X986955Y391939D03*
X980720Y512362D03*
X979373Y1342724D03*
X974700Y1536262D03*
X980400D03*
X977700D03*
X974700Y1548262D03*
Y1545262D03*
Y1551262D03*
X980400Y1548262D03*
X977700D03*
X980400Y1545262D03*
X977700D03*
X980400Y1551262D03*
X977700D03*
Y1542262D03*
X980400D03*
X974700D03*
X977700Y1539262D03*
X980400D03*
X974700D03*
Y1554262D03*
X980400D03*
X977700D03*
X989270Y1554364D03*
X987662Y1620870D03*
Y1629870D03*
Y1626870D03*
Y1623870D03*
Y1632870D03*
X1002735Y153943D03*
X999735D03*
X999915Y180548D03*
X996415D03*
X992505Y180553D03*
X993205Y174053D03*
X993305Y170953D03*
X990220Y195699D03*
Y199199D03*
X990495Y212923D03*
X990220Y202699D03*
X1002500Y266862D03*
X998500Y269862D03*
X1002500D03*
X1001065Y304622D03*
Y307122D03*
Y309622D03*
X1006201Y370004D03*
X1005720Y498862D03*
X1003220Y512862D03*
X1005520Y510932D03*
X996320Y1280683D03*
Y1284062D03*
X995066Y1536262D03*
X992466D03*
X1001066D03*
X1003766D03*
X998066D03*
X995066Y1551262D03*
X992466D03*
X995066Y1545262D03*
X992466D03*
X995066Y1548262D03*
X992466D03*
X1001066Y1551262D03*
X1003766D03*
X1001066Y1545262D03*
X1003766D03*
X1001066Y1548262D03*
X1003766D03*
X998066Y1551262D03*
Y1545262D03*
Y1548262D03*
Y1542262D03*
X1003766D03*
X1001066D03*
X992466D03*
X995066D03*
X998066Y1539262D03*
X1003766D03*
X1001066D03*
X992466D03*
X995066D03*
Y1554262D03*
X1001066D03*
X1003766D03*
X998066D03*
X990662Y1620870D03*
X993662D03*
X996662D03*
X999662D03*
X1002662D03*
Y1626870D03*
Y1623870D03*
X996662Y1629870D03*
X999662Y1626870D03*
X996662D03*
Y1623870D03*
X999662D03*
X996662Y1632870D03*
X993662Y1629870D03*
X990662D03*
X993662Y1626870D03*
X990662D03*
Y1623870D03*
X993662D03*
X990662Y1632870D03*
X993662D03*
X1001810Y1662700D03*
Y1665200D03*
X992208Y1731911D03*
X1006435Y172843D03*
X1009895Y192359D03*
X1008067Y194356D03*
X1018000Y266862D03*
X1022002Y267342D03*
X1010500Y266862D03*
X1006500D03*
X1014500D03*
Y269862D03*
X1018000D03*
X1022002Y270142D03*
X1006500Y269862D03*
X1010500D03*
X1010828Y304822D03*
Y307322D03*
Y309822D03*
X1021419Y305704D03*
X1006710Y372931D03*
X1021612Y1536262D03*
X1016012D03*
X1018612D03*
Y1551262D03*
X1016012D03*
X1018612Y1545262D03*
X1016012D03*
X1018612Y1548262D03*
X1016012D03*
X1021612Y1551262D03*
Y1545262D03*
Y1548262D03*
X1018612Y1542262D03*
X1016012D03*
X1021612D03*
Y1539262D03*
X1016012D03*
X1018612D03*
Y1554262D03*
X1021612D03*
X1012636Y1554364D03*
X1019252Y1620870D03*
X1022252D03*
Y1623870D03*
Y1626870D03*
X1019252Y1623870D03*
Y1626870D03*
X1019910Y1662700D03*
Y1665200D03*
X1012208Y1731911D03*
X1032894Y155185D03*
X1031502Y267342D03*
X1028202D03*
X1025102D03*
X1033133Y272564D03*
X1031502Y270142D03*
X1029833Y272564D03*
X1026733D03*
X1023633D03*
X1028202Y270142D03*
X1025102D03*
X1036915Y290969D03*
X1035920Y420062D03*
Y417462D03*
X1027212Y1536262D03*
X1024612D03*
Y1551262D03*
X1027212D03*
X1024612Y1545262D03*
X1027212D03*
X1024612Y1548262D03*
X1027212D03*
X1024612Y1542262D03*
X1027212D03*
Y1539262D03*
X1024612D03*
Y1554262D03*
X1027212D03*
X1036002Y1554364D03*
X1025252Y1620870D03*
X1034252Y1623870D03*
Y1626870D03*
X1031252Y1623870D03*
Y1626870D03*
X1025252Y1623870D03*
X1028252D03*
Y1626870D03*
X1025252D03*
X1031252Y1620870D03*
X1034252D03*
X1028252D03*
X1023580Y1662700D03*
Y1665200D03*
X1027370Y1662700D03*
Y1665200D03*
X1032208Y1731911D03*
X1053428Y261118D03*
X1040924Y286073D03*
X1043720Y363462D03*
X1044120Y366362D03*
X1041420Y443962D03*
X1043920D03*
X1041798Y1536262D03*
X1047798D03*
X1050498D03*
X1044798D03*
X1039298D03*
X1041798Y1551262D03*
X1039298D03*
X1041798Y1545262D03*
X1039298D03*
X1041798Y1548262D03*
X1039298D03*
X1047798Y1551262D03*
X1050498D03*
X1047798Y1545262D03*
X1050498D03*
X1047798Y1548262D03*
X1050498D03*
X1044798Y1551262D03*
Y1545262D03*
Y1548262D03*
X1039298Y1542262D03*
X1044798D03*
X1050498D03*
X1047798D03*
X1041798D03*
X1044798Y1539262D03*
X1050498D03*
X1047798D03*
X1039298D03*
X1041798D03*
Y1554262D03*
X1047798D03*
X1050498D03*
X1044798D03*
X1050721Y1633043D03*
X1053721D03*
Y1624043D03*
Y1627043D03*
Y1630043D03*
X1050721Y1624043D03*
Y1627043D03*
Y1630043D03*
X1053721Y1621043D03*
X1050721D03*
X1044850Y1665050D03*
Y1662550D03*
X1052208Y1731911D03*
X1068093Y265503D03*
X1058428Y261118D03*
X1055928D03*
X1067618Y273800D03*
X1070718Y273700D03*
X1067718Y288500D03*
X1070618D03*
X1067718Y285600D03*
X1070618D03*
X1066462Y1520088D03*
X1065164Y1536262D03*
X1062464D03*
X1071164D03*
X1068164D03*
X1065164Y1551262D03*
X1062464D03*
X1065164Y1545262D03*
X1062464D03*
X1065164Y1548262D03*
X1062464D03*
X1071164Y1551262D03*
Y1545262D03*
Y1548262D03*
X1068164Y1551262D03*
Y1545262D03*
Y1548262D03*
Y1542262D03*
X1071164D03*
X1062464D03*
X1065164D03*
X1068164Y1539262D03*
X1071164D03*
X1062464D03*
X1065164D03*
Y1554262D03*
X1071164D03*
X1068164D03*
X1059368Y1554364D03*
X1065721Y1633043D03*
X1068721D03*
Y1624043D03*
Y1627043D03*
Y1630043D03*
X1065721Y1624043D03*
Y1627043D03*
Y1630043D03*
X1062721Y1633043D03*
Y1624043D03*
Y1627043D03*
Y1630043D03*
X1056721Y1633043D03*
X1059721D03*
X1056721Y1624043D03*
X1059721D03*
Y1627043D03*
X1056721D03*
X1059721Y1630043D03*
X1056721D03*
X1068721Y1621043D03*
X1065721D03*
X1062721D03*
X1059721D03*
X1056721D03*
X1079114Y75775D03*
X1078545Y435637D03*
X1081045D03*
X1082220Y522362D03*
X1085720Y522422D03*
X1073864Y1536262D03*
X1085830D03*
X1073864Y1551262D03*
Y1545262D03*
Y1548262D03*
X1085830Y1551262D03*
Y1545262D03*
Y1548262D03*
Y1542262D03*
X1073864D03*
X1085830Y1539262D03*
X1073864D03*
Y1554262D03*
X1082734Y1554364D03*
X1072208Y1731911D03*
X1094644Y67992D03*
X1099030Y245140D03*
X1095820Y420762D03*
X1088530Y1536262D03*
X1091530D03*
X1088530Y1551262D03*
Y1545262D03*
Y1548262D03*
X1094530Y1551262D03*
X1097230D03*
X1094530Y1545262D03*
X1097230D03*
X1094530Y1548262D03*
X1097230D03*
X1091530Y1551262D03*
Y1545262D03*
Y1548262D03*
Y1542262D03*
X1097230D03*
X1094530D03*
X1088530D03*
X1091530Y1539262D03*
X1094530D03*
X1088530D03*
X1104750Y1549346D03*
X1088530Y1554262D03*
X1094530D03*
X1097230D03*
X1091530D03*
X1099901Y1633203D03*
Y1624203D03*
Y1627203D03*
Y1630203D03*
Y1621203D03*
X1093901Y1633203D03*
X1096901D03*
Y1624203D03*
Y1627203D03*
Y1630203D03*
X1093901Y1624203D03*
Y1627203D03*
Y1630203D03*
X1090901Y1633203D03*
X1087901D03*
X1090901Y1624203D03*
X1087901D03*
Y1627203D03*
X1090901D03*
X1087901Y1630203D03*
X1090901D03*
X1096901Y1621203D03*
X1093901D03*
X1087901D03*
X1090901D03*
X1088790Y1641830D03*
X1094225Y1671710D03*
X1091880Y1673720D03*
X1092072Y1734244D03*
X1110754Y60028D03*
X1118486Y208942D03*
X1117820Y456132D03*
X1118110Y1398010D03*
X1115853Y1426342D03*
Y1435532D03*
X1117574Y1448604D03*
X1117407Y1628495D03*
X1106480Y1641275D03*
X1113110Y1666460D03*
X1112130Y1711600D03*
X1112252Y1706170D03*
X1112200Y1709000D03*
X1114150Y1715726D03*
X1110663Y1719189D03*
X1119200Y1727200D03*
X1119300Y1724100D03*
X1111866Y1737108D03*
X1124858Y197309D03*
X1128485Y198159D03*
X1122059Y305673D03*
X1124985Y302578D03*
X1127402Y456174D03*
X1127788Y1397126D03*
X1135709Y1397119D03*
X1133209D03*
X1123674Y1414936D03*
X1121174D03*
X1123674Y1417536D03*
Y1420136D03*
X1121174Y1417536D03*
Y1420136D03*
X1123674Y1422736D03*
X1121174D03*
X1136004Y1447858D03*
X1126117Y1450504D03*
X1131866Y1737108D03*
X1141957Y227277D03*
X1144457D03*
X1139457D03*
X1146118Y1397126D03*
X1138209Y1397119D03*
X1150843Y1415126D03*
X1148243D03*
X1150843Y1417726D03*
X1148243D03*
X1150732Y1420326D03*
X1137311Y1445191D03*
X1145108Y1476732D03*
X1138430Y1524150D03*
X1153465Y1550301D03*
X1149528D03*
X1145410Y1540640D03*
X1143060Y1538380D03*
X1141654Y1550301D03*
X1141690Y1552920D03*
X1152187Y1574738D03*
Y1590738D03*
X1155703Y73679D03*
X1165931Y1397126D03*
X1154714Y1398295D03*
X1157786Y1398252D03*
X1153913Y1420606D03*
Y1415406D03*
Y1418006D03*
X1159124D03*
Y1420606D03*
Y1415406D03*
X1161724D03*
Y1420606D03*
Y1418006D03*
X1156524Y1415406D03*
Y1420606D03*
Y1418006D03*
X1153913Y1423206D03*
X1159124D03*
X1161724D03*
X1156524D03*
X1155964Y1440864D03*
X1164260Y1450423D03*
X1158954Y1450274D03*
X1167245Y1524187D03*
X1159371D03*
X1155433D03*
X1157402Y1550301D03*
X1161339D03*
X1155187Y1574738D03*
Y1590738D03*
X1158325Y1642600D03*
X1174120Y57111D03*
X1175926Y69151D03*
X1181420Y157962D03*
X1181700Y186962D03*
X1173314Y176452D03*
X1184510Y188962D03*
X1181470Y208802D03*
X1181450Y306052D03*
X1181300Y584762D03*
X1184661Y1397126D03*
X1171752Y1397119D03*
X1176752D03*
X1174252D03*
X1174147Y1447858D03*
X1171342Y1445650D03*
X1175454Y1445191D03*
X1183410Y1594450D03*
X1183440Y1591640D03*
X1184200Y1599900D03*
X1183320Y1597080D03*
X1174550Y1615630D03*
X1178250Y1609100D03*
X1184200Y1602700D03*
X1201158Y57130D03*
X1185420Y153762D03*
X1200830Y206002D03*
X1188600Y225962D03*
X1194840Y236592D03*
X1186280Y298972D03*
X1189135Y1397529D03*
X1187736Y1420387D03*
X1188986Y1415287D03*
Y1417887D03*
X1186386Y1415287D03*
Y1417887D03*
X1191486Y1415287D03*
Y1417887D03*
X1190444Y1420384D03*
X1194750Y1424672D03*
X1191930Y1424647D03*
X1187720Y1517688D03*
X1187830Y1522188D03*
X1198546Y1520188D03*
X1187830Y1526688D03*
X1198546Y1524688D03*
X1198436Y1529362D03*
X1187720Y1531862D03*
Y1563182D03*
X1194510Y1563076D03*
X1191866Y1737108D03*
X1216176Y56742D03*
X1214415Y153962D03*
X1213720Y200309D03*
X1219060Y213312D03*
X1210900Y265300D03*
X1204475Y350684D03*
X1215896Y756942D03*
X1217210Y1684520D03*
X1211866Y1737108D03*
X1222890Y157002D03*
X1223180Y210552D03*
X1219220Y247148D03*
X1219060Y757272D03*
X1231866Y1737108D03*
X1240728Y136198D03*
X1236410Y201462D03*
X1240500Y248332D03*
Y244332D03*
X1261227Y52061D03*
X1258727D03*
X1264663Y158946D03*
X1254994Y157382D03*
X1264874Y217462D03*
X1259703Y209808D03*
X1266518Y237042D03*
X1264854Y253996D03*
Y256496D03*
X1258883Y280558D03*
X1253586Y1334649D03*
X1257586D03*
X1251866Y1737108D03*
X1278949Y123567D03*
X1278183Y201262D03*
X1275493Y193962D03*
X1273093Y213962D03*
X1275727Y209597D03*
X1279493Y248662D03*
X1277771Y255173D03*
X1273754Y256504D03*
X1276800Y276562D03*
X1279788Y1304042D03*
X1280135Y1340002D03*
Y1337402D03*
X1272707Y1334865D03*
X1280135Y1345202D03*
Y1342602D03*
X1280312Y1365689D03*
X1275856Y1358098D03*
X1271990Y1358079D03*
X1271866Y1737108D03*
X1298640Y93062D03*
X1292880Y93162D03*
X1291500Y312862D03*
Y315362D03*
X1291420Y320662D03*
Y318162D03*
X1296719Y1290197D03*
X1299169Y1295467D03*
Y1297967D03*
X1296569D03*
Y1295467D03*
Y1292967D03*
X1299169D03*
X1296581Y1300474D03*
X1299181D03*
X1296576Y1303298D03*
X1299176D03*
X1295150Y1323217D03*
X1298150D03*
X1291010Y1323307D03*
X1288010D03*
X1283280Y1372301D03*
X1293887Y1370043D03*
X1294477Y1372651D03*
X1291866Y1737108D03*
X1311960Y49672D03*
X1311260Y83032D03*
X1310906Y97807D03*
X1314406Y97756D03*
X1314059Y93877D03*
X1300990Y121812D03*
X1307677Y322996D03*
X1311077D03*
X1315169Y1274887D03*
X1315289Y1269717D03*
X1315229Y1272287D03*
X1304149Y1291317D03*
X1301889Y1284987D03*
X1301829Y1290167D03*
X1301859Y1287587D03*
X1304299Y1280967D03*
X1304269Y1283567D03*
X1304239Y1286147D03*
X1304209Y1288747D03*
X1315176Y1280218D03*
X1315181Y1277594D03*
X1299319Y1290197D03*
X1299349Y1287617D03*
X1301686Y1303268D03*
X1304196Y1299248D03*
X1304189Y1293917D03*
X1304201Y1296624D03*
X1301679Y1292937D03*
Y1295437D03*
Y1297937D03*
X1301691Y1300444D03*
X1311952Y1321945D03*
X1304066Y1323578D03*
X1307656Y1337104D03*
X1305056D03*
X1307656Y1326704D03*
X1305056D03*
X1307656Y1334504D03*
Y1329304D03*
Y1331904D03*
X1305056Y1334504D03*
Y1329304D03*
Y1331904D03*
Y1339704D03*
X1312488Y1348353D03*
X1315058Y1349488D03*
X1311866Y1737108D03*
X1318609Y49388D03*
X1322906Y94212D03*
X1319968Y98266D03*
X1329891Y99455D03*
X1329646Y104954D03*
X1322906Y109733D03*
X1328393Y264262D03*
X1319618Y318073D03*
X1325080Y323902D03*
X1316218Y318073D03*
X1328480Y323902D03*
X1331519Y1262027D03*
X1331459Y1264597D03*
X1331399Y1267197D03*
X1317889Y1267147D03*
X1320399Y1267117D03*
X1317883Y1269978D03*
X1317895Y1272485D03*
X1320393Y1269948D03*
X1320405Y1272455D03*
X1331177Y1269933D03*
Y1272433D03*
X1317895Y1274985D03*
X1320405Y1274955D03*
X1331177Y1274933D03*
X1331166Y1280248D03*
X1317746D03*
X1320256Y1280218D03*
X1317895Y1277485D03*
X1320405Y1277455D03*
X1331189Y1277440D03*
X1324945Y1346877D03*
X1327196Y1349068D03*
X1338609Y49388D03*
X1346720Y82912D03*
X1336549Y105970D03*
X1344631Y127244D03*
X1344684Y280259D03*
X1335145Y332616D03*
X1341431Y322693D03*
X1331745Y332616D03*
X1338031Y322693D03*
X1345424Y328981D03*
X1344720Y423162D03*
X1337220D03*
X1342220D03*
X1339720D03*
X1347419Y1259257D03*
X1347379Y1256687D03*
X1336269Y1274957D03*
X1333969Y1264567D03*
X1334029Y1261997D03*
X1333909Y1267167D03*
X1336339Y1269777D03*
X1336279Y1272347D03*
X1347359Y1261857D03*
X1347371Y1264564D03*
X1336519Y1264627D03*
X1336579Y1262057D03*
X1347366Y1267188D03*
X1336459Y1267227D03*
X1333687Y1269903D03*
Y1272403D03*
Y1274903D03*
X1333676Y1280218D03*
X1336261Y1277654D03*
X1333699Y1277410D03*
X1339784Y1306506D03*
X1337184D03*
X1344080Y1305919D03*
X1337663Y1301001D03*
X1343968Y1300579D03*
X1340663Y1301001D03*
X1344080Y1308519D03*
X1337184Y1309106D03*
X1339784D03*
X1338534Y1319406D03*
X1339784Y1316906D03*
Y1314306D03*
Y1311706D03*
X1337184Y1314306D03*
Y1316906D03*
Y1311706D03*
X1347015Y1335876D03*
X1343631Y1332568D03*
X1331866Y1737108D03*
X1350550Y101632D03*
X1353394Y131812D03*
X1349220Y140362D03*
X1348084Y280259D03*
X1358624Y284644D03*
X1355224D03*
X1348824Y328981D03*
X1358371Y332275D03*
X1361771D03*
X1355200Y337843D03*
X1351800D03*
X1352474Y1256866D03*
X1349964Y1256896D03*
X1352486Y1259373D03*
X1349976Y1259403D03*
X1363258Y1256851D03*
Y1259351D03*
X1349876Y1267158D03*
X1352426Y1267218D03*
X1363266Y1267188D03*
X1349976Y1261903D03*
X1352486Y1261873D03*
Y1264373D03*
X1349976Y1264403D03*
X1363258Y1261851D03*
X1363270Y1264358D03*
X1353982Y1287048D03*
X1362382D03*
X1359382D03*
X1350982D03*
X1356983Y1334095D03*
X1359516Y1334058D03*
X1355357Y1396020D03*
X1364860Y1455172D03*
X1362410Y1445272D03*
X1351866Y1737108D03*
X1380522Y260236D03*
Y263636D03*
X1368524Y282744D03*
X1365124D03*
X1378306Y657608D03*
X1374668Y659708D03*
X1378306Y669608D03*
X1374668Y671708D03*
Y683708D03*
X1378306Y681608D03*
X1374668Y695708D03*
X1378306Y693608D03*
Y705608D03*
X1374668Y707708D03*
Y719708D03*
X1378306Y717608D03*
X1379579Y1259317D03*
X1368379Y1259287D03*
X1379639Y1256747D03*
X1368439Y1256717D03*
X1365768Y1256821D03*
Y1259321D03*
X1365776Y1267158D03*
X1368326Y1267218D03*
X1379519Y1261917D03*
X1379531Y1264624D03*
X1379526Y1267248D03*
X1368361Y1264594D03*
X1368369Y1261897D03*
X1365768Y1261821D03*
X1365780Y1264328D03*
X1375463Y1287048D03*
X1372463D03*
X1370662Y1305980D03*
X1371912Y1303480D03*
X1376208Y1305919D03*
Y1303319D03*
X1371912Y1300880D03*
X1376208Y1300719D03*
Y1295586D03*
X1371912Y1295747D03*
Y1298280D03*
X1376208Y1298119D03*
X1369312Y1303480D03*
Y1300880D03*
Y1295747D03*
Y1298280D03*
X1376208Y1308519D03*
X1379271Y1335963D03*
X1375814Y1332653D03*
X1377054Y1394028D03*
X1376666Y1402778D03*
X1376686Y1399758D03*
X1370577Y1421899D03*
X1377060Y1411231D03*
X1367436Y1414778D03*
X1371960Y1436172D03*
X1365235Y1428637D03*
X1370250Y1433715D03*
X1367620Y1431472D03*
X1367170Y1453142D03*
X1368842Y1449261D03*
X1364800Y1449231D03*
X1371866Y1737108D03*
X1384002Y197668D03*
X1389256D03*
X1380602D03*
X1392656D03*
X1380638Y245694D03*
X1386630Y238651D03*
X1380638Y249094D03*
X1386630Y242051D03*
X1388754Y253803D03*
Y257203D03*
X1386273Y268670D03*
Y272070D03*
X1393206Y664708D03*
X1389568Y662608D03*
X1393206Y679208D03*
X1389568Y677108D03*
X1393206Y693708D03*
X1389568Y691608D03*
Y706108D03*
X1393206Y708208D03*
X1393199Y722708D03*
X1389561Y720608D03*
X1385338Y735098D03*
X1388976Y737198D03*
X1384652Y1256866D03*
X1382142Y1256896D03*
X1384664Y1259373D03*
X1382154Y1259403D03*
X1395436Y1256851D03*
Y1259351D03*
X1384586Y1267278D03*
X1395426Y1267188D03*
X1382036Y1267218D03*
X1382154Y1261903D03*
X1384664Y1261873D03*
Y1264373D03*
X1382154Y1264403D03*
X1395436Y1261851D03*
X1395448Y1264358D03*
X1390758Y1333473D03*
X1392076Y1335658D03*
X1388813Y1393160D03*
X1396115Y1405289D03*
Y1412789D03*
X1396615Y1420289D03*
X1387068Y1413991D03*
X1384695Y1425047D03*
X1382600Y1563480D03*
X1384840Y1565640D03*
X1386790Y1563610D03*
X1393000Y1590300D03*
X1391866Y1737108D03*
X1398006Y197668D03*
X1406786D03*
X1401406D03*
X1410186D03*
X1411909Y1259257D03*
X1400599Y1256717D03*
X1411969Y1256687D03*
X1397946Y1256821D03*
Y1259321D03*
X1400539Y1259287D03*
X1400521Y1264594D03*
X1400529Y1261897D03*
X1397936Y1267158D03*
X1400486Y1267218D03*
X1411849Y1261857D03*
X1411861Y1264564D03*
X1411856Y1267188D03*
X1397946Y1261821D03*
X1397958Y1264328D03*
X1410819Y1287198D03*
X1407819D03*
X1399419D03*
X1402419D03*
X1404040Y1303480D03*
X1408336Y1305919D03*
Y1303319D03*
X1404040Y1300880D03*
X1408336Y1300719D03*
Y1295586D03*
X1404040Y1295747D03*
Y1298280D03*
X1408336Y1298119D03*
X1401440Y1303480D03*
X1402790Y1305980D03*
X1401440Y1300880D03*
Y1295747D03*
Y1298280D03*
X1408336Y1308519D03*
X1411124Y1335924D03*
X1407719Y1332560D03*
X1403615Y1405289D03*
Y1420289D03*
X1405876Y1453298D03*
X1400220Y1518862D03*
X1409248Y1528862D03*
X1407440Y1557552D03*
X1402536Y1576097D03*
X1396900Y1642100D03*
X1411866Y1737108D03*
X1424119Y1161520D03*
X1426619D03*
X1424119Y1153369D03*
X1426619D03*
Y1169570D03*
X1424119D03*
X1416999Y1256866D03*
X1414489Y1256896D03*
X1417011Y1259373D03*
X1414501Y1259403D03*
X1427783Y1256851D03*
Y1259351D03*
X1414366Y1267158D03*
X1416916Y1267218D03*
X1427786Y1267158D03*
X1414501Y1261903D03*
X1417011Y1261873D03*
Y1264373D03*
X1414501Y1264403D03*
X1427783Y1261851D03*
X1427795Y1264358D03*
X1421294Y1334095D03*
X1423656Y1335468D03*
X1419995Y1397492D03*
X1415620Y1396652D03*
X1426872Y1405811D03*
X1421480Y1415731D03*
X1429345Y1433695D03*
X1419746Y1435932D03*
X1427349Y1442776D03*
X1414264Y1439494D03*
X1419256Y1440258D03*
X1423829Y1442776D03*
X1438609Y49388D03*
X1436060Y220018D03*
X1432660D03*
X1436270Y312592D03*
X1436335Y309407D03*
X1436320Y305862D03*
Y303362D03*
X1436050Y321352D03*
X1436120Y318272D03*
X1436232Y344176D03*
X1433418Y729104D03*
X1444099Y1259397D03*
X1432899Y1259257D03*
X1444159Y1256827D03*
X1432959Y1256687D03*
X1430293Y1256821D03*
Y1259321D03*
X1444051Y1264704D03*
X1444039Y1261997D03*
X1444046Y1267328D03*
X1432889Y1261867D03*
X1432881Y1264564D03*
X1432846Y1267188D03*
X1430296Y1267128D03*
X1430293Y1261821D03*
X1430305Y1264328D03*
X1437258Y1287198D03*
X1445106Y1287158D03*
X1440258Y1287198D03*
X1437182Y1298991D03*
X1434582Y1304191D03*
Y1306791D03*
Y1301591D03*
Y1296458D03*
Y1298991D03*
X1440507Y1305430D03*
Y1302830D03*
Y1300230D03*
X1440536Y1296455D03*
X1440464Y1308519D03*
X1437182Y1304191D03*
Y1306791D03*
Y1301591D03*
Y1296458D03*
X1443785Y1335981D03*
X1440879Y1333085D03*
X1439155Y1399064D03*
X1431717Y1420625D03*
Y1417125D03*
Y1409125D03*
X1431829Y1412370D03*
X1443325Y1410068D03*
X1431717Y1427632D03*
Y1424125D03*
X1430204Y1452014D03*
X1444468Y1570610D03*
X1443617Y1638212D03*
X1442573Y1649862D03*
X1438320Y1668292D03*
X1438220Y1673955D03*
X1431866Y1737108D03*
X1458609Y49388D03*
X1460849Y343327D03*
X1457176Y656992D03*
X1460814Y654892D03*
Y666892D03*
X1457176Y668992D03*
X1460814Y678892D03*
X1457176Y680992D03*
X1460814Y690892D03*
X1457176Y704992D03*
Y692992D03*
X1460814Y702892D03*
X1457176Y716992D03*
X1460814Y714892D03*
X1456237Y726945D03*
X1457620Y736195D03*
X1457714Y741622D03*
X1447149Y1161569D03*
X1449649D03*
X1447299Y1153369D03*
X1449799D03*
X1447149Y1170069D03*
X1449649D03*
X1449176Y1256866D03*
X1446666Y1256896D03*
X1449188Y1259373D03*
X1446678Y1259403D03*
X1459960Y1259351D03*
Y1256851D03*
X1449106Y1267358D03*
X1459886Y1267218D03*
X1446556Y1267298D03*
X1446678Y1261903D03*
X1449188Y1261873D03*
Y1264373D03*
X1446678Y1264403D03*
X1459960Y1261851D03*
X1459972Y1264358D03*
X1453366Y1287198D03*
X1458766D03*
X1461766D03*
X1450366D03*
X1453303Y1334095D03*
X1455436Y1335598D03*
X1461377Y1417844D03*
X1454829Y1439732D03*
X1459135Y1439627D03*
X1459136Y1442241D03*
X1456030Y1590302D03*
X1451500Y1612800D03*
X1454167Y1638302D03*
X1459127D03*
X1448507Y1638212D03*
X1462000Y153362D03*
X1474660Y252878D03*
X1471690Y259862D03*
X1463330Y264060D03*
X1465171Y647132D03*
X1469020Y647102D03*
X1472076Y657392D03*
Y671892D03*
X1475714Y659492D03*
Y673992D03*
X1472076Y686392D03*
X1475714Y688492D03*
X1472076Y700892D03*
X1475714Y702992D03*
X1472076Y715392D03*
X1475714Y717492D03*
X1468876Y728392D03*
X1472514Y730492D03*
X1464999Y1259317D03*
X1476369Y1259237D03*
X1465059Y1256747D03*
X1462470Y1259321D03*
Y1256821D03*
X1476291Y1275224D03*
X1464946Y1267248D03*
X1464989Y1261927D03*
X1464981Y1264624D03*
X1476339Y1264467D03*
Y1267037D03*
X1476309Y1261807D03*
X1476279Y1269637D03*
X1476291Y1272344D03*
X1462396Y1267188D03*
X1462470Y1261821D03*
X1462482Y1264328D03*
X1476291Y1278104D03*
X1472592Y1306345D03*
X1474180Y1300407D03*
X1471180D03*
X1465696Y1303480D03*
X1467046Y1305980D03*
X1468296Y1303480D03*
X1465696Y1300880D03*
X1468296D03*
X1472361Y1322440D03*
X1472592Y1308945D03*
Y1316745D03*
Y1314145D03*
Y1311545D03*
X1475599Y1349468D03*
X1475959Y1385027D03*
X1476000Y1393027D03*
X1465747Y1401405D03*
X1466448Y1421499D03*
X1475935Y1439627D03*
X1475936Y1442241D03*
X1467550Y1439642D03*
X1467536Y1442241D03*
X1478320Y1522962D03*
X1463767Y1638302D03*
X1478609Y49388D03*
X1493120Y240412D03*
X1487958Y236062D03*
X1485320Y260362D03*
X1493289Y280027D03*
X1481539Y1259377D03*
X1478999Y1259257D03*
X1481479Y1261947D03*
X1481419Y1264547D03*
X1481431Y1267254D03*
X1478939Y1261827D03*
X1478879Y1264427D03*
X1478891Y1267134D03*
X1481359Y1271447D03*
X1492039D03*
X1481359Y1274144D03*
X1492091D03*
X1478859Y1271417D03*
Y1274114D03*
X1481361Y1280054D03*
X1492101D03*
X1478821D03*
X1481359Y1277024D03*
X1492091D03*
X1478859Y1276994D03*
X1491840Y1300447D03*
X1485523Y1347521D03*
X1487386Y1349258D03*
X1481155Y1387742D03*
X1481255Y1382042D03*
X1478559Y1385027D03*
X1481159Y1384727D03*
X1481155Y1396342D03*
Y1398942D03*
Y1390342D03*
X1478600Y1393027D03*
X1481107Y1393095D03*
X1479658Y1405397D03*
X1485301Y1409442D03*
X1485274Y1406911D03*
X1485380Y1412202D03*
X1479671Y1410411D03*
Y1412911D03*
Y1407911D03*
X1482201Y1409442D03*
X1482174Y1406911D03*
X1482280Y1412202D03*
X1484395Y1439598D03*
X1484336Y1442241D03*
X1482830Y1525162D03*
X1491866Y1737108D03*
X1498609Y49388D03*
X1497199Y1275667D03*
X1497259Y1273097D03*
X1494629Y1271477D03*
X1494631Y1274144D03*
X1506569Y1285947D03*
X1508819Y1284797D03*
X1506539Y1288557D03*
X1508759Y1287367D03*
X1508699Y1289967D03*
X1494641Y1280054D03*
X1494631Y1277024D03*
X1506551Y1291254D03*
X1497199Y1278277D03*
X1497161Y1280974D03*
X1506689Y1283377D03*
X1494840Y1300447D03*
X1506591Y1297014D03*
Y1294134D03*
X1508711Y1295554D03*
Y1298434D03*
Y1292674D03*
X1499048Y1319946D03*
X1504720Y1329143D03*
X1503786Y1326076D03*
X1504518Y1335982D03*
X1504720Y1342143D03*
Y1344743D03*
X1505116Y1369724D03*
X1518608Y49377D03*
X1513789Y1290037D03*
X1511289Y1287397D03*
X1511199Y1290007D03*
X1513791Y1292704D03*
X1516351D03*
X1513791Y1298464D03*
Y1295584D03*
X1516351D03*
Y1298464D03*
X1511251Y1292704D03*
Y1298464D03*
Y1295584D03*
X1522066Y1312808D03*
X1526066D03*
X1518066D03*
X1515066D03*
X1511066D03*
X1518451Y1369919D03*
X1511866Y1737108D03*
X1529002Y32290D03*
X1544010Y27552D03*
X1536310Y47492D03*
X1529233Y153162D03*
X1539720Y589862D03*
Y581862D03*
X1535052Y1325904D03*
X1532552Y1334504D03*
X1535052D03*
X1529952D03*
X1532552Y1339704D03*
X1529952D03*
X1537652Y1325904D03*
Y1334504D03*
X1532552Y1337104D03*
X1529952D03*
X1538510Y1346392D03*
X1531302Y1342204D03*
X1535892Y1346354D03*
Y1343754D03*
X1538757Y1356355D03*
Y1360855D03*
Y1365355D03*
X1531866Y1737108D03*
X1547768Y3010D03*
X1552960Y124359D03*
X1552720Y589862D03*
Y581862D03*
X1554753Y628860D03*
X1551866Y1737108D03*
X1567768Y3010D03*
X1573246Y306650D03*
X1572396Y309450D03*
X1567547Y755485D03*
X1571920Y762662D03*
X1568490Y758162D03*
X1570374Y760093D03*
X1587768Y3010D03*
X1576589Y300927D03*
X1588314Y592553D03*
X1585714D03*
X1583114D03*
X1590914D03*
X1588254Y595103D03*
X1588284Y597613D03*
X1585654Y595103D03*
X1585684Y597613D03*
X1583084D03*
X1583054Y595103D03*
X1588284Y608655D03*
X1585684D03*
X1583084D03*
X1590854Y595103D03*
X1590884Y597613D03*
Y608655D03*
X1588254Y613715D03*
X1588224Y611205D03*
X1585654Y613715D03*
X1585624Y611205D03*
X1583024D03*
X1583054Y613715D03*
X1590854D03*
X1590824Y611205D03*
X1591368Y628727D03*
X1591428Y626177D03*
X1588928D03*
X1588868Y628727D03*
X1591398Y631237D03*
X1588898D03*
X1591368Y650877D03*
X1591338Y648367D03*
X1591398Y645817D03*
X1588868Y650877D03*
X1588838Y648367D03*
X1588898Y645817D03*
X1591368Y653377D03*
X1588868D03*
X1591448Y657677D03*
X1588948D03*
Y660177D03*
X1591448D03*
X1588968Y665237D03*
X1591468D03*
X1588938Y662727D03*
X1591438D03*
X1588938Y679807D03*
X1588878Y682357D03*
X1588908Y684867D03*
X1591438Y679807D03*
X1591378Y682357D03*
X1591408Y684867D03*
X1591328Y696727D03*
X1591388Y694177D03*
X1588888D03*
X1588828Y696727D03*
X1591358Y699277D03*
X1588858D03*
X1591358Y718837D03*
X1591328Y716327D03*
X1591388Y713777D03*
X1588858Y718837D03*
X1588828Y716327D03*
X1588888Y713777D03*
X1591866Y1737108D03*
X1607768Y3010D03*
X1603747Y192951D03*
X1603530Y202402D03*
X1604240Y227892D03*
Y238242D03*
X1602980Y560002D03*
X1593514Y592553D03*
X1601830Y590685D03*
X1604430D03*
X1607200Y583962D03*
X1593484Y597613D03*
X1593454Y595103D03*
X1593484Y608655D03*
X1593424Y611205D03*
X1593454Y613715D03*
X1601830Y615201D03*
X1604430D03*
X1598868Y628727D03*
X1598928Y626177D03*
X1593868Y628727D03*
X1593928Y626177D03*
X1596428D03*
X1596368Y628727D03*
X1598898Y631237D03*
X1593898D03*
X1596398D03*
X1598868Y650877D03*
X1598838Y648367D03*
X1596368Y650877D03*
X1593868D03*
X1596338Y648367D03*
X1593838D03*
X1598898Y645817D03*
X1596398D03*
X1593898D03*
X1598868Y653377D03*
X1596368D03*
X1593868D03*
X1598948Y657677D03*
X1593948D03*
X1596448D03*
Y660177D03*
X1593948D03*
X1598948D03*
X1596468Y665237D03*
X1593968D03*
X1598968D03*
X1596438Y662727D03*
X1593938D03*
X1598938D03*
X1593938Y679807D03*
X1596438D03*
X1593878Y682357D03*
X1596378D03*
X1593908Y684867D03*
X1596408D03*
X1598878Y682357D03*
X1598908Y684867D03*
X1598938Y679807D03*
X1596288Y688902D03*
X1598888D03*
X1598828Y696727D03*
X1593828D03*
X1593888Y694177D03*
X1596388D03*
X1596328Y696727D03*
X1593858Y699277D03*
X1596358D03*
X1598888Y694177D03*
X1596288Y691502D03*
X1598858Y699277D03*
X1598888Y691502D03*
X1598858Y718837D03*
X1598828Y716327D03*
X1596358Y718837D03*
X1593858D03*
X1596328Y716327D03*
X1593828D03*
X1596388Y713777D03*
X1593888D03*
X1598888D03*
X1596250Y721452D03*
X1598850D03*
X1599010Y724002D03*
X1606980Y1449922D03*
X1621920Y25962D03*
X1622220Y49862D03*
X1619980Y590685D03*
X1620170Y623762D03*
X1622770D03*
X1619980Y615201D03*
X1620170Y626362D03*
X1622770D03*
X1620170Y657762D03*
X1622770D03*
X1622109Y652469D03*
X1619509D03*
X1620170Y660362D03*
X1622770D03*
X1622109Y686469D03*
X1619509D03*
X1622770Y691762D03*
Y694362D03*
X1620170Y691762D03*
Y694362D03*
X1619509Y720469D03*
X1622109D03*
X1614116Y1411169D03*
X1623448Y1420028D03*
Y1417428D03*
Y1414828D03*
Y1412228D03*
X1612630Y1418842D03*
X1615062Y1421241D03*
X1615597Y1433669D03*
X1617215Y1440822D03*
X1611866Y1737108D03*
X1633111Y206693D03*
X1642135Y414202D03*
X1637667Y587844D03*
Y590444D03*
X1629867D03*
Y587844D03*
X1632467Y590444D03*
Y587844D03*
X1635067Y590444D03*
Y587844D03*
X1626606Y616576D03*
X1629206D03*
X1631806D03*
X1634406D03*
X1637006D03*
X1639606D03*
X1630570Y623762D03*
X1627970D03*
X1625370D03*
X1630570Y626362D03*
X1627970D03*
X1625370D03*
X1630570Y657762D03*
X1627970D03*
X1625370D03*
X1629909Y652469D03*
X1632509D03*
X1624709D03*
X1627309D03*
X1630570Y660362D03*
X1627970D03*
X1625370D03*
X1629909Y686469D03*
X1632509D03*
X1624709D03*
X1627309D03*
X1625370Y691762D03*
Y694362D03*
X1630570D03*
Y691762D03*
X1627970D03*
Y694362D03*
X1632509Y720469D03*
X1627309D03*
X1629909D03*
X1624709D03*
X1638277Y1269065D03*
X1640812Y1270020D03*
X1637183Y1394411D03*
X1639683D03*
X1629262Y1394418D03*
X1634683Y1394411D03*
X1625948Y1417428D03*
Y1412228D03*
Y1414828D03*
Y1420028D03*
X1630643Y1440290D03*
X1627591Y1447796D03*
X1637478Y1445150D03*
X1634643Y1442982D03*
X1630643Y1443090D03*
X1631866Y1737108D03*
X1652610Y394727D03*
X1652810Y407402D03*
X1647110Y434177D03*
X1649291Y556057D03*
X1653230Y549322D03*
X1642873Y604206D03*
Y607206D03*
X1645625Y600495D03*
Y603295D03*
X1642873Y601206D03*
Y598206D03*
X1645625Y597795D03*
Y594995D03*
X1642873Y595006D03*
X1649220Y620662D03*
X1642340Y618546D03*
X1642873Y610206D03*
X1656550Y653086D03*
X1652581Y646311D03*
X1655637D03*
X1656550Y687086D03*
X1652581Y714311D03*
X1655637D03*
X1656188Y1394736D03*
X1647592Y1394418D03*
X1655779Y1417618D03*
Y1412418D03*
Y1415018D03*
X1653279Y1412418D03*
X1650679D03*
X1653279Y1415018D03*
X1650679D03*
X1653168Y1417618D03*
X1650557D03*
X1648947Y1476695D03*
X1651866Y1737108D03*
X1668100Y180852D03*
X1659610Y394727D03*
X1663610D03*
X1661110Y434177D03*
X1662447Y480619D03*
X1663376Y515531D03*
X1667376D03*
X1665790Y523417D03*
X1670004Y537065D03*
Y543065D03*
Y531065D03*
X1664040Y569642D03*
X1668040D03*
X1672040D03*
X1665700Y583462D03*
X1661510Y583442D03*
X1672770Y580512D03*
X1669770D03*
X1664997Y604762D03*
X1662120Y604782D03*
X1657220Y620662D03*
X1663720Y620434D03*
X1664410Y617953D03*
X1668920Y617637D03*
X1659458Y637149D03*
X1658085Y639511D03*
X1659914Y649681D03*
X1659458Y671149D03*
X1658085Y673511D03*
X1659914Y683681D03*
X1659458Y705149D03*
X1658085Y707511D03*
X1659914Y717681D03*
X1673226Y1394411D03*
X1667405Y1394418D03*
X1659260Y1394693D03*
X1658390Y1420218D03*
Y1415018D03*
Y1412418D03*
Y1417618D03*
X1663590Y1420218D03*
X1660990D03*
Y1415018D03*
Y1417618D03*
Y1412418D03*
X1663590Y1415018D03*
Y1417618D03*
Y1412418D03*
X1657438Y1438156D03*
X1660428Y1447566D03*
X1667577Y1447545D03*
X1668786Y1440290D03*
Y1443256D03*
X1666123Y1557557D03*
X1666198Y1561557D03*
Y1581321D03*
X1671866Y1737108D03*
X1686154Y434160D03*
X1682810Y465940D03*
X1681817Y495290D03*
X1682004Y537065D03*
X1682180Y543065D03*
X1676004D03*
X1682004Y531065D03*
X1676004D03*
X1678860Y556752D03*
X1676040Y569627D03*
X1688301Y722158D03*
X1683121D03*
X1680401D03*
X1686135Y1394418D03*
X1675926Y1394411D03*
X1678426D03*
X1687860Y1415179D03*
X1689210Y1417679D03*
X1687860Y1412579D03*
X1675621Y1445150D03*
X1680720Y1487062D03*
X1697725Y205120D03*
X1693987Y230174D03*
Y233174D03*
X1703487Y232174D03*
X1704444Y407045D03*
X1697914Y427155D03*
X1698014Y424055D03*
X1701124Y433650D03*
X1697214Y433655D03*
X1704624Y433650D03*
X1700846Y455894D03*
X1697648Y463724D03*
X1693648D03*
X1702760Y478207D03*
X1696760D03*
X1693236Y472650D03*
X1702760Y490207D03*
X1696760D03*
Y484207D03*
X1703720Y509362D03*
X1707200Y498962D03*
X1699265Y525507D03*
X1696851Y515607D03*
X1693701D03*
X1699291Y537507D03*
X1699251Y529507D03*
X1699297Y549507D03*
X1702270Y552742D03*
X1703306Y550064D03*
X1692883Y703943D03*
X1698920Y698562D03*
X1695227Y722325D03*
X1699307Y722465D03*
X1698137Y718345D03*
X1701087Y719055D03*
X1695367Y719345D03*
X1691021Y722158D03*
X1690809Y1393970D03*
X1699150Y1393613D03*
X1690460Y1415179D03*
Y1412579D03*
X1691918Y1417676D03*
X1692960Y1415179D03*
Y1412579D03*
X1693404Y1421939D03*
X1699593Y1428384D03*
X1697820Y1423616D03*
X1699545Y1425868D03*
X1699437Y1431295D03*
X1691866Y1737108D03*
X1707220Y15662D03*
X1714589Y21562D03*
X1710106Y48720D03*
Y40020D03*
X1719530Y162950D03*
X1707444Y407045D03*
X1711144Y425945D03*
X1711477Y465229D03*
Y468379D03*
X1708760Y478031D03*
Y490207D03*
Y484207D03*
X1710500Y538162D03*
X1709356Y541144D03*
X1709680Y545432D03*
X1709027Y655141D03*
X1706720Y703762D03*
X1719727Y1472088D03*
X1718149Y1496270D03*
X1717149Y1505895D03*
X1720174D03*
X1717988Y1520951D03*
X1711988D03*
X1717149Y1513945D03*
X1720174D03*
X1714988Y1520951D03*
X1708988D03*
X1717988Y1530445D03*
X1714988D03*
X1708988D03*
X1711988D03*
X1711866Y1737108D03*
X1727768Y3010D03*
X1726720Y49862D03*
X1733720D03*
X1730220D03*
X1736040Y41792D03*
X1732810Y52482D03*
X1736040Y44292D03*
X1730140Y52552D03*
X1727600Y52582D03*
X1738220Y98862D03*
X1736720Y101862D03*
X1733378Y134907D03*
X1736508D03*
X1730765Y151362D03*
X1733920D03*
X1738200Y193862D03*
X1725473Y474859D03*
X1731866Y1737108D03*
X1747768Y3010D03*
X1740858Y72330D03*
Y79830D03*
Y74830D03*
Y82330D03*
X1754398Y100307D03*
X1745220Y98862D03*
X1741720D03*
X1743720Y101862D03*
X1740220D03*
X1748720Y97362D03*
X1745485Y119539D03*
X1747482Y121367D03*
X1738520Y151362D03*
X1751220Y147562D03*
X1748465D03*
X1754120Y171562D03*
X1750920Y171662D03*
X1751084Y190928D03*
X1752200Y197762D03*
X1748500Y193862D03*
X1745500D03*
X1741200D03*
X1754307Y262186D03*
X1751068Y262123D03*
X1754245Y269724D03*
X1751068Y266048D03*
X1754307Y266111D03*
X1754414Y275329D03*
X1752165Y273901D03*
X1749565D03*
X1751006Y269661D03*
X1749595Y276711D03*
X1752195D03*
X1745000Y299862D03*
X1740831Y489362D03*
X1740886Y493960D03*
X1752316Y703969D03*
Y695669D03*
X1752217Y692988D03*
X1752276Y720529D03*
X1752316Y712269D03*
X1751866Y1737108D03*
X1767768Y3010D03*
X1769274Y50742D03*
X1771774Y53682D03*
X1759700Y57662D03*
X1764400Y57462D03*
X1758063Y68637D03*
X1758573Y87107D03*
Y83607D03*
X1768168Y80497D03*
X1758568Y79697D03*
X1765068Y80397D03*
X1766278Y93627D03*
X1764678Y122927D03*
X1766880Y234842D03*
Y231842D03*
X1758500Y231822D03*
Y234822D03*
X1755378Y233528D03*
X1763731Y283817D03*
X1766725Y282981D03*
X1763731Y279517D03*
X1760398Y279548D03*
X1766765Y279433D03*
X1757439Y279611D03*
X1760398Y283848D03*
X1759509Y292434D03*
X1762549Y286704D03*
X1757439Y283911D03*
X1768045Y295238D03*
X1765053Y295188D03*
X1762285Y295137D03*
X1759629Y295164D03*
X1767309Y290994D03*
X1763045Y289691D03*
X1759529Y289864D03*
X1766655Y286531D03*
X1767455Y302651D03*
X1764955Y301951D03*
X1758563Y310478D03*
X1754963D03*
X1770220Y377452D03*
Y382952D03*
X1768560Y539042D03*
X1766060D03*
X1755112Y703948D03*
Y695648D03*
X1755013Y692967D03*
X1757612Y703948D03*
Y695648D03*
X1755072Y720508D03*
X1755112Y712248D03*
X1757572Y720508D03*
X1757612Y712248D03*
X1774274Y50742D03*
X1776710Y53562D03*
X1785178Y86927D03*
Y89927D03*
X1782000Y128455D03*
X1771915Y128393D03*
X1782000Y125955D03*
Y123455D03*
X1771915Y125893D03*
Y123393D03*
X1786690Y234782D03*
Y231782D03*
X1783800Y231762D03*
Y234762D03*
X1775140Y234792D03*
Y231792D03*
X1779226Y275604D03*
X1783563Y273471D03*
X1786089D03*
X1771029Y295164D03*
X1771229Y291064D03*
X1772863Y310478D03*
X1771866Y1737108D03*
X1787768Y3010D03*
X1793061Y24659D03*
X1794910Y44573D03*
X1797663Y269571D03*
X1800189D03*
X1790563Y273471D03*
X1793089D03*
X1802763Y308671D03*
X1795763D03*
X1798289D03*
X1788763D03*
X1791289D03*
X1795484Y1496401D03*
X1792645Y1511423D03*
X1798450Y1524830D03*
X1801450D03*
Y1527830D03*
X1814322Y49388D03*
X1814349Y269634D03*
X1811823D03*
X1807249D03*
X1804723D03*
X1812349Y308734D03*
X1809823D03*
X1805289Y308671D03*
X1803517Y1495567D03*
X1818410Y1525815D03*
X1812250Y1521830D03*
X1811250Y1524830D03*
Y1527830D03*
X1807850D03*
X1804650D03*
Y1524830D03*
X1807850D03*
X1814370Y1528900D03*
X1814210Y1525815D03*
X1818524Y1528991D03*
X1834322Y49388D03*
X1823426Y1507916D03*
X1831994Y1525977D03*
X1835334Y1520921D03*
X1828510Y1525915D03*
X1821710D03*
X1830466Y1606658D03*
X1828880Y1626595D03*
Y1646595D03*
Y1666595D03*
Y1686595D03*
X1843134Y244362D03*
X1850331Y311946D03*
X1840691Y329470D03*
Y349470D03*
Y369470D03*
Y389470D03*
Y409470D03*
Y429470D03*
Y449470D03*
Y469470D03*
Y489470D03*
Y509470D03*
Y529470D03*
Y549470D03*
Y569470D03*
Y589470D03*
Y669470D03*
Y1329470D03*
Y1409470D03*
Y1429470D03*
Y1449470D03*
Y1469470D03*
Y1489470D03*
Y1509470D03*
Y1529470D03*
Y1549470D03*
Y1569470D03*
Y1589470D03*
X1854096Y52383D03*
X1854470Y112379D03*
Y152379D03*
Y172379D03*
Y192379D03*
Y212379D03*
Y232379D03*
Y252379D03*
Y272379D03*
Y292379D03*
G54D20*
X1897608Y1001506D03*
X1907608D03*
X1945484Y1670313D03*
X1955484D03*
G54D11*
G01X212891Y566632D02*
Y570171D01*
X210900Y572162D01*
Y581562D01*
X212891Y583553D01*
Y601981D01*
G01D02*
Y605671D01*
X211200Y607362D01*
Y616462D01*
X212891Y618153D01*
Y635981D01*
X36399Y960892D03*
Y957546D03*
Y967585D03*
X52541Y964239D03*
X66099Y816995D03*
Y810302D03*
Y833727D03*
Y823688D03*
Y827034D03*
Y840420D03*
Y960892D03*
Y957546D03*
Y967585D03*
Y1221916D03*
Y1215223D03*
Y1238648D03*
Y1228609D03*
Y1231955D03*
Y1245341D03*
X82241Y813648D03*
Y806955D03*
Y820341D03*
Y830381D03*
Y823688D03*
Y837074D03*
Y964239D03*
Y1218570D03*
Y1211877D03*
Y1225263D03*
Y1241995D03*
Y1235302D03*
Y1228609D03*
X95799Y960892D03*
Y957546D03*
X125499Y780184D03*
Y773491D03*
Y786877D03*
Y803609D03*
Y796916D03*
Y790223D03*
Y847113D03*
Y853806D03*
Y860499D03*
Y863845D03*
Y883924D03*
Y877231D03*
Y870538D03*
Y890617D03*
Y897310D03*
Y900656D03*
Y914042D03*
Y907349D03*
Y960892D03*
Y957546D03*
Y1061286D03*
Y1074672D03*
Y1067979D03*
Y1091404D03*
Y1081365D03*
Y1084711D03*
Y1098097D03*
Y1111483D03*
Y1104790D03*
Y1128215D03*
Y1118176D03*
Y1121522D03*
Y1134908D03*
Y1185105D03*
Y1178412D03*
Y1191798D03*
Y1208530D03*
Y1201837D03*
Y1195144D03*
X141641Y770144D03*
Y776837D03*
Y786877D03*
Y783530D03*
Y800263D03*
Y793570D03*
Y850459D03*
Y843766D03*
Y867192D03*
Y860499D03*
Y857152D03*
Y873885D03*
Y880577D03*
Y887270D03*
Y897310D03*
Y893963D03*
Y910696D03*
Y904003D03*
Y1071326D03*
Y1064633D03*
Y1078018D03*
Y1094751D03*
Y1088058D03*
Y1081365D03*
Y1108137D03*
Y1101444D03*
Y1124869D03*
Y1118176D03*
Y1114829D03*
Y1131562D03*
Y1175066D03*
Y1181759D03*
Y1191798D03*
Y1188452D03*
Y1205184D03*
Y1198491D03*
X155199Y960892D03*
Y957546D03*
X184899Y960892D03*
Y957546D03*
X194197Y1614292D03*
X197597D03*
X206257D03*
X214599Y960892D03*
Y957546D03*
X209657Y1614292D03*
X218317D03*
X221717D03*
X230377D03*
X233777D03*
X244299Y960892D03*
Y957546D03*
X242437Y1614292D03*
X254497D03*
X245837D03*
X266557D03*
X257897D03*
X269957D03*
X278617D03*
X282017D03*
X290677D03*
X302737D03*
X294077D03*
X306137D03*
X314797D03*
X318197D03*
X330257D03*
X338917D03*
X326857D03*
X350727Y851380D03*
X354427Y844971D03*
X348878Y848176D03*
X352578D03*
X341911Y1105426D03*
X343762Y1108630D03*
X345611Y1111834D03*
X351161Y1102221D03*
X349312Y1111834D03*
X353011Y1105426D03*
X345611D03*
X341912Y1111834D03*
X354861Y1102221D03*
X353012Y1111834D03*
X351162Y1108630D03*
X347461Y1115039D03*
X350977Y1614292D03*
X342317D03*
X354377D03*
X356279Y841467D03*
X361827Y844971D03*
X363679Y841467D03*
X369227Y844971D03*
X371079Y841467D03*
X358127Y844971D03*
X359978Y848176D03*
X365527Y844971D03*
X367378Y848176D03*
X371078Y893036D03*
X363037Y1614292D03*
X366437D03*
X387727Y844971D03*
X376627D03*
X380327D03*
X384027D03*
X385879Y841467D03*
X372927Y844971D03*
X374778Y848176D03*
X378479Y841467D03*
X382178Y848176D03*
X374778Y899445D03*
X382178D03*
Y893036D03*
X374778D03*
X385878D03*
X372929Y896240D03*
X380329D03*
X376629D03*
X384029D03*
X376629Y902649D03*
X380329D03*
X374778Y912262D03*
X376629Y909057D03*
X382178Y912262D03*
X380329Y909057D03*
X372929Y915466D03*
X380329D03*
X376629D03*
X384029D03*
X374778Y931488D03*
X376629Y928283D03*
X382178Y931488D03*
X380329Y928283D03*
X376629Y921875D03*
X374778Y918670D03*
X380329Y921875D03*
X382178Y918670D03*
X380329Y941100D03*
X382178Y937896D03*
X376629Y947509D03*
X380329D03*
X376629Y941100D03*
X374778Y937896D03*
X372929Y934691D03*
X380329D03*
X376629D03*
X384029D03*
X376629Y960326D03*
X374778Y957122D03*
X380329Y960326D03*
X382178Y957122D03*
X374778Y950713D03*
X382178D03*
X372929Y953917D03*
X380329D03*
X376629D03*
X384029D03*
X380329Y966735D03*
X376629D03*
X374778Y969939D03*
X382178D03*
X375211Y1002888D03*
X377062Y999684D03*
X382611Y1002888D03*
X380762Y999684D03*
X377062Y1012501D03*
X375211Y1009297D03*
X380762Y1012501D03*
X382611Y1009297D03*
X377062Y1031727D03*
X375211Y1028523D03*
X380762Y1031727D03*
X382611Y1028523D03*
X375211Y1022114D03*
X377062Y1018910D03*
X382611Y1022114D03*
X380762Y1018910D03*
X377062Y1025318D03*
X384462D03*
X373360D03*
X380760D03*
X375211Y1047749D03*
X382611D03*
X375211Y1041340D03*
X377062Y1038136D03*
X382611Y1041340D03*
X380762Y1038136D03*
X373362Y1044544D03*
X380762D03*
X377062D03*
X384462D03*
X375211Y1060565D03*
X377062Y1057361D03*
X382611Y1060565D03*
X380762Y1057361D03*
X377062Y1050952D03*
X380762D03*
X373362Y1063770D03*
X384462D03*
X377062D03*
X380762D03*
Y1070178D03*
X382611Y1066974D03*
X377062Y1070178D03*
X375211Y1066974D03*
Y1079791D03*
X377062Y1076587D03*
X382611Y1079791D03*
X380762Y1076587D03*
X377062Y1089404D03*
X375211Y1086200D03*
X380762Y1089404D03*
X382611Y1086200D03*
X373362Y1082995D03*
X384462D03*
X377062D03*
X380762D03*
X386311Y1105426D03*
X382611Y1111834D03*
X375211Y1105426D03*
X377062Y1108630D03*
X380762Y1102221D03*
X378911Y1111834D03*
X384462Y1108630D03*
X386311Y1111834D03*
X378912Y1105426D03*
X375211Y1111834D03*
X382611Y1105426D03*
X380762Y1115039D03*
X375097Y1614292D03*
X378497D03*
X400678Y848176D03*
X391427Y844971D03*
X395127D03*
X398827D03*
X400679Y841467D03*
X389578Y848176D03*
X393279Y841467D03*
X396978Y848176D03*
X402527Y844971D03*
X400678Y860993D03*
X402529Y947509D03*
X398829Y953917D03*
X402529D03*
X400680Y950713D03*
X398829Y973143D03*
X400678Y976347D03*
X402529Y979552D03*
Y973143D03*
X390011Y1002888D03*
X388162Y999684D03*
X393711Y1002888D03*
X395562Y999684D03*
X399262D03*
X401111Y1022114D03*
X402960Y1018910D03*
X402962Y1025318D03*
X399262D03*
X402962Y1082995D03*
X402961Y1089404D03*
X408078Y848176D03*
X415478D03*
X406227Y844971D03*
X409927D03*
X413627D03*
X417327D03*
X404378Y848176D03*
X408079Y841467D03*
X411778Y848176D03*
X415479Y841467D03*
X419178Y848176D03*
X415478Y860993D03*
X408078D03*
X415478Y873810D03*
X408078Y899445D03*
X415478D03*
X411778Y905853D03*
X408078D03*
X408569Y929108D03*
X406308Y928626D03*
X415185Y956620D03*
X411685D03*
X409385D03*
X417685D03*
X404785Y971100D03*
X407085D03*
X409385D03*
X411685D03*
X420205D03*
X412365Y985610D03*
X410065D03*
X420145Y985550D03*
X412385Y1000080D03*
X410085D03*
X420215Y1000040D03*
X420405Y1014470D03*
X408511Y1079791D03*
X406662Y1089404D03*
X410362D03*
X404811Y1086200D03*
X419611D03*
X414062Y1082995D03*
X410362D03*
X406662D03*
X408511Y1092608D03*
X414062Y1089404D03*
X419611Y1092608D03*
X412211Y1086200D03*
X422878Y848176D03*
X421027Y844971D03*
X424727D03*
X428427D03*
X433978Y848176D03*
X435829Y844671D03*
X422879Y841467D03*
X426578Y848176D03*
X430278D03*
Y860993D03*
X422878D03*
Y873810D03*
X430278Y899445D03*
X422878D03*
X424729Y902649D03*
X424927Y927255D03*
X423176Y929465D03*
X422427Y927255D03*
X425676Y929465D03*
X427875Y941930D03*
Y944230D03*
X430280Y944305D03*
X432130Y941101D03*
X435830D03*
X432129Y947510D03*
X435830D03*
X427875Y956373D03*
Y954073D03*
X422685Y956620D03*
X425185D03*
X430280Y957123D03*
X432129Y960327D03*
Y953918D03*
X430280Y950714D03*
X435830Y960327D03*
Y953918D03*
X432129Y966736D03*
X430280Y963531D03*
X435830Y966736D03*
X430268Y976348D03*
X432129Y973144D03*
X430280Y969940D03*
X427875Y971267D03*
X422685Y971100D03*
X427875Y968967D03*
X435830Y973144D03*
X430280Y982757D03*
X432129Y979553D03*
X427875Y983111D03*
X435830Y979553D03*
X422685Y985580D03*
X427875Y985411D03*
Y997521D03*
X430712Y1009298D03*
X427875Y1012152D03*
X430712Y1002889D03*
X427875Y999821D03*
X422685Y1000060D03*
X436263Y1006094D03*
Y999685D03*
X432562Y1006094D03*
Y999685D03*
X427875Y1014452D03*
X423015Y1014470D03*
X436263Y1012502D03*
X432562D03*
X430712Y1022115D03*
Y1015706D03*
X427875Y1026704D03*
X430712Y1028524D03*
X436263Y1018911D03*
X432562D03*
Y1025319D03*
X436263D03*
X427875Y1029004D03*
Y1031304D03*
X436263Y1031728D03*
X432562D03*
X423285Y1036884D03*
X430711Y1041340D03*
X430712Y1034932D03*
X427875Y1033604D03*
X423285Y1032284D03*
Y1034584D03*
X436262Y1038137D03*
X436261Y1044544D03*
X432562Y1038137D03*
X434412Y1041340D03*
X432561Y1044544D03*
X434412Y1047749D03*
X436262Y1057361D03*
Y1050952D03*
Y1063770D03*
Y1070178D03*
Y1076587D03*
X421462Y1089404D03*
X423311Y1092608D03*
X427011D03*
X430710Y1086200D03*
X425162Y1082995D03*
Y1095813D03*
X430711Y1092608D03*
X423311Y1086200D03*
X428861Y1089404D03*
X427012Y1086200D03*
X436262Y1127856D03*
X436261Y1134264D03*
X432561D03*
X450628Y844971D03*
X446927Y844671D03*
X452479Y841467D03*
X448778Y848176D03*
X443227Y844671D03*
X437678Y848176D03*
X452478Y886627D03*
X445078D03*
X452478Y899445D03*
X437680Y944305D03*
X441380D03*
X443230Y941101D03*
X445079Y944305D03*
X439530Y941101D03*
X450630D03*
X448780Y944305D03*
X443229Y947510D03*
X439529D03*
X450630D03*
X445079Y957123D03*
X437680D03*
X441380D03*
X439529Y960327D03*
X443229D03*
Y953918D03*
X439529D03*
X437680Y950714D03*
X441380D03*
X445079D03*
X448780Y957123D03*
X450630Y953918D03*
Y960327D03*
X448780Y950714D03*
X445079Y963531D03*
X437680D03*
X441380D03*
X439529Y966736D03*
X443229D03*
X448780Y963531D03*
X450630Y966736D03*
X445079Y976348D03*
Y969940D03*
X439529Y973144D03*
X443229D03*
X437680Y976348D03*
X441380D03*
X437680Y969940D03*
X441380D03*
X450630Y973144D03*
X448780Y976348D03*
Y969940D03*
X445079Y982757D03*
X437680D03*
X441380D03*
X439529Y979553D03*
X443229D03*
X448780Y982757D03*
X450630Y979553D03*
X439962Y1006094D03*
X443662D03*
X445511Y1009298D03*
X438113D03*
X441813D03*
X445512Y1002889D03*
X438113D03*
X441813D03*
X439962Y999685D03*
X443662D03*
X451062Y1006094D03*
X449213Y1009298D03*
Y1002889D03*
X451062Y999685D03*
X439962Y1012502D03*
X443662D03*
X451062D03*
X445511Y1022115D03*
X438113D03*
X441813D03*
X445512Y1015706D03*
X438113D03*
X439962Y1018911D03*
X441813Y1015706D03*
X443662Y1018911D03*
Y1025319D03*
X439962D03*
X445511Y1028524D03*
X441813D03*
X438113D03*
X449213Y1022115D03*
X451062Y1018911D03*
X449213Y1015706D03*
X451062Y1025319D03*
X449213Y1028524D03*
X439962Y1031728D03*
X443662D03*
X451062D03*
X439962Y1038137D03*
X443662D03*
X438112Y1041340D03*
X439961Y1044544D03*
X441812Y1041340D03*
X443661Y1044544D03*
X447361D03*
X445511Y1041340D03*
X445512Y1034932D03*
X438113D03*
X441813D03*
X451062Y1038137D03*
X449211Y1041340D03*
X449213Y1034932D03*
X445510Y1047749D03*
X441812D03*
X438112D03*
Y1060565D03*
Y1054157D03*
X439961Y1057361D03*
X441812Y1054157D03*
Y1060565D03*
X443661Y1057361D03*
X445511Y1060565D03*
Y1054157D03*
X439961Y1050952D03*
X443661D03*
X439961Y1063770D03*
X443661D03*
X439961Y1076587D03*
Y1070178D03*
X441812Y1073383D03*
X438112D03*
X443661Y1070178D03*
Y1076587D03*
X445511Y1073383D03*
X441812Y1066974D03*
X438112D03*
X445511D03*
X441812Y1079791D03*
X445511D03*
X443661Y1082995D03*
X445511Y1086200D03*
X447361Y1089404D03*
X449211Y1092608D03*
X447361Y1095813D03*
X443661Y1108630D03*
X445511Y1105426D03*
X452912D03*
X451061Y1108630D03*
X449212Y1105426D03*
X451061Y1102221D03*
X449212Y1099017D03*
X445511Y1111834D03*
X452912D03*
X449212D03*
X438112Y1124651D03*
X439961Y1121447D03*
X441812Y1124651D03*
X445511D03*
X443661Y1121447D03*
X441812Y1118243D03*
X445511D03*
X443661Y1115039D03*
X452912Y1124651D03*
Y1118243D03*
X451061Y1121447D03*
X449212Y1124651D03*
Y1118243D03*
X451061Y1115039D03*
X439961Y1127856D03*
X443661D03*
X451061D03*
X441812Y1137769D03*
X438112D03*
X445511D03*
X443661Y1134264D03*
X441812Y1131060D03*
X439961Y1134264D03*
X438112Y1131060D03*
X445511D03*
X452912Y1137769D03*
Y1131060D03*
X449212Y1137769D03*
Y1131060D03*
X451061Y1134264D03*
X459878Y848176D03*
X467278D03*
X467279Y841467D03*
X463578Y848176D03*
X459879Y841467D03*
X458027Y844971D03*
X454327D03*
X469127D03*
X465427D03*
X461727D03*
X456178Y848176D03*
X459878Y860993D03*
X467278D03*
Y873810D03*
X459878D03*
Y886627D03*
X467278D03*
X459878Y899445D03*
X467278D03*
X468236Y928349D03*
X465936D03*
X463636D03*
X461336D03*
X459036D03*
X453585Y942238D03*
Y939938D03*
Y944538D03*
X453403Y956999D03*
X461424Y956620D03*
X458404D03*
X453403Y959299D03*
X468904Y956620D03*
Y971100D03*
X458404D03*
X461424Y971140D03*
X453403Y973099D03*
Y970799D03*
Y986899D03*
X461424Y985580D03*
X458404D03*
X453403Y984599D03*
X468904Y985580D03*
X453403Y998399D03*
Y1012199D03*
X458404Y1000080D03*
X461424D03*
X453403Y1000699D03*
X468904Y1000080D03*
X458404Y1014540D03*
X461295Y1014510D03*
X453403Y1014499D03*
X467712Y1054157D03*
Y1060565D03*
X465862Y1076587D03*
X458461Y1108630D03*
X456612Y1105426D03*
X454761Y1108630D03*
Y1102221D03*
X460312Y1111834D03*
X456611D03*
X464012Y1124651D03*
X462161Y1121447D03*
X460312Y1124651D03*
X456611D03*
X454761Y1121447D03*
X464011Y1118243D03*
X462161Y1115039D03*
X460312Y1118243D03*
X456611D03*
X454761Y1115039D03*
X462161Y1127856D03*
X454761D03*
X465861D03*
X464012Y1137469D03*
X460312D03*
X456612D03*
X464012Y1131060D03*
X462161Y1134264D03*
X460312Y1131060D03*
X456611D03*
X454761Y1134264D03*
X462161Y1140973D03*
X458461D03*
X454761D03*
X467712Y1137469D03*
X465861Y1134264D03*
X467712Y1131060D03*
X465861Y1140973D03*
X474678Y848176D03*
X482078D03*
X483927Y844971D03*
X480227D03*
X476527D03*
X470978Y848176D03*
X482079Y841467D03*
X478378Y848176D03*
X474679Y841467D03*
X472827Y844971D03*
X474678Y860993D03*
X482078D03*
X474678Y873810D03*
X482078D03*
X474678Y886627D03*
X482078D03*
Y905853D03*
X470536Y928349D03*
X480229Y947509D03*
X478378Y950713D03*
X480229Y953917D03*
X478378Y957122D03*
X471404Y956620D03*
X476285Y973826D03*
Y971526D03*
X471404Y971100D03*
X473904D03*
X471404Y985580D03*
X478811Y1009297D03*
X471404Y1000080D03*
X480661Y1018910D03*
X478811Y1022114D03*
Y1028523D03*
Y1015705D03*
X476325Y1031795D03*
Y1027195D03*
Y1029495D03*
X470724Y1028827D03*
X476962Y1044544D03*
X478811Y1047749D03*
X473261Y1057361D03*
X471412Y1060565D03*
X475112Y1054157D03*
X469562Y1063770D03*
X469561Y1057361D03*
X473262Y1063770D03*
X469561Y1050952D03*
X473262D03*
X482511Y1054157D03*
X480662Y1063770D03*
X480661Y1057361D03*
X478812Y1060565D03*
X476962Y1063770D03*
Y1057361D03*
X478812Y1054157D03*
X476961Y1050952D03*
X475111Y1073383D03*
X469561Y1134264D03*
X478351Y1614292D03*
X481751D03*
X489478Y848176D03*
X496878D03*
X493178D03*
X489478Y841467D03*
X487627Y844971D03*
X500578Y848176D03*
X496878Y841467D03*
X495027Y844971D03*
X491327D03*
X485778Y848176D03*
X498727Y844971D03*
X489478Y860993D03*
X496878D03*
Y873810D03*
X489478D03*
X500578Y899445D03*
X489478Y886627D03*
X496878D03*
X500578Y912262D03*
X498729Y909057D03*
Y902649D03*
X500578Y905853D03*
X496878D03*
X500578Y931488D03*
X498729Y921875D03*
X500578Y918670D03*
X498729Y928283D03*
X496878Y925079D03*
X500578D03*
X498729Y947509D03*
Y941100D03*
X500578Y937896D03*
X496878Y944304D03*
X500578D03*
Y950713D03*
Y957122D03*
X498729Y960326D03*
X487629Y979552D03*
X485778Y976347D03*
X491329Y979552D03*
X493178Y976347D03*
X501011Y1002888D03*
X499162Y999684D03*
Y1031727D03*
X501011Y1028523D03*
Y1041340D03*
X499162Y1038136D03*
X501011Y1047749D03*
Y1034931D03*
X497311D03*
X501011Y1060565D03*
X499162Y1057361D03*
Y1050952D03*
X501011Y1054157D03*
X497311D03*
X499162Y1070178D03*
X501011Y1066974D03*
Y1079791D03*
X499162Y1076587D03*
X497311Y1073383D03*
X501011D03*
X499162Y1089404D03*
X501011Y1086200D03*
X497311Y1092608D03*
X501011D03*
X490411Y1614292D03*
X493811D03*
X517227Y844971D03*
X511679Y841467D03*
X509827Y844971D03*
X504279Y841467D03*
X515378Y848176D03*
X513527Y844971D03*
X507978Y848176D03*
X506127Y844971D03*
X502427D03*
X504278Y899445D03*
Y912262D03*
X506129Y909057D03*
Y902649D03*
X507978Y905853D03*
X504278D03*
X506129Y928283D03*
Y921875D03*
X504278Y918670D03*
Y931488D03*
Y925079D03*
X507978D03*
X506129Y947509D03*
Y941100D03*
X504278Y937896D03*
X507978Y944304D03*
X504278D03*
Y950713D03*
Y957122D03*
X506129Y960326D03*
X504711Y1002888D03*
X506561Y999684D03*
X517661D03*
X512111Y1002888D03*
X513962Y999684D03*
X506562Y1031727D03*
X504711Y1028523D03*
Y1041340D03*
X506562Y1038136D03*
X504711Y1047749D03*
X508411Y1034931D03*
X504711D03*
Y1060565D03*
X506562Y1057361D03*
Y1050952D03*
X508411Y1054157D03*
X504711D03*
Y1079791D03*
X506562Y1076587D03*
Y1070178D03*
X504711Y1066974D03*
X508411Y1073383D03*
X504711D03*
X510262Y1095813D03*
X506561D03*
X506562Y1089404D03*
X504711Y1086200D03*
X508411Y1092608D03*
X504711D03*
X517662Y1102221D03*
X515811Y1099017D03*
X514531Y1614292D03*
X502471D03*
X517931D03*
X505871D03*
X532028Y844671D03*
X526478Y848176D03*
X524627Y844971D03*
X519079Y841467D03*
X533878Y848176D03*
X530178D03*
X522778D03*
X520927Y844971D03*
X532029Y864197D03*
X533879Y854584D03*
X519513Y1002888D03*
X530611D03*
X532461Y999684D03*
X526911Y1002888D03*
X525062Y999684D03*
X528761Y1140973D03*
X532461D03*
X526591Y1614292D03*
X529991D03*
X543129Y851380D03*
X539429D03*
X535729Y864197D03*
X543128D03*
X546828D03*
X535729Y857789D03*
X543130D03*
X539429D03*
X541279Y860993D03*
Y854584D03*
X538651Y1614292D03*
X542051D03*
X562771D03*
X550711D03*
X566171D03*
X554111D03*
X574831D03*
X578231D03*
X598951D03*
X586891D03*
X590291D03*
X611011D03*
X614411D03*
X602351D03*
X620799Y960892D03*
Y957546D03*
X629931Y1258727D03*
X623071Y1614292D03*
X626471D03*
X647191D03*
X635131D03*
X638531D03*
X650499Y960892D03*
Y957546D03*
X650599Y1258727D03*
X654606Y1431203D03*
X662651Y1614292D03*
X659251D03*
X650591D03*
X674628Y424313D03*
X677778Y414864D03*
X674628Y421163D03*
Y418013D03*
X677778Y427462D03*
Y440061D03*
X674628D03*
X677778Y436911D03*
X680928Y440061D03*
X677778Y449510D03*
X674628Y458959D03*
X680928D03*
X677778Y471557D03*
X674628Y484006D03*
X680299Y960892D03*
Y957546D03*
Y1258727D03*
X687227Y424313D03*
X690376Y427462D03*
X680928Y414864D03*
Y418013D03*
X684077Y421163D03*
X696676Y427462D03*
Y418013D03*
X680928Y433761D03*
X684077Y443210D03*
Y433761D03*
X687227Y455809D03*
X680928Y462108D03*
X696676D03*
X684077Y465258D03*
X680928Y471557D03*
Y477856D03*
X693526Y474707D03*
X699825Y471557D03*
Y474707D03*
X709899Y960892D03*
Y957546D03*
X709999Y1258727D03*
X728172Y421163D03*
X725022Y424313D03*
X728172Y427462D03*
X731322Y421163D03*
X718723Y433761D03*
X725022Y430612D03*
X731322Y440061D03*
X728172Y458959D03*
X721873Y452659D03*
X725022Y458959D03*
X721873Y455809D03*
X718723Y452659D03*
Y462108D03*
Y465258D03*
X721873Y474707D03*
X739699Y780184D03*
Y773491D03*
Y786877D03*
Y803609D03*
Y796916D03*
Y790223D03*
Y847113D03*
Y853806D03*
Y860499D03*
Y863845D03*
Y883924D03*
Y877231D03*
Y870538D03*
Y890617D03*
Y897310D03*
Y900656D03*
Y914042D03*
Y907349D03*
Y960892D03*
Y957546D03*
Y1061286D03*
Y1074672D03*
Y1067979D03*
Y1091404D03*
Y1081365D03*
Y1084711D03*
Y1098097D03*
Y1111483D03*
Y1104790D03*
Y1128215D03*
Y1118176D03*
Y1121522D03*
Y1134908D03*
Y1185105D03*
Y1178412D03*
Y1191798D03*
Y1208530D03*
Y1201837D03*
Y1195144D03*
Y1258727D03*
X755841Y770144D03*
Y776837D03*
Y786877D03*
Y783530D03*
Y800263D03*
Y793570D03*
Y850459D03*
Y843766D03*
Y867192D03*
Y860499D03*
Y857152D03*
Y873885D03*
Y880577D03*
Y887270D03*
Y897310D03*
Y893963D03*
Y910696D03*
Y904003D03*
X755676Y1071326D03*
X755741Y1064633D03*
X755841Y1078018D03*
Y1094751D03*
Y1088058D03*
Y1081365D03*
X755676Y1108137D03*
X755841Y1101444D03*
Y1124869D03*
Y1118176D03*
Y1114829D03*
Y1131562D03*
Y1175066D03*
X755676Y1181759D03*
X755841Y1191798D03*
X755676Y1188452D03*
X755841Y1205184D03*
Y1198491D03*
X769399Y960892D03*
Y957546D03*
Y1258727D03*
X799099Y816995D03*
Y810302D03*
Y833727D03*
Y823688D03*
Y827034D03*
Y840420D03*
Y960892D03*
Y957546D03*
Y967585D03*
Y1221916D03*
Y1215223D03*
Y1238648D03*
Y1228609D03*
Y1231955D03*
Y1245341D03*
Y1258727D03*
X815241Y813648D03*
Y806955D03*
Y820341D03*
Y830381D03*
Y823688D03*
Y837074D03*
Y964239D03*
Y1218570D03*
Y1211877D03*
Y1225263D03*
Y1241995D03*
Y1235302D03*
Y1228609D03*
X828799Y960892D03*
Y957546D03*
Y967585D03*
Y1258727D03*
X844941Y964239D03*
X1003831Y1259077D03*
X1012541Y960892D03*
Y957546D03*
Y967585D03*
X1028683Y964239D03*
X1033541Y1258727D03*
X1042241Y816995D03*
Y810302D03*
Y833727D03*
Y823688D03*
Y827034D03*
Y840420D03*
Y960892D03*
Y957546D03*
Y967585D03*
Y1221916D03*
Y1215223D03*
Y1238648D03*
Y1228609D03*
Y1231955D03*
Y1245341D03*
X1058383Y813648D03*
Y806955D03*
Y820341D03*
Y830381D03*
Y823688D03*
Y837074D03*
Y964239D03*
Y1218570D03*
Y1211877D03*
Y1225263D03*
Y1241995D03*
Y1235302D03*
Y1228609D03*
X1063241Y1258727D03*
X1071941Y960892D03*
Y957546D03*
X1101641Y780184D03*
Y773491D03*
Y786877D03*
Y803609D03*
Y796916D03*
Y790223D03*
Y847113D03*
Y853806D03*
Y860499D03*
Y863845D03*
Y883924D03*
Y877231D03*
Y870538D03*
Y890617D03*
Y897310D03*
Y900656D03*
Y914042D03*
Y907349D03*
Y960892D03*
Y957546D03*
Y1061286D03*
Y1074672D03*
Y1067979D03*
Y1091404D03*
Y1081365D03*
Y1084711D03*
Y1098097D03*
Y1111483D03*
Y1104790D03*
Y1128215D03*
Y1118176D03*
Y1121522D03*
Y1134908D03*
Y1185105D03*
Y1178412D03*
Y1191798D03*
Y1208530D03*
Y1201837D03*
Y1195144D03*
X1092941Y1258727D03*
X1117783Y770144D03*
Y776837D03*
Y786877D03*
Y783530D03*
Y800263D03*
Y793570D03*
Y850459D03*
Y843766D03*
Y867192D03*
Y860499D03*
Y857152D03*
Y873885D03*
Y880577D03*
Y887270D03*
Y897310D03*
Y893963D03*
Y910696D03*
Y904003D03*
Y1071326D03*
Y1064633D03*
Y1078018D03*
Y1094751D03*
Y1088058D03*
Y1081365D03*
Y1108137D03*
Y1101444D03*
Y1124869D03*
Y1118176D03*
Y1114829D03*
Y1131562D03*
Y1175066D03*
Y1181759D03*
Y1191798D03*
Y1188452D03*
Y1205184D03*
Y1198491D03*
X1131341Y960892D03*
Y957546D03*
X1122641Y1258727D03*
X1161041Y960892D03*
Y957546D03*
X1190741Y960892D03*
Y957546D03*
X1196772Y1590094D03*
X1200172D03*
X1212232D03*
X1208832D03*
X1220441Y960892D03*
Y957546D03*
X1220892Y1590094D03*
X1232952D03*
X1224292D03*
X1245012D03*
X1236352D03*
X1248412D03*
X1257072D03*
X1260472D03*
X1269132D03*
X1281192D03*
X1272532D03*
X1293802Y166699D03*
X1296999Y183349D03*
X1297007Y172249D03*
X1296999Y194449D03*
X1293798Y205833D03*
X1293252Y1590094D03*
X1284592D03*
X1296652D03*
X1309817Y175949D03*
X1313027Y181499D03*
X1303407Y175949D03*
X1300207Y196299D03*
X1313027Y192599D03*
X1300207Y207399D03*
X1313027Y203699D03*
X1300220Y222199D03*
X1312503Y1121447D03*
X1305312Y1590094D03*
X1308712D03*
X1315352Y186024D03*
Y179724D03*
X1319442Y174099D03*
X1315405Y189227D03*
X1322652Y209249D03*
X1326869Y851380D03*
X1330569Y844971D03*
X1325020Y848176D03*
X1328720D03*
X1325021Y860993D03*
X1323603Y1121447D03*
X1319903Y1127856D03*
X1316203D03*
X1318054Y1118243D03*
X1321753Y1124651D03*
X1323603Y1127856D03*
X1319903Y1121447D03*
X1316203D03*
X1318053Y1131060D03*
X1317372Y1590094D03*
X1320772D03*
X1329432D03*
X1332421Y841467D03*
X1337969Y844971D03*
X1339821Y841467D03*
X1345369Y844971D03*
X1347221Y841467D03*
X1334269Y844971D03*
X1336120Y848176D03*
X1341669Y844971D03*
X1343520Y848176D03*
X1339820Y860993D03*
X1347220D03*
X1332420D03*
X1347220Y893036D03*
X1345803Y1108630D03*
X1340254Y1105426D03*
X1336554Y1111834D03*
X1334703Y1108630D03*
X1343954Y1111834D03*
X1342103Y1108630D03*
X1338403D03*
X1342103Y1115039D03*
X1345803D03*
X1334703D03*
X1332832Y1590094D03*
X1341492D03*
X1344892D03*
X1355961Y155458D03*
X1363869Y844971D03*
X1352769D03*
X1356469D03*
X1360169D03*
X1362021Y841467D03*
X1349069Y844971D03*
X1350920Y848176D03*
X1354621Y841467D03*
X1358320Y848176D03*
X1362020Y860993D03*
X1354620D03*
X1362020Y873810D03*
X1350920Y899445D03*
X1358320D03*
Y893036D03*
X1350920D03*
X1362020D03*
X1349071Y896240D03*
X1356471D03*
X1352771D03*
X1360171D03*
X1352771Y902649D03*
X1356471D03*
X1350920Y912262D03*
X1352771Y909057D03*
X1358320Y912262D03*
X1356471Y909057D03*
X1349071Y915466D03*
X1356471D03*
X1352771D03*
X1360171D03*
X1350920Y931488D03*
X1352771Y928283D03*
X1358320Y931488D03*
X1356471Y928283D03*
X1352771Y921875D03*
X1350920Y918670D03*
X1356471Y921875D03*
X1358320Y918670D03*
X1356471Y941100D03*
X1358320Y937896D03*
X1352771Y947509D03*
X1356471D03*
X1352771Y941100D03*
X1350920Y937896D03*
X1349071Y934691D03*
X1356471D03*
X1352771D03*
X1360171D03*
X1352771Y960326D03*
X1350920Y957122D03*
X1356471Y960326D03*
X1358320Y957122D03*
X1350920Y950713D03*
X1358320D03*
X1349071Y953917D03*
X1356471D03*
X1352771D03*
X1360171D03*
X1356471Y966735D03*
X1352771D03*
X1350920Y969939D03*
X1358320D03*
X1351353Y1002888D03*
X1353204Y999684D03*
X1358753Y1002888D03*
X1356904Y999684D03*
X1353204Y1012501D03*
X1351353Y1009297D03*
X1356904Y1012501D03*
X1358753Y1009297D03*
X1353204Y1031727D03*
X1351353Y1028523D03*
X1356904Y1031727D03*
X1358753Y1028523D03*
X1351353Y1022114D03*
X1353204Y1018910D03*
X1358753Y1022114D03*
X1356904Y1018910D03*
X1353204Y1025318D03*
X1360604D03*
X1349502D03*
X1356902D03*
X1351353Y1047749D03*
X1358753D03*
X1351353Y1041340D03*
X1353204Y1038136D03*
X1358753Y1041340D03*
X1356904Y1038136D03*
X1349504Y1044544D03*
X1356904D03*
X1353204D03*
X1360604D03*
X1351353Y1060565D03*
X1353204Y1057361D03*
X1358753Y1060565D03*
X1356904Y1057361D03*
X1353204Y1050952D03*
X1356904D03*
X1349504Y1063770D03*
X1360604D03*
X1353204D03*
X1356904D03*
Y1070178D03*
X1358753Y1066974D03*
X1353204Y1070178D03*
X1351353Y1066974D03*
Y1079791D03*
X1353204Y1076587D03*
X1358753Y1079791D03*
X1356904Y1076587D03*
X1353204Y1089404D03*
X1351353Y1086200D03*
X1356904Y1089404D03*
X1358753Y1086200D03*
X1349504Y1082995D03*
X1360604D03*
X1353204D03*
X1356904D03*
X1353552Y1590094D03*
X1356952D03*
X1376820Y848176D03*
X1367569Y844971D03*
X1369421Y841467D03*
X1373120Y848176D03*
X1376821Y841467D03*
X1365720Y848176D03*
X1371269Y844971D03*
X1374969D03*
X1378669D03*
X1376820Y860993D03*
X1369420D03*
Y873810D03*
X1376820Y886627D03*
X1378671Y947509D03*
Y953917D03*
X1374971D03*
X1376822Y950713D03*
X1374971Y973143D03*
X1376820Y976347D03*
X1378671Y979552D03*
Y973143D03*
X1366153Y1002888D03*
X1364304Y999684D03*
X1369853Y1002888D03*
X1371704Y999684D03*
X1375404D03*
Y1025318D03*
X1377253Y1022114D03*
X1379102Y1018910D03*
X1379104Y1025318D03*
X1369853Y1111834D03*
X1368004Y1108630D03*
X1377253Y1099017D03*
X1379104Y1108630D03*
X1373553Y1105426D03*
X1371704Y1108630D03*
X1379104Y1102221D03*
X1377253Y1111834D03*
X1375404Y1108630D03*
Y1115039D03*
X1368004D03*
X1379104D03*
X1365612Y1590094D03*
X1377672D03*
X1369012D03*
X1391620Y848176D03*
X1384220D03*
X1380520D03*
X1386069Y844971D03*
X1389769D03*
X1393469D03*
X1382369D03*
X1384221Y841467D03*
X1387920Y848176D03*
X1391621Y841467D03*
X1395320Y848176D03*
X1384220Y860993D03*
X1391620D03*
Y873810D03*
X1386071Y896240D03*
X1389771D03*
X1393471D03*
X1387920Y899445D03*
X1391620Y893036D03*
X1395320Y899445D03*
X1391620D03*
X1387920Y905853D03*
X1384220D03*
X1382809Y927986D03*
X1385070Y928468D03*
X1392534Y942097D03*
X1394834D03*
X1393826Y956619D03*
X1387826D03*
X1391326D03*
X1385526D03*
X1380926Y971099D03*
X1383226D03*
X1387826D03*
X1385526D03*
X1396346D03*
X1396286Y985549D03*
X1388506Y985609D03*
X1386206D03*
X1386226Y1000079D03*
X1396356Y1000039D03*
X1388526Y1000079D03*
X1396546Y1014469D03*
X1380953Y1099017D03*
X1395753Y1105426D03*
X1393904Y1108630D03*
X1390204Y1102221D03*
X1392053Y1111834D03*
X1388353D03*
X1384653Y1105426D03*
Y1099017D03*
X1392053Y1105426D03*
X1395753Y1111834D03*
X1388353Y1105426D03*
X1384653Y1111834D03*
X1386504Y1108630D03*
X1390204Y1115039D03*
X1381072Y1590094D03*
X1399020Y848176D03*
X1397169Y844971D03*
X1399021Y841467D03*
X1402720Y848176D03*
X1406420D03*
X1411969Y844971D03*
X1400869D03*
X1404569D03*
X1410120Y848176D03*
X1399020Y860993D03*
X1397171Y896240D03*
X1402720Y899445D03*
X1404571Y896240D03*
X1410120Y899445D03*
X1399020Y893036D03*
X1400871Y896240D03*
X1406420Y893036D03*
X1408271Y896240D03*
X1411971D03*
X1406420Y899445D03*
X1399020D03*
X1401528Y927155D03*
X1399028D03*
X1401817Y929464D03*
X1399317D03*
X1406421Y944304D03*
X1408271Y941100D03*
X1411971D03*
X1404016Y944229D03*
Y941929D03*
X1408270Y947509D03*
X1411971D03*
X1406421Y950713D03*
Y957122D03*
X1408270Y953917D03*
Y960326D03*
X1411971Y953917D03*
Y960326D03*
X1404016Y954072D03*
Y956372D03*
X1401326Y956619D03*
X1398826D03*
X1406421Y963530D03*
X1408270Y966735D03*
X1411971D03*
X1406421Y969939D03*
X1406409Y976347D03*
X1408270Y973143D03*
X1411971D03*
X1404016Y971266D03*
Y968966D03*
X1398826Y971099D03*
X1406421Y982756D03*
X1408270Y979552D03*
X1411971D03*
X1404016Y983110D03*
Y985410D03*
X1398826Y985579D03*
X1404016Y997520D03*
X1412404Y999684D03*
Y1006093D03*
Y1012501D03*
X1406853Y1002888D03*
Y1009297D03*
X1408703Y999684D03*
Y1006093D03*
Y1012501D03*
X1404016Y1012151D03*
Y999820D03*
X1398826Y1000059D03*
X1404016Y1014451D03*
X1399156Y1014469D03*
X1406853Y1028523D03*
X1412404Y1018910D03*
X1406853Y1015705D03*
Y1022114D03*
X1408703Y1018910D03*
X1412404Y1025318D03*
X1408703D03*
X1404016Y1026703D03*
X1412404Y1031727D03*
X1408703D03*
X1404016Y1029003D03*
Y1031303D03*
X1412403Y1038136D03*
Y1044544D03*
X1406853Y1034931D03*
Y1041340D03*
X1408703Y1038136D03*
Y1044544D03*
X1410554Y1041340D03*
X1404016Y1033603D03*
X1399426Y1036883D03*
Y1034583D03*
Y1032283D03*
X1410554Y1047749D03*
X1412404Y1050952D03*
Y1057361D03*
Y1063770D03*
Y1070178D03*
Y1076587D03*
X1405003D03*
X1406853Y1079791D03*
X1412404Y1082995D03*
Y1089404D03*
X1412403Y1095813D03*
X1412404Y1102221D03*
Y1108630D03*
Y1115039D03*
Y1121447D03*
Y1127856D03*
X1408703Y1121447D03*
Y1127856D03*
X1412403Y1134264D03*
X1408703D03*
X1413820Y848176D03*
Y893036D03*
X1421220Y899445D03*
X1419371Y896240D03*
X1424920Y899445D03*
X1426772Y896240D03*
X1417520Y899445D03*
X1421220Y893036D03*
X1423071Y896240D03*
X1428621Y893036D03*
X1413821Y944304D03*
X1415671Y941100D03*
X1417521Y944304D03*
X1419371Y941100D03*
X1421220Y944304D03*
X1424921D03*
X1426771Y941100D03*
X1415670Y947509D03*
X1419370D03*
X1426771D03*
X1413821Y950713D03*
Y957122D03*
X1415670Y953917D03*
Y960326D03*
X1417521Y950713D03*
Y957122D03*
X1419370Y953917D03*
Y960326D03*
X1421220Y950713D03*
Y957122D03*
X1424921Y950713D03*
Y957122D03*
X1426771Y953917D03*
Y960326D03*
X1413821Y963530D03*
X1415670Y966735D03*
X1417521Y963530D03*
X1419370Y966735D03*
X1421220Y963530D03*
X1424921D03*
X1426771Y966735D03*
X1413821Y969939D03*
Y976347D03*
X1415670Y973143D03*
X1417521Y969939D03*
Y976347D03*
X1419370Y973143D03*
X1421220Y969939D03*
Y976347D03*
X1424921Y969939D03*
Y976347D03*
X1426771Y973143D03*
X1413821Y982756D03*
X1415670Y979552D03*
X1417521Y982756D03*
X1419370Y979552D03*
X1421220Y982756D03*
X1424921D03*
X1426771Y979552D03*
X1414254Y1002888D03*
Y1009297D03*
X1416103Y999684D03*
Y1006093D03*
Y1012501D03*
X1417954Y1002888D03*
Y1009297D03*
X1419803Y999684D03*
Y1006093D03*
Y1012501D03*
X1421653Y1002888D03*
Y1009297D03*
X1425354Y1002888D03*
Y1009297D03*
X1427203Y999684D03*
Y1006093D03*
Y1012501D03*
X1421653Y1028523D03*
X1414254D03*
X1417954D03*
X1425354D03*
X1414254Y1015705D03*
Y1022114D03*
X1416103Y1018910D03*
X1417954Y1015705D03*
Y1022114D03*
X1419803Y1018910D03*
X1421653Y1015705D03*
Y1022114D03*
X1425354Y1015705D03*
Y1022114D03*
X1427203Y1018910D03*
X1416103Y1025318D03*
X1419803D03*
X1427203D03*
X1416103Y1031727D03*
X1419803D03*
X1427203D03*
X1414254Y1034931D03*
Y1041340D03*
X1416103Y1038136D03*
Y1044544D03*
X1417954Y1034931D03*
Y1041340D03*
X1419803Y1038136D03*
Y1044544D03*
X1421653Y1034931D03*
Y1041340D03*
X1423503Y1044544D03*
X1425354Y1034931D03*
X1425353Y1041340D03*
X1427203Y1038136D03*
X1421653Y1047749D03*
X1414254D03*
X1417954D03*
X1414254Y1054157D03*
X1416103Y1050952D03*
X1417954Y1054157D03*
X1419803Y1050952D03*
X1421653Y1054157D03*
X1414254Y1060565D03*
X1416103Y1057361D03*
X1417954Y1060565D03*
X1419803Y1057361D03*
X1421653Y1060565D03*
X1416103Y1063770D03*
X1419803D03*
X1414254Y1066974D03*
Y1073383D03*
X1416103Y1070178D03*
Y1076587D03*
X1417954Y1066974D03*
Y1073383D03*
X1419803Y1070178D03*
Y1076587D03*
X1421653Y1066974D03*
Y1073383D03*
X1414254Y1079791D03*
X1417954D03*
X1421653D03*
X1416103Y1082995D03*
X1419803D03*
X1414254Y1086200D03*
Y1092608D03*
X1416103Y1089404D03*
Y1095813D03*
X1417954Y1086200D03*
Y1092608D03*
X1419803Y1089404D03*
Y1095813D03*
X1421653Y1086200D03*
Y1092608D03*
X1423503Y1089404D03*
Y1095813D03*
X1425353Y1092608D03*
X1414254Y1099017D03*
Y1105426D03*
Y1111834D03*
X1416103Y1102221D03*
Y1108630D03*
X1417954Y1099017D03*
Y1105426D03*
Y1111834D03*
X1419803Y1102221D03*
Y1108630D03*
X1421653Y1099017D03*
Y1105426D03*
Y1111834D03*
X1425354Y1099017D03*
Y1105426D03*
Y1111834D03*
X1427203Y1102221D03*
Y1108630D03*
X1429054Y1105426D03*
Y1111834D03*
X1414254Y1118243D03*
Y1124651D03*
X1416103Y1115039D03*
Y1121447D03*
Y1127856D03*
X1417954Y1118243D03*
Y1124651D03*
X1419803Y1115039D03*
Y1121447D03*
Y1127856D03*
X1421653Y1118243D03*
Y1124651D03*
X1425354Y1118243D03*
Y1124651D03*
X1427203Y1115039D03*
Y1121447D03*
Y1127856D03*
X1429054Y1118243D03*
Y1124651D03*
X1414254Y1131060D03*
Y1137769D03*
X1416103Y1134264D03*
X1417954Y1131060D03*
Y1137769D03*
X1419803Y1134264D03*
X1421653Y1131060D03*
Y1137769D03*
X1425354Y1131060D03*
Y1137769D03*
X1427203Y1134264D03*
X1429054Y1131060D03*
Y1137769D03*
X1430471Y896240D03*
X1436020Y893036D03*
X1437871Y896240D03*
X1441571D03*
X1432320Y899445D03*
X1434171Y896240D03*
X1439720Y899445D03*
X1443420Y893036D03*
X1429726Y944537D03*
Y939937D03*
Y942237D03*
X1429544Y959298D03*
Y956998D03*
X1437565Y956619D03*
X1434545D03*
X1445045D03*
X1429544Y970798D03*
Y973098D03*
X1437565Y971139D03*
X1434545Y971099D03*
X1429544Y986898D03*
Y984598D03*
X1437565Y985579D03*
X1434545D03*
X1445045D03*
X1429544Y998398D03*
Y1012198D03*
Y1000698D03*
X1437565Y1000079D03*
X1434545D03*
X1445045D03*
X1429544Y1014498D03*
X1437436Y1014509D03*
X1434545Y1014539D03*
X1445036Y1014549D03*
X1443854Y1054157D03*
Y1060565D03*
X1442004Y1076587D03*
X1430903Y1102221D03*
Y1108630D03*
X1432754Y1105426D03*
X1432753Y1111834D03*
X1434603Y1108630D03*
X1436454Y1111834D03*
X1430903Y1115039D03*
Y1121447D03*
Y1127856D03*
X1432753Y1118243D03*
Y1124651D03*
X1436454Y1118243D03*
Y1124651D03*
X1438303Y1115039D03*
Y1121447D03*
Y1127856D03*
X1440153Y1118243D03*
X1440154Y1124651D03*
X1442003Y1127856D03*
X1443854Y1131060D03*
Y1137469D03*
X1430903Y1134264D03*
Y1140973D03*
X1432753Y1131060D03*
X1432754Y1137469D03*
X1434603Y1140973D03*
X1436454Y1131060D03*
Y1137469D03*
X1438303Y1134264D03*
Y1140973D03*
X1440154Y1131060D03*
Y1137469D03*
X1442003Y1134264D03*
Y1140973D03*
X1456371Y947509D03*
Y953917D03*
X1454520Y957122D03*
Y950713D03*
X1447545Y956619D03*
X1450045Y971099D03*
X1445445D03*
X1447745D03*
X1452426Y973825D03*
Y971525D03*
X1447545Y985579D03*
X1454953Y1009297D03*
X1447545Y1000079D03*
X1447345Y1014539D03*
X1454953Y1028523D03*
Y1022114D03*
X1456803Y1018910D03*
X1454953Y1015705D03*
X1446934Y1028889D03*
X1452466Y1031794D03*
Y1029494D03*
Y1027194D03*
X1454953Y1047749D03*
X1453104Y1044544D03*
X1456804Y1063770D03*
X1458653Y1054157D03*
X1454954D03*
X1453104Y1057361D03*
Y1063770D03*
X1454954Y1060565D03*
X1456803Y1057361D03*
X1453103Y1050952D03*
X1445703Y1057361D03*
X1445704Y1063770D03*
X1447554Y1060565D03*
X1449403Y1057361D03*
X1449404Y1063770D03*
X1451254Y1054157D03*
X1445703Y1050952D03*
X1449404D03*
X1451253Y1073383D03*
X1445703Y1134264D03*
X1476720Y899445D03*
Y912262D03*
X1474871Y909057D03*
Y902649D03*
X1476720Y905853D03*
X1473020D03*
X1476720Y931488D03*
X1474871Y921875D03*
X1476720Y918670D03*
X1474871Y928283D03*
X1473020Y925079D03*
X1476720D03*
X1474871Y947509D03*
Y941100D03*
X1476720Y937896D03*
X1473020Y944304D03*
X1476720D03*
Y950713D03*
Y957122D03*
X1474871Y960326D03*
X1463771Y979552D03*
X1461920Y976347D03*
X1467471Y979552D03*
X1469320Y976347D03*
X1477153Y1002888D03*
X1475304Y999684D03*
Y1031727D03*
X1477153Y1028523D03*
Y1041340D03*
X1475304Y1038136D03*
X1477153Y1047749D03*
Y1034931D03*
X1473453D03*
X1477153Y1060565D03*
X1475304Y1057361D03*
Y1050952D03*
X1477153Y1054157D03*
X1473453D03*
X1475304Y1070178D03*
X1477153Y1066974D03*
Y1079791D03*
X1475304Y1076587D03*
X1473453Y1073383D03*
X1477153D03*
X1475304Y1089404D03*
X1477153Y1086200D03*
X1473453Y1092608D03*
X1477153D03*
X1467595Y1614292D03*
X1470995D03*
X1480420Y899445D03*
Y912262D03*
X1482271Y909057D03*
Y902649D03*
X1484120Y905853D03*
X1480420D03*
X1482271Y928283D03*
Y921875D03*
X1480420Y918670D03*
Y931488D03*
Y925079D03*
X1484120D03*
X1482271Y947509D03*
Y941100D03*
X1480420Y937896D03*
X1484120Y944304D03*
X1480420D03*
Y950713D03*
Y957122D03*
X1482271Y960326D03*
X1480853Y1002888D03*
X1482703Y999684D03*
X1493803D03*
X1488253Y1002888D03*
X1490104Y999684D03*
X1482704Y1031727D03*
X1480853Y1028523D03*
Y1041340D03*
X1482704Y1038136D03*
X1480853Y1047749D03*
X1484553Y1034931D03*
X1480853D03*
Y1060565D03*
X1482704Y1057361D03*
Y1050952D03*
X1484553Y1054157D03*
X1480853D03*
Y1079791D03*
X1482704Y1076587D03*
Y1070178D03*
X1480853Y1066974D03*
X1484553Y1073383D03*
X1480853D03*
X1486404Y1095813D03*
X1482703D03*
X1482704Y1089404D03*
X1480853Y1086200D03*
X1484553Y1092608D03*
X1480853D03*
X1493804Y1102221D03*
X1491953Y1099017D03*
X1491715Y1614292D03*
X1479655D03*
X1483055D03*
X1508171Y864197D03*
X1510021Y854584D03*
X1495655Y1002888D03*
X1506753D03*
X1508603Y999684D03*
X1503053Y1002888D03*
X1501204Y999684D03*
X1508603Y1140973D03*
X1504903D03*
X1503775Y1614292D03*
X1507175D03*
X1495115D03*
X1519271Y851380D03*
X1515571D03*
X1511871Y864197D03*
X1519270D03*
X1522970D03*
X1511871Y857789D03*
X1519271D03*
X1515571D03*
X1517421Y860993D03*
Y854584D03*
X1515835Y1614292D03*
X1519235D03*
X1527895D03*
X1539955D03*
X1531295D03*
X1552015D03*
X1555415D03*
X1543355D03*
X1564075D03*
X1567475D03*
X1588195D03*
X1576135D03*
X1591595D03*
X1579535D03*
X1596941Y960892D03*
Y957546D03*
X1600255Y1614292D03*
X1603655D03*
X1612315D03*
X1615715D03*
X1626641Y960892D03*
Y957546D03*
X1636435Y1614292D03*
X1624375D03*
X1639835D03*
X1627775D03*
X1656441Y960892D03*
Y957546D03*
X1651895Y1614292D03*
X1648495D03*
X1686041Y960892D03*
Y957546D03*
X1715841Y780184D03*
Y773491D03*
Y786877D03*
Y803609D03*
Y796916D03*
Y790223D03*
Y847113D03*
Y853806D03*
Y860499D03*
Y863845D03*
Y883924D03*
Y877231D03*
Y870538D03*
Y890617D03*
Y897310D03*
Y900656D03*
Y914042D03*
Y907349D03*
Y960892D03*
Y957546D03*
Y1061286D03*
Y1074672D03*
Y1067979D03*
Y1091404D03*
Y1081365D03*
Y1084711D03*
Y1098097D03*
Y1111483D03*
Y1104790D03*
Y1128215D03*
Y1118176D03*
Y1121522D03*
Y1134908D03*
Y1185105D03*
Y1178412D03*
Y1191798D03*
Y1208530D03*
Y1201837D03*
Y1195144D03*
X1731983Y770144D03*
Y776837D03*
Y786877D03*
Y783530D03*
Y800263D03*
Y793570D03*
Y850459D03*
Y843766D03*
Y867192D03*
Y860499D03*
Y857152D03*
Y873885D03*
Y880577D03*
Y887270D03*
Y897310D03*
Y893963D03*
Y910696D03*
Y904003D03*
X1731818Y1071326D03*
X1731883Y1064633D03*
X1731983Y1078018D03*
Y1094751D03*
Y1088058D03*
Y1081365D03*
X1731818Y1108137D03*
X1731983Y1101444D03*
Y1124869D03*
Y1118176D03*
Y1114829D03*
Y1131562D03*
Y1175066D03*
X1731818Y1181759D03*
X1731983Y1191798D03*
X1731818Y1188452D03*
X1731983Y1205184D03*
Y1198491D03*
X1745541Y960892D03*
Y957546D03*
X1775241Y816995D03*
Y810302D03*
Y833727D03*
Y823688D03*
Y827034D03*
Y840420D03*
Y960892D03*
Y957546D03*
Y967585D03*
Y1221916D03*
Y1215223D03*
Y1238648D03*
Y1228609D03*
Y1231955D03*
Y1245341D03*
X1791383Y813648D03*
Y806955D03*
Y820341D03*
Y830381D03*
Y823688D03*
Y837074D03*
Y964239D03*
Y1218570D03*
Y1211877D03*
Y1225263D03*
Y1241995D03*
Y1235302D03*
Y1228609D03*
X1804941Y960892D03*
Y957546D03*
Y967585D03*
X1821083Y964239D03*
G54D30*
G01X326940Y1011170D02*
X317432D01*
X307965Y1015091D01*
X304891D01*
X304016Y1015966D01*
X280912D01*
X280036Y1015090D01*
X261714D01*
X261713Y1015091D01*
X58641D01*
X48370Y1004820D01*
Y995720D01*
X39770Y987120D01*
X35770D01*
X31270Y982620D01*
Y966021D01*
X36399Y960892D01*
G01X327525Y969370D02*
X324389D01*
X318506Y963487D01*
X286888D01*
X285745Y964630D01*
X274612D01*
X264703Y954721D01*
X258648D01*
X253102Y949175D01*
X247555D01*
X247111Y949619D01*
X232809D01*
X232009Y948819D01*
X219334D01*
X215978Y945463D01*
X212123D01*
X208409Y949177D01*
X114643D01*
X113728Y948262D01*
X100513D01*
X97771Y945520D01*
X95208D01*
X88205Y952523D01*
X63267D01*
X58970Y956820D01*
Y960119D01*
X55896Y963193D01*
X55299Y964634D01*
X54008Y965925D01*
X49847D01*
X49127Y966645D01*
Y968625D01*
X48407Y969345D01*
X47017D01*
X46297Y968625D01*
Y966645D01*
X45577Y965925D01*
X42838D01*
X41178Y967585D01*
X36399D01*
G01X327121Y1009210D02*
X318711D01*
X309351Y1013087D01*
X280037D01*
X280036Y1013086D01*
X261714D01*
X261713Y1013087D01*
X59944D01*
X50697Y1003840D01*
Y991447D01*
X40770Y981520D01*
X35770D01*
X33770Y979520D01*
Y966920D01*
X34781Y965909D01*
X37078D01*
X39721Y963266D01*
Y960868D01*
X36399Y957546D01*
G01X327524Y968001D02*
X324916D01*
X319069Y962154D01*
X275000D01*
X265477Y952631D01*
X259444D01*
X253481Y946668D01*
X249908D01*
X249084Y945844D01*
X233844D01*
X233302Y946386D01*
X219709D01*
X216801Y943478D01*
X206319D01*
X203967Y945830D01*
X200735D01*
X200732Y945833D01*
X188939D01*
X188937Y945831D01*
X147800D01*
X147080Y945111D01*
Y943265D01*
X146360Y942545D01*
X145080D01*
X144360Y943265D01*
Y945111D01*
X143640Y945831D01*
X118777D01*
X114708Y941762D01*
X109061D01*
X108341Y942482D01*
Y945411D01*
X107621Y946131D01*
X106341D01*
X105621Y945411D01*
Y942482D01*
X104901Y941762D01*
X100545D01*
X98877Y943430D01*
X94488D01*
X88741Y949177D01*
X68221D01*
X68220Y949176D01*
X59814D01*
X54570Y954420D01*
Y961079D01*
X53770Y963010D01*
X52541Y964239D01*
G01X327121Y1007249D02*
X319421D01*
X310389Y1010990D01*
X280037D01*
X280036Y1010989D01*
X261714D01*
X261713Y1010990D01*
X80864D01*
X77860Y1007986D01*
X64657D01*
X60849Y1004178D01*
Y1001664D01*
X60129Y1000944D01*
X56158D01*
X55438Y1000224D01*
Y998944D01*
X56158Y998224D01*
X60129D01*
X60849Y997504D01*
Y996224D01*
X60129Y995504D01*
X56158D01*
X55438Y994784D01*
Y993504D01*
X56158Y992784D01*
X60129D01*
X60849Y992064D01*
Y963171D01*
X63128Y960892D01*
X66099D01*
G01X324723Y897046D02*
X308691D01*
X296964Y885319D01*
Y874783D01*
X263879Y841698D01*
X262432Y838205D01*
X258106Y833879D01*
X257214Y831726D01*
X253493Y826158D01*
X252154Y824819D01*
X236720D01*
X233792Y821891D01*
X219790D01*
X216118Y818219D01*
X213042D01*
X206798Y811975D01*
X198208D01*
X194859Y815324D01*
X173178D01*
X172242Y814388D01*
X168281D01*
X167372Y815297D01*
X165651D01*
X164742Y814388D01*
X159628D01*
X157212Y811972D01*
X139409D01*
X137188Y814193D01*
X132571D01*
X131440Y815324D01*
X125154D01*
X125150Y815328D01*
X93405D01*
X92775Y815958D01*
Y817268D01*
X92145Y817898D01*
X90675D01*
X90045Y817268D01*
Y815958D01*
X89415Y815328D01*
X79337D01*
X78590Y814581D01*
X74332D01*
X73612Y813861D01*
Y812828D01*
X72892Y812108D01*
X71612D01*
X70892Y812828D01*
Y813861D01*
X70172Y814581D01*
X68513D01*
X66099Y816995D01*
G01X324723Y893126D02*
X310691D01*
X301043Y883478D01*
Y873069D01*
X268769Y840795D01*
X265200Y832178D01*
X261967Y828945D01*
X260774D01*
X259362Y827533D01*
Y825917D01*
X253048Y819603D01*
X249424D01*
X248240Y818419D01*
X239527D01*
X236896Y815788D01*
X233438D01*
X232269Y814619D01*
X219619D01*
X216519Y811519D01*
X213356D01*
X207119Y805282D01*
X198429D01*
X195080Y808631D01*
X183530D01*
X182143Y810018D01*
X173715D01*
X172328Y808631D01*
X161839D01*
X158492Y805284D01*
X140232D01*
X139448Y806068D01*
X136752D01*
X134189Y808631D01*
X77580D01*
X76908Y807959D01*
X74605D01*
X73885Y807239D01*
Y806162D01*
X73165Y805442D01*
X71885D01*
X71165Y806162D01*
Y807239D01*
X70445Y807959D01*
X68442D01*
X66099Y810302D01*
G01X325323Y907326D02*
X302852D01*
X286093Y890567D01*
Y878710D01*
X265107Y857724D01*
X259452D01*
X257084Y855356D01*
Y853564D01*
X252863Y849343D01*
X248980D01*
X245676Y846039D01*
X244008D01*
X239628Y841659D01*
X234583D01*
X231443Y838519D01*
X220019D01*
X215788Y834288D01*
X205383D01*
X204274Y835397D01*
X197682D01*
X194330Y838749D01*
X175350D01*
X172001Y835400D01*
X169020D01*
X168300Y834680D01*
Y833391D01*
X167580Y832671D01*
X166300D01*
X165580Y833391D01*
Y834680D01*
X164860Y835400D01*
X131490D01*
X128144Y838746D01*
X123938D01*
X120436Y835244D01*
X115019D01*
X114154Y836109D01*
X108996D01*
X108276Y835389D01*
Y834907D01*
X107556Y834187D01*
X106276D01*
X105556Y834907D01*
Y835389D01*
X104836Y836109D01*
X99956D01*
X98586Y834739D01*
X83966D01*
X83308Y835397D01*
X74648D01*
X73928Y836117D01*
Y837334D01*
X73208Y838054D01*
X71928D01*
X71208Y837334D01*
Y836117D01*
X70488Y835397D01*
X67768D01*
X66099Y833727D01*
G01X325323Y902186D02*
X305443D01*
X291527Y888270D01*
Y876826D01*
X264812Y850111D01*
X260987D01*
X257752Y846875D01*
X254364Y838700D01*
X252206Y836541D01*
X249013Y835219D01*
X248747Y834577D01*
X246751Y833751D01*
X246111Y834016D01*
X241607Y832151D01*
X234790D01*
X231943Y830971D01*
X229825Y830550D01*
X229440Y829973D01*
X227320Y829552D01*
X226744Y829937D01*
X219905Y828577D01*
X216976Y827365D01*
X212502D01*
X212012Y826875D01*
X209852D01*
X209362Y827365D01*
X207202D01*
X206205Y826368D01*
X202877D01*
X201867Y825358D01*
X200218D01*
X199198Y826378D01*
X196402D01*
X194179Y828600D01*
X191257Y829811D01*
X186811D01*
X185712Y828712D01*
X184104D01*
X183023Y829793D01*
X180346D01*
X178513Y827960D01*
Y827267D01*
X176985Y825739D01*
X176292D01*
X174489Y823936D01*
X172329D01*
X171839Y823446D01*
X169679D01*
X169189Y823936D01*
X167029D01*
X166539Y823446D01*
X164379D01*
X163889Y823936D01*
X161119D01*
X155274Y826356D01*
X153114D01*
X152624Y825866D01*
X150464D01*
X149974Y826356D01*
X143575D01*
X142580Y825361D01*
X140763D01*
X139777Y826347D01*
X136713D01*
X134915Y828144D01*
X133375Y828784D01*
X129684D01*
X128771Y829697D01*
X127427D01*
X126438Y828708D01*
X124621D01*
X123545Y829784D01*
X122179D01*
X120849Y829232D01*
X117871Y826255D01*
X111929Y823793D01*
X108149D01*
X107659Y823303D01*
X105499D01*
X105009Y823793D01*
X102240D01*
X96014Y826374D01*
X92698D01*
X92208Y825884D01*
X90048D01*
X89558Y826374D01*
X84193D01*
X83180Y825361D01*
X81363D01*
X80377Y826347D01*
X77729D01*
X76214Y824834D01*
X73731Y823805D01*
X72175D01*
X69999Y824706D01*
X67117D01*
X66099Y823688D01*
G01X325323Y903406D02*
X304937D01*
X290307Y888776D01*
Y877332D01*
X264306Y851331D01*
X260481D01*
X256717Y847567D01*
X253329Y839392D01*
X251514Y837576D01*
X241364Y833371D01*
X234547D01*
X231587Y832145D01*
X219549Y829751D01*
X216733Y828585D01*
X206696D01*
X205699Y827588D01*
X202949D01*
X201831Y828706D01*
X200216D01*
X199108Y827598D01*
X196908D01*
X194871Y829635D01*
X191500Y831031D01*
X186726D01*
X185706Y832051D01*
X184051D01*
X183013Y831013D01*
X179840D01*
X173983Y825156D01*
X161362D01*
X155518Y827576D01*
X143626D01*
X142495Y828707D01*
X140861D01*
X139721Y827567D01*
X137219D01*
X135607Y829179D01*
X133619Y830004D01*
X130190D01*
X129277Y830917D01*
X127525D01*
X127482Y830960D01*
X127447D01*
X126353Y832054D01*
X124719D01*
X123669Y831004D01*
X121936D01*
X120157Y830267D01*
X117179Y827290D01*
X114432Y826151D01*
X111686Y825013D01*
X102483D01*
X96258Y827594D01*
X84208D01*
X83095Y828707D01*
X81461D01*
X80321Y827567D01*
X77223D01*
X75523Y825869D01*
X73487Y825025D01*
X72418D01*
X70243Y825926D01*
X67207D01*
X66099Y827034D01*
G01X325324Y911246D02*
X301059D01*
X281774Y891961D01*
Y880919D01*
X262869Y862014D01*
X257187D01*
X250867Y855694D01*
X249209D01*
X247493Y853978D01*
X244941D01*
X239024Y848061D01*
X234605D01*
X231195Y844651D01*
X218777D01*
X215624Y841498D01*
X211719D01*
X210999Y842218D01*
Y844342D01*
X210279Y845062D01*
X208999D01*
X208279Y844342D01*
Y842218D01*
X207559Y841498D01*
X204520D01*
X203928Y842090D01*
X198909D01*
X196409Y844590D01*
X186437D01*
X185585Y845442D01*
X184223D01*
X183433Y844652D01*
X178472D01*
X177682Y845442D01*
X175411D01*
X172061Y842092D01*
X131491D01*
X129519Y844064D01*
X127637D01*
X126262Y845439D01*
X123938D01*
X120297Y841798D01*
X115484D01*
X113006Y844276D01*
X101089D01*
X98222Y841409D01*
X85168D01*
X84487Y842090D01*
X80089D01*
X79369Y842810D01*
Y844137D01*
X78649Y844857D01*
X77369D01*
X76649Y844137D01*
Y842810D01*
X75929Y842090D01*
X74649D01*
X73929Y842810D01*
Y844137D01*
X73209Y844857D01*
X71929D01*
X71209Y844137D01*
Y842810D01*
X70489Y842090D01*
X67769D01*
X66099Y840420D01*
G01X327121Y1005247D02*
X319523D01*
X319421Y1005289D01*
X319370Y1005268D01*
X311126Y1008682D01*
X310746Y1008840D01*
X310617Y1008893D01*
X280037D01*
X280036Y1008892D01*
X261714D01*
X261713Y1008893D01*
X100929D01*
X100209Y1008173D01*
Y1006859D01*
X99489Y1006139D01*
X98209D01*
X97489Y1006859D01*
Y1008173D01*
X96769Y1008893D01*
X95489D01*
X94769Y1008173D01*
Y1006859D01*
X94049Y1006139D01*
X92769D01*
X92049Y1006859D01*
Y1008173D01*
X91329Y1008893D01*
X90049D01*
X89329Y1008173D01*
Y1006859D01*
X88609Y1006139D01*
X87329D01*
X86609Y1006859D01*
Y1008173D01*
X85889Y1008893D01*
X82730D01*
X79550Y1005713D01*
X65350D01*
X62916Y1003279D01*
Y965059D01*
X65413Y962562D01*
X67542D01*
X68285Y961819D01*
Y959732D01*
X66099Y957546D01*
G01X328821Y972439D02*
X323720D01*
X317438Y966157D01*
X289017D01*
X286255Y968919D01*
X273053D01*
X263090Y958956D01*
X256011D01*
X252917Y955862D01*
X237654D01*
X236997Y956519D01*
X231983D01*
X231334Y955870D01*
X220397D01*
X216861Y952334D01*
X213469D01*
X209556Y956247D01*
X204146D01*
X203769Y955870D01*
X196881D01*
X196434Y955423D01*
X186255D01*
X185808Y955870D01*
X167928D01*
X166099Y957699D01*
X161699D01*
X159162Y955162D01*
X157037D01*
X156329Y955870D01*
X153447D01*
X152938Y956379D01*
X144554D01*
X144045Y955870D01*
X140580D01*
X139929Y955219D01*
X132536D01*
X131885Y955870D01*
X100685D01*
X97150Y952335D01*
X94922D01*
X92469Y954788D01*
Y956398D01*
X88755Y965367D01*
X88213Y965909D01*
X79767D01*
X77298Y968378D01*
X73578Y969919D01*
X71734D01*
X67454Y968146D01*
X66099Y967585D01*
G01X328123Y1093767D02*
X327344D01*
X317627Y1097792D01*
X261065Y1154354D01*
X259296D01*
X249303Y1164347D01*
X239941D01*
X238770Y1165518D01*
X235828D01*
X231701Y1169645D01*
X229917D01*
X223180Y1176382D01*
X220642D01*
X217070Y1179954D01*
Y1182036D01*
X215447Y1183659D01*
X213463D01*
X210343Y1186779D01*
X196211D01*
X189570Y1193420D01*
Y1196321D01*
X185727Y1200164D01*
X182326D01*
X179569Y1202921D01*
X175769D01*
X172331Y1206359D01*
X170679D01*
X164156Y1212882D01*
X162076D01*
X158060Y1216898D01*
X155013D01*
X153779Y1215664D01*
X152293D01*
X151059Y1216898D01*
X149573D01*
X148339Y1215664D01*
X146853D01*
X145619Y1216898D01*
X130956D01*
X127607Y1213549D01*
X80093D01*
X79373Y1212829D01*
Y1208961D01*
X78653Y1208241D01*
X77442D01*
X76653Y1209030D01*
Y1212829D01*
X75933Y1213549D01*
X74653D01*
X73933Y1212829D01*
Y1211080D01*
X73213Y1210360D01*
X71933D01*
X71213Y1211080D01*
Y1212829D01*
X70493Y1213549D01*
X67773D01*
X66099Y1215223D01*
G01X328727Y1098175D02*
X327668D01*
X320503Y1101143D01*
X265507Y1156139D01*
Y1159226D01*
X262200Y1162533D01*
X259976D01*
X252766Y1169743D01*
X248845D01*
X248406Y1170182D01*
X240414D01*
X237680Y1172916D01*
X235071D01*
X231848Y1176139D01*
X230211D01*
X224742Y1181608D01*
Y1185174D01*
X222523Y1187393D01*
X219788D01*
X216198Y1190983D01*
X212145D01*
X206310Y1196818D01*
X197772D01*
X194829Y1199761D01*
X191883D01*
X190070Y1201574D01*
Y1203422D01*
X186635Y1206857D01*
X181533D01*
X178658Y1209732D01*
X175426D01*
X172056Y1213102D01*
X170910D01*
X164294Y1219718D01*
X161480D01*
X157607Y1223591D01*
X152502D01*
X151573Y1224520D01*
X149872D01*
X148943Y1223591D01*
X139854D01*
X139224Y1224221D01*
Y1225050D01*
X138594Y1225680D01*
X137124D01*
X136494Y1225050D01*
Y1224221D01*
X135864Y1223591D01*
X131622D01*
X130294Y1223041D01*
X127495Y1220242D01*
X100927D01*
X97804Y1223365D01*
X87635D01*
X84512Y1220242D01*
X79361D01*
X78641Y1220962D01*
Y1225710D01*
X77921Y1226430D01*
X76641D01*
X75921Y1225710D01*
Y1220962D01*
X75201Y1220242D01*
X67773D01*
X66099Y1221916D01*
G01X332922Y1110144D02*
X331160D01*
X272424Y1168880D01*
Y1176859D01*
X262514Y1186769D01*
X258921D01*
X254570Y1191120D01*
X248143D01*
X247148Y1190125D01*
X241275D01*
X240025Y1191375D01*
Y1192265D01*
X240622Y1192862D01*
Y1193752D01*
X239581Y1194793D01*
X238691D01*
X238094Y1194196D01*
X237204D01*
X231781Y1199619D01*
X230022D01*
X223082Y1206559D01*
X220007D01*
X216785Y1209781D01*
X213902D01*
X206786Y1216897D01*
X200100D01*
X190061Y1226936D01*
X180952D01*
X177794Y1230094D01*
X176036D01*
X172076Y1234054D01*
X167498D01*
X165136Y1236416D01*
X160658D01*
X157336Y1239738D01*
X154600D01*
X147324Y1247014D01*
X137403D01*
X134057Y1243668D01*
X122742D01*
X118912Y1239838D01*
X115695D01*
X112567Y1236710D01*
X101525D01*
X97913Y1240322D01*
X76988D01*
X74540Y1242770D01*
X70221D01*
X66099Y1238648D01*
G01X330923Y1104924D02*
X328284D01*
X325056Y1108152D01*
X324363D01*
X322835Y1109680D01*
Y1110373D01*
X321308Y1111900D01*
X320615D01*
X319087Y1113428D01*
Y1114121D01*
X317560Y1115648D01*
X316867D01*
X315339Y1117176D01*
Y1117869D01*
X313812Y1119396D01*
X313119D01*
X311591Y1120924D01*
Y1121617D01*
X310064Y1123144D01*
X309371D01*
X307843Y1124672D01*
Y1125365D01*
X306316Y1126892D01*
X305623D01*
X304095Y1128420D01*
Y1129113D01*
X302568Y1130640D01*
X301875D01*
X300347Y1132168D01*
Y1132861D01*
X298820Y1134388D01*
X298127D01*
X296599Y1135916D01*
Y1136609D01*
X295072Y1138136D01*
X294379D01*
X292851Y1139664D01*
Y1140357D01*
X291324Y1141884D01*
X290631D01*
X289103Y1143412D01*
Y1144105D01*
X287576Y1145632D01*
X286883D01*
X285355Y1147160D01*
Y1147853D01*
X266016Y1167192D01*
Y1175198D01*
X263500Y1177714D01*
X262236D01*
X261264Y1176742D01*
X259708D01*
X258538Y1177912D01*
X254791D01*
X252567Y1180136D01*
X249222D01*
X248203Y1181155D01*
X246363D01*
X245293Y1180085D01*
X243322D01*
X242340Y1181067D01*
X240221D01*
X237676Y1183611D01*
X234818Y1184795D01*
X229942Y1189671D01*
X229130Y1191627D01*
X222808Y1197949D01*
X212589Y1202186D01*
X207929Y1206846D01*
X205430Y1207882D01*
X203161D01*
X202136Y1206857D01*
X200163D01*
X199229Y1207791D01*
X197068D01*
X194472Y1210386D01*
X192000Y1211410D01*
X189090Y1214321D01*
Y1216855D01*
X188023Y1217922D01*
X187019D01*
X185994Y1216897D01*
X184021D01*
X183040Y1217878D01*
X181549D01*
X179528Y1219898D01*
X175803Y1221441D01*
X173216Y1224026D01*
X153065Y1232373D01*
X148705Y1236733D01*
X145643Y1238001D01*
X143521D01*
X142495Y1236975D01*
X140764D01*
X139807Y1237932D01*
X138506D01*
X135941Y1235366D01*
X134536Y1234784D01*
X127524D01*
X126368Y1233628D01*
X124621D01*
X123654Y1234595D01*
X122176D01*
X118410Y1230828D01*
X113265Y1228698D01*
X102861D01*
X96421Y1231365D01*
X84196D01*
X83113Y1230282D01*
X81476D01*
X80444Y1231314D01*
X78022D01*
X76094Y1229385D01*
X74677Y1228799D01*
X72108D01*
X69996Y1229673D01*
X67163D01*
X66099Y1228609D01*
G01X330923Y1106144D02*
X328790D01*
X267236Y1167698D01*
Y1175704D01*
X264006Y1178934D01*
X262329D01*
X261170Y1180093D01*
X259692D01*
X258731Y1179132D01*
X255297D01*
X253073Y1181356D01*
X249728D01*
X248709Y1182375D01*
X246360D01*
X245303Y1183432D01*
X243419D01*
X242274Y1182287D01*
X240727D01*
X238368Y1184646D01*
X235510Y1185830D01*
X230977Y1190363D01*
X230167Y1192317D01*
X223500Y1198984D01*
X213281Y1203221D01*
X208622Y1207880D01*
X205673Y1209102D01*
X203246D01*
X202145Y1210203D01*
X200261D01*
X199069Y1209011D01*
X197574D01*
X195164Y1211421D01*
X192692Y1212445D01*
X190310Y1214827D01*
Y1217361D01*
X188529Y1219142D01*
X187104D01*
X186002Y1220244D01*
X184120D01*
X182974Y1219098D01*
X182055D01*
X180220Y1220933D01*
X176494Y1222476D01*
X173907Y1225061D01*
X153757Y1233408D01*
X149398Y1237767D01*
X145886Y1239221D01*
X143526D01*
X142425Y1240322D01*
X140861D01*
X139691Y1239152D01*
X138000D01*
X135249Y1236401D01*
X134292Y1236004D01*
X127393D01*
X126423Y1236974D01*
X124719D01*
X123560Y1235815D01*
X121670D01*
X117718Y1231863D01*
X113022Y1229918D01*
X103104D01*
X96664Y1232585D01*
X84121D01*
X83077Y1233629D01*
X81533D01*
X80438Y1232534D01*
X77516D01*
X75402Y1230420D01*
X74434Y1230019D01*
X72351D01*
X70240Y1230893D01*
X67161D01*
X66099Y1231955D01*
G01X330758Y1116197D02*
X276780Y1170175D01*
Y1178484D01*
X266867Y1188397D01*
Y1191588D01*
X261637Y1196818D01*
X258872D01*
X255525Y1200165D01*
X239485D01*
X237667Y1201983D01*
X235203Y1203004D01*
X232018Y1206189D01*
X230206D01*
X224575Y1211820D01*
X213901Y1216242D01*
Y1216275D01*
X206586Y1223590D01*
X200262D01*
X197323Y1226529D01*
Y1229013D01*
X189359Y1236977D01*
X177381D01*
X171472Y1242886D01*
X161487D01*
X157705Y1246668D01*
Y1248851D01*
X153861Y1252695D01*
X136165D01*
X133838Y1250368D01*
X108858D01*
X105505Y1247015D01*
X67773D01*
X66099Y1245341D01*
G01X324723Y891166D02*
X311503D01*
X303003Y882666D01*
Y872124D01*
X270940Y840061D01*
X266580Y829538D01*
X262122Y825080D01*
X261430D01*
X251098Y814748D01*
X248148D01*
X246938Y815958D01*
X241490D01*
X237251Y811719D01*
X232619D01*
X231819Y812519D01*
X228131D01*
X227411Y811799D01*
Y809990D01*
X226691Y809270D01*
X225411D01*
X224691Y809990D01*
Y811799D01*
X223971Y812519D01*
X221119D01*
X217448Y808848D01*
X214049D01*
X207821Y802620D01*
X202428D01*
X201757Y801949D01*
X200349D01*
X199428Y802870D01*
X197495D01*
X195094Y805271D01*
X172265D01*
X171138Y806398D01*
X162498D01*
X159354Y803254D01*
X144103D01*
X142787Y801938D01*
X140678D01*
X138968Y803648D01*
X135997D01*
X133107Y806538D01*
X130948D01*
X129689Y805279D01*
X109628D01*
X108998Y804649D01*
Y803827D01*
X108368Y803197D01*
X106898D01*
X106268Y803827D01*
Y804649D01*
X105638Y805279D01*
X98598D01*
X97819Y804500D01*
X92176D01*
X91456Y803780D01*
Y802299D01*
X90736Y801579D01*
X89456D01*
X88736Y802299D01*
Y803780D01*
X88016Y804500D01*
X84696D01*
X82241Y806955D01*
G01X324723Y895086D02*
X309682D01*
X298924Y884328D01*
Y873971D01*
X266755Y841802D01*
X263292Y833442D01*
X260994Y831144D01*
X260168D01*
X257286Y828262D01*
Y826936D01*
X253169Y822819D01*
X240299D01*
X235999Y818519D01*
X233619D01*
X232519Y819619D01*
X227499D01*
X226779Y818899D01*
Y817682D01*
X226059Y816962D01*
X224779D01*
X224059Y817682D01*
Y818899D01*
X223339Y819619D01*
X220619D01*
X216919Y815919D01*
X213719D01*
X206429Y808629D01*
X198656D01*
X195307Y811978D01*
X160598D01*
X157245Y808625D01*
X154287D01*
X152958Y809954D01*
X151567D01*
X150238Y808625D01*
X148847D01*
X147518Y809954D01*
X146127D01*
X144798Y808625D01*
X137997D01*
X134650Y811972D01*
X120756D01*
X119555Y810771D01*
X118036D01*
X116835Y811972D01*
X114503D01*
X113866Y812609D01*
X108851D01*
X108131Y811889D01*
Y811422D01*
X107411Y810702D01*
X106131D01*
X105411Y811422D01*
Y811889D01*
X104691Y812609D01*
X102374D01*
X101013Y811248D01*
X93991D01*
X93361Y811878D01*
Y812838D01*
X92731Y813468D01*
X91261D01*
X90631Y812838D01*
Y811878D01*
X90001Y811248D01*
X84641D01*
X82241Y813648D01*
G01X325323Y905366D02*
X303664D01*
X288053Y889755D01*
Y877898D01*
X265893Y855738D01*
X260539D01*
X259407Y854606D01*
Y853033D01*
X253489Y847115D01*
Y846191D01*
X252350Y845052D01*
X248423D01*
X247413Y844042D01*
Y843152D01*
X249128Y841438D01*
Y840548D01*
X248349Y839769D01*
X247459D01*
X245744Y841483D01*
X244854D01*
X242348Y838977D01*
X234876D01*
X232175Y836276D01*
X228644D01*
X227924Y835556D01*
Y834398D01*
X227204Y833678D01*
X225924D01*
X225204Y834398D01*
Y835556D01*
X224484Y836276D01*
X220976D01*
X216751Y832051D01*
X196857D01*
X193511Y835397D01*
X177636D01*
X172315Y830076D01*
X162812D01*
X160835Y832053D01*
X131253D01*
X127906Y835400D01*
X123938D01*
X121535Y832997D01*
X114784D01*
X113764Y831977D01*
X108965D01*
X108245Y831257D01*
Y828313D01*
X107525Y827593D01*
X106245D01*
X105525Y828313D01*
Y831257D01*
X104805Y831977D01*
X100552D01*
X99876Y832653D01*
X84513D01*
X82241Y830381D01*
G01X325323Y900226D02*
X306814D01*
X293784Y887196D01*
Y876235D01*
X262103Y844554D01*
X260494D01*
X257898Y841959D01*
X254469Y833684D01*
X251681Y830895D01*
X249720D01*
X246949Y828124D01*
X241745D01*
X241255Y828614D01*
X239095D01*
X238605Y828124D01*
X235497D01*
X232712Y825339D01*
X228276D01*
X227786Y825829D01*
X225626D01*
X225136Y825339D01*
X214624D01*
X206852Y817567D01*
X202996D01*
X201895Y818668D01*
X200226D01*
X199134Y817576D01*
X197914D01*
X194580Y820910D01*
X186857D01*
X185753Y822014D01*
X184119D01*
X182979Y820874D01*
X180535D01*
X178316Y818655D01*
X175011D01*
X173358Y820308D01*
X159656D01*
X156908Y817560D01*
X143603D01*
X142495Y818668D01*
X140861D01*
X139721Y817528D01*
X136880D01*
X133548Y820860D01*
X127507D01*
X126353Y822014D01*
X124719D01*
X123579Y820874D01*
X121880D01*
X119068Y823686D01*
X116908D01*
X113557Y822300D01*
X111542Y820285D01*
X100653D01*
X97602Y823336D01*
X85845D01*
X85118Y822609D01*
X83320D01*
X82241Y823688D01*
G01X325323Y899006D02*
X307320D01*
X295004Y886690D01*
Y875729D01*
X262609Y843334D01*
X261000D01*
X258933Y841267D01*
X255504Y832992D01*
X252187Y829675D01*
X250226D01*
X247455Y826904D01*
X236003D01*
X233218Y824119D01*
X215130D01*
X207358Y816347D01*
X203005D01*
X201980Y815322D01*
X200163D01*
X199129Y816356D01*
X197408D01*
X194074Y819690D01*
X186860D01*
X185838Y818668D01*
X184021D01*
X183035Y819654D01*
X181041D01*
X178822Y817435D01*
X174505D01*
X172852Y819088D01*
X160162D01*
X157414Y816340D01*
X143598D01*
X142580Y815322D01*
X140763D01*
X139777Y816308D01*
X136374D01*
X133042Y819640D01*
X127410D01*
X126438Y818668D01*
X124621D01*
X123635Y819654D01*
X121374D01*
X118562Y822466D01*
X117151D01*
X114248Y821265D01*
X112048Y819065D01*
X100147D01*
X97096Y822116D01*
X86351D01*
X85624Y821389D01*
X83289D01*
X82241Y820341D01*
G01X325323Y909286D02*
X301871D01*
X284092Y891507D01*
Y879927D01*
X263950Y859785D01*
X257871D01*
X253743Y855657D01*
Y853093D01*
X252134Y851484D01*
X248109D01*
X244809Y848184D01*
X242578D01*
X240183Y845789D01*
X235127D01*
X231622Y842284D01*
X219884D01*
X217117Y839517D01*
X211719D01*
X210999Y838797D01*
Y837014D01*
X210279Y836294D01*
X208999D01*
X208279Y837014D01*
Y838797D01*
X207559Y839517D01*
X204720D01*
X203947Y838744D01*
X198500D01*
X195148Y842096D01*
X175515D01*
X170900Y837481D01*
X168112D01*
X167392Y838201D01*
Y839382D01*
X166655Y840119D01*
X165392D01*
X164672Y839399D01*
Y838201D01*
X163952Y837481D01*
X157930D01*
X155792Y839619D01*
X144625D01*
X143752Y838746D01*
X131490D01*
X128144Y842092D01*
X123938D01*
X121534Y839688D01*
X115866D01*
X114787Y838609D01*
X109061D01*
X108341Y839329D01*
Y841403D01*
X107587Y842157D01*
X106341D01*
X105621Y841437D01*
Y839329D01*
X104901Y838609D01*
X99880D01*
X99065Y839424D01*
X92919D01*
X92199Y838704D01*
Y837476D01*
X91479Y836756D01*
X90199D01*
X89479Y837476D01*
Y838704D01*
X88759Y839424D01*
X84591D01*
X82241Y837074D01*
G01X327525Y971082D02*
X324232D01*
X317986Y964836D01*
X287986D01*
X286164Y966658D01*
X273637D01*
X263679Y956700D01*
X257144D01*
X252972Y952528D01*
X247319D01*
X246910Y952119D01*
X234669D01*
X233667Y953121D01*
X228991D01*
X228393Y952523D01*
X220247D01*
X218018Y950294D01*
X210961D01*
X209595Y951660D01*
X204670D01*
X203807Y952523D01*
X196263D01*
X195647Y953139D01*
X188887D01*
X188271Y952523D01*
X185410D01*
X185409Y952524D01*
X168144D01*
X165999Y954669D01*
X161738D01*
X159104Y952035D01*
X152319D01*
X151599Y952755D01*
Y953511D01*
X150879Y954231D01*
X149599D01*
X148879Y953511D01*
Y952755D01*
X148159Y952035D01*
X145378D01*
X144889Y952524D01*
X136541D01*
X135956Y953109D01*
X129602D01*
X129017Y952524D01*
X123811D01*
X122501Y951214D01*
X115382D01*
X114073Y952523D01*
X111061D01*
X109928Y953656D01*
X108570D01*
X107940Y953026D01*
Y951778D01*
X107310Y951148D01*
X105840D01*
X105210Y951778D01*
Y953026D01*
X104580Y953656D01*
X102290D01*
X98740Y950106D01*
X94249D01*
X90258Y954097D01*
Y956222D01*
X88034Y958446D01*
X87016D01*
X85867Y957297D01*
X84849D01*
X83943Y958203D01*
Y959221D01*
X85092Y960370D01*
Y961388D01*
X82241Y964239D01*
G01X328123Y1091428D02*
X327707D01*
X316074Y1096247D01*
X260547Y1151774D01*
X258397D01*
X254296Y1155875D01*
X251162D01*
X247157Y1159880D01*
X241508D01*
X237871Y1163517D01*
X234889D01*
X231105Y1167301D01*
X229429D01*
X222447Y1174283D01*
X219273D01*
X214992Y1178564D01*
X213974D01*
X213592Y1178182D01*
X212574D01*
X211668Y1179088D01*
Y1180106D01*
X212050Y1180488D01*
Y1181506D01*
X210124Y1183432D01*
X196658D01*
X187506Y1192584D01*
Y1195183D01*
X185871Y1196818D01*
X182772D01*
X178988Y1200602D01*
X175202D01*
X171715Y1204089D01*
X169665D01*
X163289Y1210465D01*
X161343D01*
X158257Y1213551D01*
X131820D01*
X128479Y1210210D01*
X119232D01*
X118490Y1209468D01*
Y1207933D01*
X117770Y1207213D01*
X116490D01*
X115770Y1207933D01*
Y1209482D01*
X115050Y1210202D01*
X109739D01*
X109019Y1209482D01*
Y1204959D01*
X108299Y1204239D01*
X107190D01*
X106299Y1205130D01*
Y1209482D01*
X105579Y1210202D01*
X101463D01*
X100833Y1209572D01*
Y1207448D01*
X100203Y1206818D01*
X98733D01*
X98103Y1207448D01*
Y1209298D01*
X97473Y1209928D01*
X96003D01*
X95373Y1209298D01*
Y1207448D01*
X94743Y1206818D01*
X93273D01*
X92643Y1207448D01*
Y1209572D01*
X92013Y1210202D01*
X90543D01*
X89913Y1209572D01*
Y1207448D01*
X89283Y1206818D01*
X87813D01*
X87183Y1207448D01*
Y1209572D01*
X86553Y1210202D01*
X83916D01*
X82241Y1211877D01*
G01X328123Y1096148D02*
X326987D01*
X319502Y1099245D01*
X263031Y1155716D01*
Y1158602D01*
X261222Y1160411D01*
X259124D01*
X257394Y1162141D01*
Y1162186D01*
X252474Y1167106D01*
X249188D01*
X248406Y1166324D01*
X241002D01*
X236900Y1170426D01*
X234704D01*
X230993Y1174137D01*
X229429D01*
X222003Y1181563D01*
X220375D01*
X219265Y1182673D01*
Y1184301D01*
X217222Y1186344D01*
X213756D01*
X206629Y1193471D01*
X199509D01*
X198879Y1192841D01*
Y1189705D01*
X198249Y1189075D01*
X196847D01*
X196149Y1189773D01*
Y1192841D01*
X195519Y1193471D01*
X194957D01*
X194286Y1194142D01*
Y1195860D01*
X192548Y1197598D01*
X191192D01*
X187398Y1201392D01*
Y1202748D01*
X186635Y1203511D01*
X181979D01*
X178175Y1207315D01*
X174988D01*
X171465Y1210838D01*
X170096D01*
X163487Y1217447D01*
X160481D01*
X157684Y1220244D01*
X152652D01*
X151944Y1219536D01*
X149922D01*
X149214Y1220244D01*
X139119D01*
X137984Y1219109D01*
X136389D01*
X135254Y1220244D01*
X131188D01*
X127839Y1216895D01*
X123442D01*
X122273Y1218064D01*
X119598D01*
X118327Y1216793D01*
X114397D01*
X113007Y1218183D01*
X109276D01*
X108646Y1217553D01*
Y1216344D01*
X108016Y1215714D01*
X106546D01*
X105916Y1216344D01*
Y1217553D01*
X105286Y1218183D01*
X101000D01*
X98614Y1215797D01*
X93402D01*
X92682Y1216517D01*
Y1220685D01*
X91962Y1221405D01*
X90682D01*
X89962Y1220685D01*
Y1216517D01*
X89242Y1215797D01*
X85014D01*
X82241Y1218570D01*
G01X328727Y1101562D02*
X325878D01*
X323554Y1102524D01*
X322027Y1104051D01*
X321334D01*
X319806Y1105579D01*
Y1106272D01*
X318279Y1107799D01*
X317586D01*
X316058Y1109327D01*
Y1110020D01*
X314531Y1111547D01*
X313838D01*
X312310Y1113075D01*
Y1113768D01*
X310783Y1115295D01*
X310090D01*
X308562Y1116823D01*
Y1117516D01*
X307035Y1119043D01*
X306342D01*
X304814Y1120571D01*
Y1121264D01*
X303287Y1122791D01*
X302594D01*
X301066Y1124319D01*
Y1125012D01*
X299539Y1126539D01*
X298846D01*
X297318Y1128067D01*
Y1128760D01*
X295791Y1130287D01*
X295098D01*
X293570Y1131815D01*
Y1132508D01*
X292043Y1134035D01*
X291350D01*
X289822Y1135563D01*
Y1136256D01*
X288295Y1137783D01*
X287602D01*
X286074Y1139311D01*
Y1140004D01*
X284547Y1141531D01*
X283854D01*
X282326Y1143059D01*
Y1143752D01*
X280799Y1145279D01*
X280106D01*
X278578Y1146807D01*
Y1147500D01*
X267944Y1158135D01*
Y1160505D01*
X260301Y1168148D01*
X259004D01*
X253380Y1173772D01*
X250019D01*
X248427Y1172180D01*
X242492D01*
X237012Y1177660D01*
X234922D01*
X231649Y1180933D01*
X230621D01*
X227445Y1184109D01*
Y1186148D01*
X223494Y1190099D01*
X221975D01*
X216921Y1195153D01*
X212613D01*
X206576Y1201190D01*
X203161D01*
X202135Y1200164D01*
X200164D01*
X199182Y1201146D01*
X197115D01*
X194168Y1204093D01*
X192337D01*
X188838Y1207592D01*
X188841Y1209933D01*
X187545Y1211229D01*
X187019D01*
X185994Y1210204D01*
X184021D01*
X182999Y1211226D01*
X180739D01*
X178271Y1213694D01*
X176258D01*
X171022Y1218930D01*
X169278D01*
X164345Y1223862D01*
X146376Y1231308D01*
X143517D01*
X142491Y1230282D01*
X140764D01*
X139782Y1231264D01*
X138691D01*
X134385Y1226958D01*
X128727Y1224615D01*
X127335D01*
X126310Y1223590D01*
X124717D01*
X123650Y1224657D01*
X123630D01*
X123589Y1224698D01*
X121186D01*
X118753Y1222265D01*
X114586D01*
X112154Y1224697D01*
X102649D01*
X96331Y1227314D01*
X86279D01*
X85250Y1226285D01*
X83263D01*
X82241Y1225263D01*
G01X331141Y1113685D02*
X330498D01*
X274820Y1169363D01*
Y1177648D01*
X264557Y1187911D01*
Y1190923D01*
X262008Y1193472D01*
X257943D01*
X254597Y1196818D01*
X239707D01*
X236095Y1200430D01*
X234946D01*
X231503Y1203873D01*
X229624D01*
X223405Y1210092D01*
X212817Y1214480D01*
X207054Y1220243D01*
X199739D01*
X193635Y1226347D01*
Y1227237D01*
X194245Y1227847D01*
Y1228737D01*
X193204Y1229778D01*
X192314D01*
X191578Y1229042D01*
X190688D01*
X186100Y1233630D01*
X182438D01*
X181808Y1233000D01*
Y1231873D01*
X181178Y1231243D01*
X179708D01*
X179078Y1231873D01*
Y1233000D01*
X178448Y1233630D01*
X175342D01*
X172790Y1236182D01*
X169864D01*
X165357Y1240689D01*
X159782D01*
X149893Y1250578D01*
X137278D01*
X133714Y1247014D01*
X117186D01*
X113033Y1242861D01*
X109266D01*
X108546Y1242141D01*
Y1239732D01*
X107826Y1239012D01*
X106546D01*
X105826Y1239732D01*
Y1242141D01*
X105106Y1242861D01*
X99543D01*
X98058Y1244346D01*
X93710D01*
X92990Y1243626D01*
Y1243002D01*
X92270Y1242282D01*
X90990D01*
X90270Y1243002D01*
Y1243626D01*
X89550Y1244346D01*
X84592D01*
X82241Y1241995D01*
G01X332923Y1108184D02*
X330322D01*
X270446Y1168060D01*
Y1175760D01*
X262770Y1183436D01*
X258453D01*
X253169Y1188720D01*
X250712D01*
X248770Y1186778D01*
X240324D01*
X233414Y1193688D01*
Y1195202D01*
X231097Y1197519D01*
X228869D01*
X221978Y1204410D01*
X218687D01*
X215471Y1207626D01*
X212883D01*
X206959Y1213550D01*
X196904D01*
X195440Y1215014D01*
Y1215904D01*
X196356Y1216820D01*
Y1217710D01*
X195315Y1218751D01*
X194425D01*
X193509Y1217835D01*
X192619D01*
X186864Y1223590D01*
X181294D01*
X176792Y1228092D01*
X173617D01*
X167484Y1230632D01*
X164067Y1234049D01*
X159654D01*
X155991Y1237712D01*
X153646D01*
X147691Y1243667D01*
X137688D01*
X134342Y1240321D01*
X124180D01*
X121689Y1237830D01*
X116472D01*
X113277Y1234635D01*
X109301D01*
X108581Y1233915D01*
Y1232621D01*
X107861Y1231901D01*
X106581D01*
X105861Y1232621D01*
Y1233915D01*
X105141Y1234635D01*
X100028D01*
X97044Y1237619D01*
X93539D01*
X92819Y1236899D01*
Y1235561D01*
X92099Y1234841D01*
X90819D01*
X90099Y1235561D01*
Y1236899D01*
X89379Y1237619D01*
X84558D01*
X82241Y1235302D01*
G01X328727Y1102782D02*
X326121D01*
X324246Y1103559D01*
X269164Y1158641D01*
Y1161011D01*
X260807Y1169368D01*
X259510D01*
X253886Y1174992D01*
X249513D01*
X247921Y1173400D01*
X242998D01*
X237518Y1178880D01*
X235428D01*
X232155Y1182153D01*
X231127D01*
X228665Y1184615D01*
Y1186654D01*
X224000Y1191319D01*
X222481D01*
X217427Y1196373D01*
X213119D01*
X207082Y1202410D01*
X203246D01*
X202145Y1203511D01*
X200261D01*
X199116Y1202366D01*
X197621D01*
X194674Y1205313D01*
X192843D01*
X190059Y1208097D01*
X190062Y1210438D01*
X188051Y1212449D01*
X187104D01*
X186002Y1213551D01*
X184120D01*
X183015Y1212446D01*
X181245D01*
X178777Y1214914D01*
X176764D01*
X171528Y1220150D01*
X169784D01*
X165037Y1224897D01*
X146619Y1232528D01*
X143508D01*
X142407Y1233629D01*
X140861D01*
X139716Y1232484D01*
X138184D01*
X133693Y1227993D01*
X128484Y1225835D01*
X127340D01*
X126239Y1226936D01*
X124719D01*
X123701Y1225918D01*
X120680D01*
X118247Y1223485D01*
X115092D01*
X112660Y1225917D01*
X102892D01*
X96574Y1228534D01*
X85773D01*
X84744Y1227505D01*
X83345D01*
X82241Y1228609D01*
G01X332421Y1001526D02*
X318398D01*
X309839Y1005071D01*
X261714D01*
X261713Y1005072D01*
X204086D01*
X197073Y998059D01*
X190724Y995554D01*
X187929Y992759D01*
Y990179D01*
X187089Y989339D01*
X185424D01*
X185419Y989334D01*
X181814D01*
X178463Y985983D01*
X169238D01*
X168518Y986703D01*
Y988255D01*
X167798Y988975D01*
X166518D01*
X165798Y988255D01*
Y986703D01*
X165078Y985983D01*
X159082D01*
X157797Y987268D01*
X152342D01*
X144369Y979295D01*
X131000D01*
X127653Y975948D01*
X117898D01*
X113569Y971619D01*
X103733D01*
X100069Y967955D01*
Y965162D01*
X95799Y960892D01*
G01X332421Y999556D02*
X319512D01*
X309726Y1003609D01*
X298884D01*
X297367Y1002980D01*
X296487Y1002616D01*
X280037D01*
X280036Y1002615D01*
X271008D01*
X257137Y996870D01*
X200776D01*
X191392Y989994D01*
X186798Y983375D01*
X185592Y982642D01*
X183239D01*
X177099Y982345D01*
X175909D01*
X169629Y983641D01*
X163779D01*
X148989Y977514D01*
X147423Y975948D01*
X131634D01*
X130662Y974976D01*
X127552Y970132D01*
X126393Y969255D01*
X107508D01*
X95799Y957546D01*
G01X324723Y873217D02*
X322394D01*
X321089Y871912D01*
Y863876D01*
X286785Y829572D01*
X275536Y802412D01*
X261551Y788427D01*
X257468D01*
X253460Y784419D01*
X248269D01*
X245269Y781419D01*
X242919D01*
X236244Y774744D01*
X234715D01*
X231569Y771598D01*
X219148D01*
X215113Y767563D01*
X210081D01*
X209165Y768479D01*
X182859D01*
X179520Y771818D01*
X168330D01*
X167610Y772538D01*
Y774473D01*
X166890Y775193D01*
X165600D01*
X164880Y774473D01*
Y772538D01*
X164160Y771818D01*
X158284D01*
X155683Y774419D01*
X146559D01*
X142471Y778507D01*
X134207D01*
X133761Y778061D01*
X127622D01*
X125499Y780184D01*
G01X328458Y865009D02*
X327142Y863693D01*
Y861612D01*
X292181Y826651D01*
X280752Y799062D01*
X264038Y782348D01*
X260146D01*
X253717Y775919D01*
X250269D01*
X246769Y772419D01*
X243769D01*
X241769Y770419D01*
Y767418D01*
X237935Y763584D01*
X236076Y762935D01*
X229773Y761788D01*
X211278Y760365D01*
X157369D01*
X155259Y760639D01*
X148893Y761825D01*
X142718Y763672D01*
X139570Y765070D01*
X125499Y773491D01*
G01X324723Y878386D02*
X317845D01*
X315942Y876483D01*
Y866052D01*
X281899Y832009D01*
X273679Y811993D01*
X272152Y810466D01*
Y809773D01*
X270624Y808245D01*
X269931D01*
X268404Y806718D01*
Y806025D01*
X266876Y804497D01*
X266183D01*
X261247Y799561D01*
X259611D01*
X257940Y797890D01*
Y797197D01*
X256412Y795668D01*
X255719D01*
X254192Y794141D01*
X251560Y793051D01*
X251294Y792409D01*
X249298Y791583D01*
X248658Y791848D01*
X246663Y791022D01*
X246398Y790381D01*
X244401Y789554D01*
X243761Y789819D01*
X241766Y788993D01*
X241501Y788352D01*
X239504Y787525D01*
X238864Y787790D01*
X232855Y785301D01*
X230695D01*
X230205Y784811D01*
X228045D01*
X227555Y785301D01*
X225395D01*
X224905Y784811D01*
X222745D01*
X222255Y785301D01*
X220095D01*
X219605Y784811D01*
X217445D01*
X216955Y785301D01*
X213024D01*
X211340Y783618D01*
X211339Y782925D01*
X209811Y781397D01*
X209118D01*
X207228Y779509D01*
X202820D01*
X201819Y778508D01*
X200239D01*
X199157Y779590D01*
X198193D01*
X190198Y782902D01*
X186700D01*
X185652Y781854D01*
X184127D01*
X183075Y782906D01*
X180564D01*
X179636Y781978D01*
X178708Y781049D01*
X177450Y780529D01*
X175738D01*
X167235Y784052D01*
X161024D01*
X158312Y782929D01*
X157029D01*
X155905Y781805D01*
X154480D01*
X153395Y782890D01*
X152133D01*
X148549Y784375D01*
X143805Y789119D01*
X143391D01*
X142819Y788547D01*
X140903D01*
X139841Y789609D01*
X137337D01*
X135682Y787954D01*
X133386Y787004D01*
X130491D01*
X128345Y787893D01*
X126515D01*
X125499Y786877D01*
G01X324723Y885486D02*
X313856D01*
X308683Y880313D01*
Y869328D01*
X275604Y836249D01*
X268190Y818348D01*
X262784Y812942D01*
X260184D01*
X253461Y806219D01*
X250019D01*
X246795Y802995D01*
X235795D01*
X232419Y799619D01*
X220419D01*
X216043Y795243D01*
X212743D01*
X211357Y796629D01*
X210013D01*
X208627Y795243D01*
X207283D01*
X205897Y796629D01*
X204553D01*
X203167Y795243D01*
X198950D01*
X197735Y794028D01*
X196220D01*
X195005Y795243D01*
X189061D01*
X185714Y798590D01*
X183816D01*
X181119Y795893D01*
X175643D01*
X174569Y794819D01*
X161503D01*
X160731Y795591D01*
X150846D01*
X149518Y796919D01*
X144539D01*
X142872Y798586D01*
X133990D01*
X133270Y799306D01*
Y800996D01*
X132550Y801716D01*
X131260D01*
X130540Y800996D01*
Y799306D01*
X129820Y798586D01*
X128276D01*
X127550Y799312D01*
Y801558D01*
X125499Y803609D01*
G01X324723Y883526D02*
X314668D01*
X310643Y879501D01*
Y868286D01*
X277200Y834843D01*
X269652Y816622D01*
X261496Y808466D01*
X259116D01*
X252269Y801619D01*
X248919D01*
X245719Y798419D01*
X242099D01*
X241379Y799139D01*
Y800315D01*
X240659Y801035D01*
X239379D01*
X238659Y800315D01*
Y799139D01*
X237939Y798419D01*
X235219D01*
X231619Y794819D01*
X228370D01*
X227650Y795539D01*
Y796825D01*
X226930Y797545D01*
X225650D01*
X224930Y796825D01*
Y795539D01*
X224210Y794819D01*
X220019D01*
X217097Y791897D01*
X214317D01*
X213038Y790618D01*
X211587D01*
X210308Y791897D01*
X208857D01*
X207578Y790618D01*
X206127D01*
X204848Y791897D01*
X189589D01*
X186243Y795243D01*
X184211D01*
X180863Y791895D01*
X169007D01*
X167790Y790678D01*
X166277D01*
X165060Y791895D01*
X157762D01*
X156585Y790718D01*
X155032D01*
X153855Y791895D01*
X150743D01*
X147398Y795240D01*
X134549D01*
X133919Y794610D01*
X133112D01*
X132392Y793890D01*
Y792815D01*
X131672Y792095D01*
X130382D01*
X129662Y792815D01*
Y793890D01*
X128942Y794610D01*
X127805D01*
X125499Y796916D01*
G01X324723Y879606D02*
X317339D01*
X314722Y876989D01*
Y866558D01*
X280863Y832699D01*
X272643Y812683D01*
X260741Y800781D01*
X259105D01*
X253500Y795176D01*
X232612Y786521D01*
X212518D01*
X206722Y780729D01*
X202877D01*
X201752Y781854D01*
X200213D01*
X199169Y780810D01*
X198436D01*
X190441Y784122D01*
X186680D01*
X185602Y785200D01*
X184175D01*
X183101Y784126D01*
X180058D01*
X178016Y782084D01*
X177207Y781749D01*
X175981D01*
X167478Y785272D01*
X160781D01*
X158069Y784149D01*
X157015D01*
X155914Y785250D01*
X154487D01*
X153347Y784110D01*
X152376D01*
X149241Y785410D01*
X142752Y791899D01*
X140867D01*
X139797Y790829D01*
X136831D01*
X134991Y788989D01*
X133143Y788224D01*
X130734D01*
X128588Y789113D01*
X126609D01*
X125499Y790223D01*
G01X325324Y916926D02*
X298705D01*
X276044Y894265D01*
Y883609D01*
X260455Y868020D01*
X254685D01*
X252580Y865915D01*
X250159D01*
X246325Y862081D01*
X243313D01*
X236429Y855197D01*
X233129D01*
X230962Y857364D01*
X219356D01*
X217468Y855476D01*
X197213D01*
X193870Y852133D01*
X184211D01*
X180878Y855466D01*
X168265D01*
X164746Y851947D01*
X160460D01*
X157298Y848785D01*
X127171D01*
X125499Y847113D01*
G01X325324Y920846D02*
X296514D01*
X272082Y896414D01*
Y885991D01*
X260983Y874892D01*
X253292D01*
X247315Y868915D01*
X243456D01*
X236505Y861964D01*
X227419D01*
X226699Y862684D01*
Y864439D01*
X225979Y865159D01*
X224699D01*
X223979Y864439D01*
Y862684D01*
X223259Y861964D01*
X220539D01*
X216987Y865516D01*
X198119D01*
X191429Y858826D01*
X183887D01*
X181059Y861654D01*
X168704D01*
X165321Y858271D01*
X160014D01*
X157221Y855478D01*
X157178D01*
X157176Y855476D01*
X127169D01*
X125499Y853806D01*
G01X326124Y926008D02*
X293551D01*
X265654Y898111D01*
Y891732D01*
X263869Y889947D01*
X262180D01*
X261184Y888951D01*
X259613D01*
X258576Y889988D01*
X256550D01*
X254014Y887451D01*
X251279Y886318D01*
X250349Y885388D01*
X249331Y883483D01*
X249533Y882820D01*
X248514Y880914D01*
X247851Y880713D01*
X246276Y877766D01*
X243541Y876635D01*
X237019D01*
X231303Y874267D01*
X227981D01*
X227491Y873777D01*
X225331D01*
X224841Y874267D01*
X222681D01*
X222191Y873777D01*
X220031D01*
X219541Y874267D01*
X217381D01*
X215115Y876533D01*
X212093D01*
X211603Y876043D01*
X209443D01*
X208953Y876533D01*
X203042D01*
X202056Y875547D01*
X200023D01*
X199051Y876519D01*
X197860D01*
X194661Y873318D01*
X192845D01*
X192355Y872828D01*
X190195D01*
X189705Y873318D01*
X186951D01*
X185839Y872206D01*
X183956D01*
X182909Y873253D01*
X181550D01*
X180353Y872055D01*
X177669Y870944D01*
X175408D01*
X172211Y872268D01*
X170361D01*
X168404Y871456D01*
X166877Y869929D01*
X166878Y869236D01*
X165349Y867707D01*
X164656D01*
X163415Y866465D01*
X160657Y865322D01*
X160392Y864681D01*
X158396Y863854D01*
X157756Y864119D01*
X155738Y863283D01*
X153578D01*
X153088Y862793D01*
X150928D01*
X150438Y863283D01*
X143657D01*
X142552Y862178D01*
X140647D01*
X139611Y863214D01*
X138352D01*
X135882Y860744D01*
X134150D01*
X133660Y860254D01*
X131500D01*
X131010Y860744D01*
X129563D01*
X127640Y861540D01*
X126540D01*
X125499Y860499D01*
G01X326124Y927228D02*
X293045D01*
X264434Y898617D01*
Y892238D01*
X263363Y891167D01*
X262312D01*
X261194Y892285D01*
X259593D01*
X258516Y891208D01*
X256044D01*
X253322Y888486D01*
X250587Y887353D01*
X249359Y886125D01*
X245405Y878727D01*
X243298Y877855D01*
X236776D01*
X231060Y875487D01*
X217887D01*
X215621Y877753D01*
X203145D01*
X201983Y878915D01*
X200203D01*
X199027Y877739D01*
X197354D01*
X194155Y874538D01*
X186952D01*
X185925Y875565D01*
X183977D01*
X182885Y874473D01*
X181044D01*
X179661Y873090D01*
X177426Y872164D01*
X175651D01*
X172454Y873488D01*
X170117D01*
X167712Y872491D01*
X162723Y867500D01*
X155495Y864503D01*
X143650D01*
X142632Y865521D01*
X140674D01*
X139587Y864434D01*
X137846D01*
X135376Y861964D01*
X129806D01*
X127883Y862760D01*
X126584D01*
X125499Y863845D01*
G01X327124Y940162D02*
X285295D01*
X263593Y918460D01*
X258811D01*
X252215Y911864D01*
X250188D01*
X247346Y909022D01*
X237832D01*
X234029Y905219D01*
X220270D01*
X217379Y902328D01*
X197778D01*
X191085Y895635D01*
X170045D01*
X168950Y894540D01*
X161624D01*
X156849Y889765D01*
X154332D01*
X152031Y887464D01*
X149494D01*
X147626Y885596D01*
X127171D01*
X125499Y883924D01*
G01X326124Y935068D02*
X288369D01*
X262337Y909036D01*
X258470D01*
X251763Y902329D01*
X242700D01*
X242070Y901699D01*
Y900389D01*
X239845Y898164D01*
X232746D01*
X229746Y895164D01*
X225566D01*
X224685Y896045D01*
X222846D01*
X221965Y895164D01*
X219245D01*
X216370Y892289D01*
X211737D01*
X211017Y893009D01*
Y894128D01*
X210297Y894848D01*
X209017D01*
X208297Y894128D01*
Y893009D01*
X207577Y892289D01*
X197241D01*
X193895Y888943D01*
X174344D01*
X171191Y885790D01*
X169204D01*
X168484Y885070D01*
Y883841D01*
X167764Y883121D01*
X166484D01*
X165764Y883841D01*
Y885070D01*
X165044Y885790D01*
X162004D01*
X158532Y882318D01*
X152637D01*
X151834Y881515D01*
Y880625D01*
X152884Y879576D01*
Y878686D01*
X152105Y877907D01*
X151215D01*
X150165Y878956D01*
X149275D01*
X148346Y878027D01*
X145277D01*
X144399Y878905D01*
X134053D01*
X133333Y879625D01*
Y881204D01*
X132613Y881924D01*
X131333D01*
X130613Y881204D01*
Y879625D01*
X129893Y878905D01*
X127173D01*
X125499Y877231D01*
G01X326124Y931148D02*
X289993D01*
X261185Y902340D01*
X258153D01*
X256423Y900610D01*
Y898817D01*
X253616Y896010D01*
X250690D01*
X247297Y892617D01*
Y890194D01*
X246046Y888943D01*
X232425D01*
X229340Y885858D01*
X221007D01*
X219813Y884664D01*
X204551D01*
X203619Y885596D01*
X196995D01*
X193649Y882250D01*
X181046D01*
X177699Y878903D01*
X167275D01*
X163098Y874726D01*
X161596D01*
X158134Y871264D01*
X145324D01*
X144377Y872211D01*
X138761D01*
X138041Y871491D01*
Y867224D01*
X137321Y866504D01*
X136041D01*
X135321Y867224D01*
Y871491D01*
X134601Y872211D01*
X131332D01*
X130612Y872931D01*
Y875186D01*
X129892Y875906D01*
X128612D01*
X127892Y875186D01*
Y872931D01*
X125499Y870538D01*
G01X327124Y944125D02*
X283568D01*
Y944114D01*
X264672Y925218D01*
X259045D01*
X252619Y918792D01*
X250150D01*
X247073Y915715D01*
X235161D01*
X231465Y912019D01*
X219629D01*
X216631Y909021D01*
X191402D01*
X188057Y905676D01*
X180414D01*
X177070Y902332D01*
X167340D01*
X163903Y898895D01*
X159825D01*
X157921Y896991D01*
X155065D01*
X150361Y892287D01*
X139489D01*
X138769Y893007D01*
Y893957D01*
X138049Y894677D01*
X136769D01*
X136049Y893957D01*
Y893007D01*
X135329Y892287D01*
X134049D01*
X133329Y893007D01*
Y893957D01*
X132609Y894677D01*
X131329D01*
X130609Y893957D01*
Y893007D01*
X129889Y892287D01*
X127169D01*
X125499Y890617D01*
G01X327124Y949318D02*
X281162D01*
X264305Y932461D01*
X257882D01*
X254754Y929333D01*
X250685D01*
X244895Y926929D01*
X242735D01*
X242245Y926439D01*
X240085D01*
X239595Y926929D01*
X235810D01*
X231878Y922997D01*
X229718D01*
X229228Y922507D01*
X227068D01*
X226578Y922997D01*
X224418D01*
X223928Y922507D01*
X221768D01*
X221278Y922997D01*
X219073D01*
X216202Y920126D01*
X214042D01*
X213552Y919636D01*
X211392D01*
X210902Y920126D01*
X208742D01*
X208252Y919636D01*
X206092D01*
X205602Y920126D01*
X203201D01*
X202137Y919062D01*
X200162D01*
X199161Y920063D01*
X197920D01*
X194631Y916774D01*
X192915D01*
X192425Y916284D01*
X190265D01*
X189775Y916774D01*
X186943D01*
X185885Y915716D01*
X183910D01*
X182909Y916717D01*
X179750D01*
X178223Y915190D01*
Y914497D01*
X176695Y912969D01*
X176002D01*
X174991Y911957D01*
X172996Y911130D01*
X172731Y910489D01*
X170735Y909662D01*
X170094Y909927D01*
X167970Y909047D01*
X161194D01*
X157844Y905697D01*
X153054D01*
X151527Y904170D01*
Y903477D01*
X149999Y901949D01*
X149306D01*
X147365Y900008D01*
X143761D01*
X142736Y898983D01*
X140763D01*
X139761Y899985D01*
X137870D01*
X136237Y898352D01*
X133748Y897321D01*
X130825D01*
X128393Y898328D01*
X126517D01*
X125499Y897310D01*
G01X327124Y950538D02*
X280656D01*
X263799Y933681D01*
X257376D01*
X254248Y930553D01*
X250441D01*
X244651Y928149D01*
X235304D01*
X231372Y924217D01*
X218567D01*
X215696Y921346D01*
X203206D01*
X202144Y922408D01*
X200262D01*
X199137Y921283D01*
X197414D01*
X194125Y917994D01*
X186960D01*
X185892Y919062D01*
X184010D01*
X182885Y917937D01*
X179244D01*
X174299Y912992D01*
X167727Y910267D01*
X160688D01*
X157338Y906917D01*
X152548D01*
X146859Y901228D01*
X143846D01*
X142745Y902329D01*
X140861D01*
X139737Y901205D01*
X137364D01*
X135545Y899386D01*
X133505Y898541D01*
X131068D01*
X128637Y899548D01*
X126607D01*
X125499Y900656D01*
G01X327124Y962459D02*
X324635D01*
X320610Y958434D01*
X276984D01*
X264868Y946318D01*
X258630D01*
X254400Y942088D01*
X249185D01*
X246235Y939138D01*
X230658D01*
X226938Y935418D01*
X207872D01*
X204149Y939141D01*
X196727D01*
X190034Y932448D01*
X162192D01*
X157549Y927805D01*
Y922374D01*
X150013Y914838D01*
X145278D01*
X144400Y915716D01*
X127615D01*
X125941Y914042D01*
X125499D01*
G01X327124Y958417D02*
X326138D01*
X322179Y954458D01*
X278819D01*
X263734Y939373D01*
X257358D01*
X252504Y934519D01*
X233845D01*
X230643Y931317D01*
X219128D01*
X215784Y927973D01*
X204742D01*
X203614Y929101D01*
X196251D01*
X192905Y925755D01*
X173282D01*
X165952Y918425D01*
X162635D01*
X157119Y912909D01*
X154089D01*
X152063Y910883D01*
X149819D01*
X147959Y909023D01*
X139493D01*
X138773Y909743D01*
Y911360D01*
X138053Y912080D01*
X136773D01*
X136053Y911360D01*
Y909743D01*
X135333Y909023D01*
X134053D01*
X133333Y909743D01*
Y911360D01*
X132613Y912080D01*
X131333D01*
X130613Y911360D01*
Y909743D01*
X129893Y909023D01*
X127173D01*
X125499Y907349D01*
G01X332421Y997571D02*
X320738D01*
X309381Y1002275D01*
X301191D01*
X300355Y1001928D01*
X300354D01*
X296794Y1000453D01*
X271056D01*
X253769Y993294D01*
X252465Y991987D01*
X251573D01*
X248673Y994887D01*
X226007D01*
X223549Y992429D01*
X219269D01*
X217979Y993719D01*
X205149D01*
X203869Y992439D01*
Y990875D01*
X202329Y989335D01*
X195795D01*
X194569Y988109D01*
Y986819D01*
X187045Y979295D01*
X184599D01*
X184596Y979298D01*
X181977D01*
X181775Y979500D01*
X174566D01*
X173988Y978922D01*
X168469D01*
X167749Y979642D01*
Y980961D01*
X167029Y981681D01*
X165749D01*
X165029Y980961D01*
Y979642D01*
X164309Y978922D01*
X159161D01*
X155559Y975320D01*
X151712D01*
X149306Y972914D01*
Y968521D01*
X146693Y965908D01*
X139073D01*
X138353Y966628D01*
Y970063D01*
X137633Y970783D01*
X136353D01*
X135633Y970063D01*
Y966628D01*
X134913Y965908D01*
X130515D01*
X125499Y960892D01*
G01X332421Y995605D02*
X321621D01*
X308817Y1000908D01*
X303047D01*
X301784Y1000385D01*
X301761Y1000376D01*
X297064Y998430D01*
X271314D01*
X256266Y992197D01*
X253920Y989851D01*
X250251D01*
X247300Y992802D01*
X227322D01*
X224169Y989649D01*
X220889D01*
X220381Y989571D01*
X216249Y988939D01*
X202889Y985989D01*
X200534D01*
X198984Y985059D01*
X193968Y979603D01*
X185792Y975949D01*
X182589D01*
X175536Y975651D01*
X171639Y976824D01*
X168553D01*
X167833Y976104D01*
Y973796D01*
X167113Y973076D01*
X165833D01*
X165113Y973796D01*
Y976104D01*
X164393Y976824D01*
X161380D01*
X157776Y973220D01*
X152870D01*
X151670Y972020D01*
Y963995D01*
X150237Y962562D01*
X138953D01*
X138323Y961932D01*
Y959744D01*
X137603Y959024D01*
X136028D01*
X135398Y959654D01*
Y962450D01*
X134768Y963080D01*
X131033D01*
X125499Y957546D01*
G01X399262Y999684D02*
X396487Y1001286D01*
X396486D01*
X396467Y1001297D01*
G02X395561Y1002888I944J1591D01*
G01Y1002941D01*
G03X394636Y1004491I-1850J-53D01*
G02X393712Y1006055I926J1602D01*
G01Y1006093D01*
G03X392828Y1007670I-1849J0D01*
G01X392786Y1007695D01*
X392767Y1007706D01*
G02X391861Y1009297I944J1591D01*
G03X390955Y1010888I-1850J0D01*
G01X390936Y1010899D01*
G02X390012Y1012444I925J1602D01*
G01Y1012501D01*
G03X389106Y1014092I-1850J0D01*
G01X389049Y1014125D01*
G03X387236Y1014103I-887J-1624D01*
G02X385386I-925J1602D01*
G03X383536I-925J-1602D01*
G01X383498Y1014081D01*
G02X381687Y1014103I-886J1624D01*
G01X381649Y1014125D01*
G03X379836Y1014103I-887J-1624D01*
G02X377986I-925J1602D01*
G01X377933Y1014134D01*
G03X376136Y1014103I-871J-1633D01*
G02X374286I-925J1602D01*
G01X374233Y1014134D01*
G03X372436Y1014103I-871J-1633D01*
G02X370586I-925J1602D01*
G01X370533Y1014134D01*
G03X368736Y1014103I-871J-1633D01*
G02X366886I-925J1602D01*
G03X365036I-925J-1602D01*
G01X364998Y1014081D01*
G02X363187Y1014103I-886J1624D01*
G01X363149Y1014125D01*
G03X361336Y1014103I-887J-1624D01*
G02X359486I-925J1602D01*
G03X357636I-925J-1602D01*
G01X357583Y1014072D01*
G02X355786Y1014103I-871J1633D01*
G03X353936I-925J-1602D01*
G02X352086I-925J1602D01*
G03X350236I-925J-1602D01*
G02X348386I-925J1602D01*
G03X346536I-925J-1602D01*
G02X344784Y1014050I-925J1602D01*
G01X344692Y1014103D01*
X344552Y1014184D01*
G03X342842Y1014103I-777J-1683D01*
G02X341128Y1014025I-932J1602D01*
G01X340993Y1014103D01*
X340853Y1014184D01*
G03X339143Y1014103I-777J-1683D01*
G02X337439Y1014020I-932J1602D01*
G01X337294Y1014103D01*
X337195Y1014160D01*
G03X335451Y1014103I-819J-1659D01*
G02X333640Y1014081I-925J1602D01*
G01X333602Y1014103D01*
G03X331752I-925J-1602D01*
G01X330444D01*
X329651Y1014896D01*
X318160D01*
X305776Y1020025D01*
X261714D01*
X261713Y1020026D01*
X238511D01*
X236944Y1021593D01*
X205398D01*
X203770Y1023221D01*
Y1025120D01*
X202745Y1026145D01*
X177965D01*
X173813Y1030297D01*
X163249D01*
X158277Y1035269D01*
X152577D01*
X144005Y1043841D01*
Y1051907D01*
X142995Y1052917D01*
X137644D01*
X129275Y1061286D01*
X125499D01*
G01X327121Y1022676D02*
X319348D01*
X307108Y1027746D01*
X266043D01*
X263566Y1030223D01*
X257465D01*
X256835Y1030853D01*
Y1032058D01*
X256205Y1032688D01*
X254735D01*
X254105Y1032058D01*
Y1030853D01*
X253475Y1030223D01*
X252252D01*
X248613Y1033862D01*
X242869D01*
X237069Y1039662D01*
X234769D01*
X232519Y1037412D01*
X218571D01*
X216452Y1039531D01*
X212017D01*
X210975Y1038489D01*
X209387D01*
X208345Y1039531D01*
X190307D01*
X186961Y1042877D01*
X181861D01*
X178117Y1046621D01*
X174921D01*
X174119Y1045819D01*
X170614D01*
X166319Y1050114D01*
Y1053819D01*
X163119Y1057019D01*
X160719D01*
X157419Y1060319D01*
X153819D01*
X147829Y1066309D01*
X137646D01*
X129283Y1074672D01*
X125499D01*
G01X327121Y1018637D02*
X318851D01*
X306445Y1023775D01*
X249083D01*
X245959Y1026899D01*
X235989D01*
X233400Y1029488D01*
X228711D01*
X228081Y1028858D01*
Y1027968D01*
X227451Y1027338D01*
X225981D01*
X225351Y1027968D01*
Y1028858D01*
X224721Y1029488D01*
X204450D01*
X203469Y1030469D01*
Y1031758D01*
X202389Y1032838D01*
X189599D01*
X186253Y1036184D01*
X173658D01*
X166582Y1043260D01*
X159470D01*
X149557Y1053173D01*
Y1057428D01*
X147369Y1059616D01*
X137569D01*
X129206Y1067979D01*
X125499D01*
G01X325426Y1033061D02*
X321153D01*
X308740Y1038202D01*
X286136D01*
X264564Y1047137D01*
X260998Y1050703D01*
X258335D01*
X252547Y1056491D01*
X249859D01*
X247309Y1053941D01*
X242869D01*
X240551Y1056259D01*
X220117D01*
X216768Y1059608D01*
X197961D01*
X187919Y1069650D01*
X178287D01*
X177456Y1068819D01*
X175019D01*
X173519Y1070319D01*
X169719D01*
X163039Y1076999D01*
X158839D01*
X155619Y1080219D01*
X151719D01*
X148902Y1083036D01*
X139751D01*
X138575Y1084212D01*
Y1086259D01*
X138075Y1086759D01*
X135156D01*
X131836Y1088134D01*
X130896Y1087744D01*
X130292Y1086288D01*
X129352Y1085898D01*
X128168Y1086389D01*
X127778Y1087329D01*
X128382Y1088785D01*
X127992Y1089725D01*
X126601Y1090302D01*
X125499Y1091404D01*
G01X325425Y1026662D02*
X319974D01*
X307679Y1031754D01*
X275282D01*
X257101Y1039269D01*
X254071Y1042300D01*
X252619Y1042899D01*
X249447D01*
X246065Y1041499D01*
X243552D01*
X240412Y1042799D01*
X236813Y1046399D01*
X235421D01*
X231585Y1044809D01*
X221419D01*
X215474Y1047271D01*
X203192D01*
X202152Y1046231D01*
X201639Y1046230D01*
X200689D01*
X200688Y1046231D01*
X200140D01*
X199138Y1047233D01*
X196006D01*
X192667Y1050572D01*
X187004D01*
X186010Y1049578D01*
X185430D01*
X185429Y1049577D01*
X184589D01*
X184588Y1049578D01*
X183998D01*
X183040Y1050536D01*
X181115D01*
X170830Y1057409D01*
X165007Y1063231D01*
X153741Y1067898D01*
X148722Y1072916D01*
X145795Y1074129D01*
X143729D01*
X142602Y1073002D01*
X140735D01*
X139748Y1073989D01*
X137734D01*
X129304Y1082419D01*
X126553D01*
X125499Y1081365D01*
G01X325425Y1027882D02*
X320217D01*
X307922Y1032974D01*
X280825D01*
X280335Y1033464D01*
X278175D01*
X277685Y1032974D01*
X275525D01*
X273529Y1033799D01*
X273264Y1034440D01*
X271266Y1035265D01*
X270626Y1034999D01*
X268630Y1035824D01*
X268365Y1036465D01*
X266367Y1037290D01*
X265727Y1037024D01*
X263731Y1037849D01*
X263466Y1038490D01*
X261468Y1039315D01*
X260828Y1039049D01*
X257792Y1040304D01*
X254762Y1043335D01*
X252861Y1044119D01*
X249202D01*
X245822Y1042719D01*
X243795D01*
X241104Y1043834D01*
X237319Y1047619D01*
X235178D01*
X231342Y1046029D01*
X228344D01*
X227854Y1046519D01*
X225694D01*
X225204Y1046029D01*
X221662D01*
X215717Y1048491D01*
X213557D01*
X213067Y1048981D01*
X210907D01*
X210417Y1048491D01*
X203178D01*
X202094Y1049575D01*
X200298D01*
X199176Y1048453D01*
X196512D01*
X193173Y1051792D01*
X187082D01*
X185952Y1052922D01*
X184156D01*
X183034Y1051800D01*
X183002D01*
X182958Y1051756D01*
X181486D01*
X179691Y1052956D01*
X179555Y1053635D01*
X177759Y1054836D01*
X177079Y1054701D01*
X171608Y1058357D01*
X169447Y1060518D01*
Y1061211D01*
X167919Y1062739D01*
X167226D01*
X165699Y1064266D01*
X159330Y1066904D01*
X159065Y1067545D01*
X157068Y1068372D01*
X156428Y1068107D01*
X154433Y1068933D01*
X149414Y1073951D01*
X146038Y1075349D01*
X143690D01*
X142691Y1076348D01*
X140747D01*
X139608Y1075209D01*
X138240D01*
X129810Y1083639D01*
X126571D01*
X125499Y1084711D01*
G01X325426Y1037034D02*
X321807D01*
X309323Y1042205D01*
X288181D01*
X266211Y1051303D01*
X261243Y1056271D01*
X259556D01*
X252643Y1063184D01*
X250235D01*
X246674Y1059623D01*
X243185D01*
X236374Y1066434D01*
X234769D01*
X232519Y1064184D01*
X218571D01*
X216452Y1066303D01*
X199719D01*
X195775Y1070247D01*
Y1074155D01*
X193586Y1076344D01*
X170114D01*
X164470Y1081988D01*
X160688D01*
X156962Y1085714D01*
X153173D01*
X149169Y1089718D01*
X137507D01*
X129128Y1098097D01*
X125499D01*
G01X326926Y1048574D02*
X322822D01*
X311039Y1053454D01*
X293430D01*
X279327Y1059296D01*
X261400Y1077223D01*
X258049D01*
X252402Y1082870D01*
X219664D01*
X216531Y1086003D01*
X214102D01*
X207027Y1093078D01*
X197280D01*
X193934Y1096424D01*
X182462D01*
X180363Y1098523D01*
X176265D01*
X172069Y1102719D01*
X170187D01*
X165565Y1107341D01*
X159639D01*
X153824Y1113156D01*
X142745D01*
X142744Y1113157D01*
X140862D01*
X140861Y1113156D01*
X134073D01*
X133353Y1113876D01*
Y1115310D01*
X132633Y1116030D01*
X131353D01*
X130633Y1115310D01*
Y1113876D01*
X129913Y1113156D01*
X127172D01*
X125499Y1111483D01*
G01X326926Y1044222D02*
X322869D01*
X310286Y1049434D01*
X290103D01*
X276908Y1054900D01*
X261058Y1070750D01*
X257881D01*
X256212Y1072419D01*
X250399D01*
X246971Y1075847D01*
X233906D01*
X231292Y1078461D01*
X217967D01*
X215381Y1081047D01*
X209386D01*
X204048Y1086385D01*
X197280D01*
X193934Y1089731D01*
X176765D01*
X166235Y1100261D01*
X160427D01*
X157369Y1103319D01*
X146727D01*
X143583Y1106463D01*
X139492D01*
X138772Y1107183D01*
Y1108198D01*
X138052Y1108918D01*
X136772D01*
X136052Y1108198D01*
Y1107183D01*
X135332Y1106463D01*
X134052D01*
X133332Y1107183D01*
Y1108198D01*
X132612Y1108918D01*
X131332D01*
X130612Y1108198D01*
Y1107183D01*
X129892Y1106463D01*
X127172D01*
X125499Y1104790D01*
G01X326926Y1059356D02*
X323860D01*
X284741Y1075550D01*
X264115Y1096176D01*
X258795D01*
X254470Y1100501D01*
X248183D01*
X245566Y1103118D01*
X227978D01*
X224097Y1106999D01*
X221289D01*
X215131Y1113157D01*
X199070D01*
X195724Y1116503D01*
X182828D01*
X179563Y1119768D01*
X170659D01*
X164678Y1125749D01*
X160439D01*
X156299Y1129889D01*
X139632D01*
X138912Y1130609D01*
Y1131581D01*
X138192Y1132301D01*
X136912D01*
X136192Y1131581D01*
Y1130609D01*
X135472Y1129889D01*
X134192D01*
X133472Y1130609D01*
Y1131581D01*
X132752Y1132301D01*
X131472D01*
X130752Y1131581D01*
Y1130609D01*
X130032Y1129889D01*
X127173D01*
X125499Y1128215D01*
G01X326926Y1053744D02*
X323908D01*
X306830Y1060818D01*
X306190Y1060553D01*
X304193Y1061380D01*
X303928Y1062021D01*
X301933Y1062847D01*
X301293Y1062582D01*
X299296Y1063409D01*
X299031Y1064050D01*
X297036Y1064876D01*
X296396Y1064611D01*
X294399Y1065438D01*
X294134Y1066079D01*
X292139Y1066905D01*
X291499Y1066640D01*
X289502Y1067467D01*
X289237Y1068108D01*
X287242Y1068934D01*
X286602Y1068669D01*
X284605Y1069496D01*
X284340Y1070137D01*
X280152Y1071872D01*
X278625Y1073399D01*
X277932D01*
X276404Y1074927D01*
Y1075620D01*
X274877Y1077147D01*
X274184D01*
X272656Y1078675D01*
Y1079368D01*
X271129Y1080895D01*
X270436D01*
X268908Y1082423D01*
Y1083116D01*
X266744Y1085280D01*
X264749Y1086107D01*
X264109Y1085842D01*
X262113Y1086669D01*
X261848Y1087311D01*
X256657Y1089463D01*
X253021Y1093099D01*
X251063D01*
X246431Y1091182D01*
X235881D01*
X229196Y1093952D01*
X221319D01*
X218877Y1096394D01*
X216239Y1102766D01*
X214864Y1104142D01*
X203161D01*
X202136Y1103117D01*
X200163D01*
X199133Y1104147D01*
X197678D01*
X194496Y1105465D01*
X193315Y1106646D01*
X191280Y1107489D01*
X187019D01*
X185994Y1106464D01*
X184021D01*
X183040Y1107445D01*
X181647D01*
X179775Y1108221D01*
X177016Y1110980D01*
X166057Y1115518D01*
X163782Y1117793D01*
X156297Y1120895D01*
X143781D01*
X142735Y1119849D01*
X140764D01*
X139786Y1120827D01*
X137225D01*
X135817Y1119421D01*
X133350Y1118399D01*
X130223D01*
X128301Y1119195D01*
X126518D01*
X125499Y1118176D01*
G01X326926Y1054964D02*
X324151D01*
X280844Y1072907D01*
X267436Y1086315D01*
X257349Y1090498D01*
X253527Y1094319D01*
X250817D01*
X246188Y1092402D01*
X236124D01*
X229439Y1095172D01*
X221825D01*
X219912Y1097085D01*
X217274Y1103458D01*
X215370Y1105362D01*
X203246D01*
X202144Y1106464D01*
X200262D01*
X199165Y1105367D01*
X197921D01*
X195188Y1106500D01*
X194007Y1107681D01*
X191523Y1108709D01*
X187104D01*
X186002Y1109811D01*
X184120D01*
X182974Y1108665D01*
X181891D01*
X180467Y1109256D01*
X177708Y1112015D01*
X166749Y1116553D01*
X164474Y1118828D01*
X156540Y1122115D01*
X143826D01*
X142745Y1123196D01*
X140861D01*
X139712Y1122047D01*
X136719D01*
X135126Y1120456D01*
X133107Y1119619D01*
X130466D01*
X128544Y1120415D01*
X126606D01*
X125499Y1121522D01*
G01X328122Y1063480D02*
X324153D01*
X288452Y1078259D01*
X264240Y1102471D01*
X259806D01*
X255714Y1106563D01*
X248706D01*
X245451Y1109818D01*
X227408D01*
X216266Y1120960D01*
X212930D01*
X210694Y1123196D01*
X198970D01*
X195624Y1126542D01*
X177343D01*
X171788Y1132097D01*
X162145D01*
X157661Y1136581D01*
X127172D01*
X125499Y1134908D01*
G01X328122Y1068642D02*
X324968D01*
X293006Y1081877D01*
X265608Y1109275D01*
X260740D01*
X258285Y1111730D01*
X255654D01*
X253565Y1113819D01*
X250559D01*
X245659Y1118719D01*
X230451D01*
X223119Y1126051D01*
X219006D01*
X215695Y1129362D01*
X213885D01*
X206666Y1136581D01*
X196204D01*
X192857Y1139928D01*
X175676D01*
X169887Y1145717D01*
X162049D01*
X158710Y1149056D01*
Y1150960D01*
X155565Y1154105D01*
X153697D01*
X148285Y1159517D01*
Y1176018D01*
X147565Y1176738D01*
X142745D01*
X142744Y1176739D01*
X140862D01*
X140861Y1176738D01*
X134053D01*
X133333Y1176018D01*
Y1174361D01*
X132613Y1173641D01*
X131333D01*
X130613Y1174361D01*
Y1176018D01*
X129893Y1176738D01*
X127173D01*
X125499Y1178412D01*
G01X328122Y1072840D02*
X325080D01*
X295828Y1084957D01*
X265121Y1115664D01*
X258981D01*
X256744Y1117901D01*
X252050D01*
X246985Y1122966D01*
X243491D01*
X240642Y1125815D01*
X236436D01*
X236025Y1126226D01*
X235223Y1126558D01*
X233485D01*
X232746Y1125819D01*
X230557D01*
X223889Y1132487D01*
X220324D01*
X216711Y1136100D01*
X213888D01*
X206714Y1143274D01*
X196442D01*
X193094Y1146622D01*
X178616D01*
X172797Y1152441D01*
X166095D01*
X157104Y1161432D01*
Y1177046D01*
X150718Y1183432D01*
X139492D01*
X138772Y1182712D01*
Y1180823D01*
X138052Y1180103D01*
X136772D01*
X136052Y1180823D01*
Y1182712D01*
X135332Y1183432D01*
X134052D01*
X133332Y1182712D01*
Y1180823D01*
X132612Y1180103D01*
X131332D01*
X130612Y1180823D01*
Y1182712D01*
X129892Y1183432D01*
X127172D01*
X125499Y1185105D01*
G01X328122Y1078044D02*
X325995D01*
X304094Y1087115D01*
X302568Y1088642D01*
X301874D01*
X300346Y1090170D01*
Y1090863D01*
X298819Y1092390D01*
X298126D01*
X296598Y1093918D01*
Y1094611D01*
X295071Y1096138D01*
X294378D01*
X292850Y1097666D01*
Y1098359D01*
X291323Y1099886D01*
X290630D01*
X289102Y1101414D01*
Y1102107D01*
X287575Y1103634D01*
X286882D01*
X285354Y1105162D01*
Y1105855D01*
X283827Y1107382D01*
X283134D01*
X281606Y1108910D01*
Y1109603D01*
X280079Y1111130D01*
X279386D01*
X277858Y1112658D01*
Y1113351D01*
X276331Y1114878D01*
X275638D01*
X274110Y1116406D01*
Y1117099D01*
X272583Y1118626D01*
X271890D01*
X270362Y1120154D01*
Y1120847D01*
X266934Y1124276D01*
X258976D01*
X252497Y1130755D01*
X242873Y1134741D01*
X234483D01*
X232400Y1136823D01*
X228564Y1138412D01*
X223310Y1143666D01*
X214083Y1147489D01*
X203890Y1157683D01*
X203061D01*
X202037Y1156659D01*
X200062D01*
X199033Y1157688D01*
X195498D01*
X193109Y1160077D01*
X189751D01*
X188706Y1161122D01*
X186813D01*
X185699Y1160008D01*
X184020D01*
X183040Y1160988D01*
X180479D01*
X178192Y1158701D01*
X175474D01*
X173463Y1159536D01*
X171453Y1160370D01*
X167369Y1164453D01*
X165977Y1167816D01*
Y1184740D01*
X163427Y1187290D01*
X146005Y1194508D01*
X143772D01*
X142735Y1193471D01*
X140764D01*
X139761Y1194474D01*
X137516D01*
X136202Y1193160D01*
X133668Y1192114D01*
X131297D01*
X129481Y1192866D01*
X126567D01*
X125499Y1191798D01*
G01X328122Y1087642D02*
X326963D01*
X313200Y1093343D01*
X263102Y1143441D01*
X259053D01*
X252331Y1150163D01*
X248954D01*
X245683Y1153434D01*
X241299D01*
X240579Y1152714D01*
Y1152104D01*
X239859Y1151384D01*
X238569D01*
X237849Y1152104D01*
Y1152714D01*
X237129Y1153434D01*
X233151D01*
X224611Y1161974D01*
X220738D01*
X217697Y1165015D01*
Y1168780D01*
X213085Y1173392D01*
X200373D01*
X193680Y1180085D01*
X183218D01*
X180878Y1182425D01*
Y1189352D01*
X170368Y1199862D01*
X161963D01*
X158879Y1202946D01*
X154622D01*
X148330Y1209238D01*
X143344D01*
X142392Y1210190D01*
X140632D01*
X136631Y1206189D01*
X127840D01*
X125499Y1208530D01*
G01X328122Y1083534D02*
X326347D01*
X309451Y1090533D01*
X263225Y1136759D01*
X259075D01*
X252552Y1143282D01*
X243440D01*
X240103Y1146619D01*
X229799D01*
X222398Y1154020D01*
X219078D01*
X206399Y1166699D01*
X195086D01*
X191739Y1170046D01*
X183146D01*
X182516Y1170676D01*
Y1173668D01*
X181886Y1174298D01*
X180416D01*
X179786Y1173668D01*
Y1170676D01*
X179156Y1170046D01*
X177494D01*
X173913Y1173627D01*
Y1185743D01*
X169017Y1190639D01*
X153907Y1196897D01*
X147293Y1203511D01*
X127173D01*
X125499Y1201837D01*
G01X328122Y1079264D02*
X326238D01*
X304786Y1088150D01*
X267440Y1125496D01*
X259482D01*
X253188Y1131790D01*
X243116Y1135961D01*
X234989D01*
X233092Y1137858D01*
X229256Y1139447D01*
X224002Y1144701D01*
X214775Y1148524D01*
X204396Y1158903D01*
X203146D01*
X202043Y1160006D01*
X200163D01*
X199065Y1158908D01*
X196004D01*
X193615Y1161297D01*
X190257D01*
X189212Y1162342D01*
X186834D01*
X185822Y1163354D01*
X184120D01*
X182974Y1162208D01*
X179973D01*
X177686Y1159921D01*
X175718D01*
X172145Y1161404D01*
X168404Y1165145D01*
X167197Y1168059D01*
Y1185246D01*
X164119Y1188324D01*
X146248Y1195728D01*
X143835D01*
X142745Y1196818D01*
X140861D01*
X139737Y1195694D01*
X137008D01*
X135511Y1194195D01*
X133426Y1193334D01*
X131540D01*
X129724Y1194086D01*
X126557D01*
X125499Y1195144D01*
G01X327040Y866427D02*
X325082Y864469D01*
Y862325D01*
X290442Y827685D01*
X279068Y800228D01*
X263278Y784438D01*
X259280D01*
X253261Y778419D01*
X249870D01*
X246370Y774919D01*
X243269D01*
X238769Y770419D01*
Y767318D01*
X237120Y765669D01*
X236026Y765008D01*
X234906Y764716D01*
X231785Y764196D01*
X222955Y763410D01*
X222174Y764064D01*
X222147Y764365D01*
X222126Y764599D01*
X221347Y765252D01*
X220059Y765137D01*
X219413Y764365D01*
X219407Y764358D01*
X219455Y763822D01*
X218801Y763042D01*
X214941Y762698D01*
X173860D01*
X173140Y763418D01*
Y764246D01*
X172420Y764966D01*
X171140D01*
X170420Y764246D01*
Y763418D01*
X169700Y762698D01*
X163035D01*
X162315Y763418D01*
Y764469D01*
X161595Y765189D01*
X160305D01*
X159585Y764469D01*
Y763418D01*
X158865Y762698D01*
X155790D01*
X154689Y762825D01*
X148322Y764109D01*
X145504Y765084D01*
X144619Y765969D01*
Y769187D01*
X143662Y770144D01*
X141641D01*
G01X324723Y870267D02*
X324003D01*
X323049Y869313D01*
Y863064D01*
X288617Y828632D01*
X277363Y801463D01*
X262333Y786433D01*
X258475D01*
X254461Y782419D01*
X249769D01*
X246269Y778919D01*
X243768D01*
X237393Y772544D01*
X235294D01*
X232169Y769419D01*
X228097D01*
X227377Y768699D01*
Y766892D01*
X226657Y766172D01*
X225377D01*
X224657Y766892D01*
Y768699D01*
X223937Y769419D01*
X220669D01*
X216777Y765527D01*
X214826Y764719D01*
X181019D01*
X177270Y768468D01*
X173870D01*
X173233Y769105D01*
X168559D01*
X167839Y768385D01*
Y765584D01*
X167119Y764864D01*
X165839D01*
X165119Y765584D01*
Y768385D01*
X164399Y769105D01*
X161679D01*
X160793Y768219D01*
X157900D01*
X157180Y767499D01*
Y765736D01*
X156460Y765016D01*
X154164D01*
X150871Y768309D01*
Y769327D01*
X151979Y770435D01*
Y771453D01*
X151066Y772366D01*
X150048D01*
X148940Y771258D01*
X147922D01*
X146861Y772319D01*
X145867D01*
X141641Y776545D01*
Y776837D01*
G01X324723Y876397D02*
X320135D01*
X317902Y874164D01*
Y865220D01*
X283884Y831202D01*
X273307Y805443D01*
X271780Y803916D01*
X271087D01*
X269559Y802388D01*
Y801695D01*
X268032Y800168D01*
X267339D01*
X265811Y798640D01*
Y797947D01*
X261980Y794116D01*
X258162D01*
X251965Y787919D01*
X246872D01*
X241826Y785829D01*
X240323Y784326D01*
X239630D01*
X238102Y782798D01*
Y782105D01*
X236575Y780578D01*
X234951D01*
X232456Y778083D01*
X228359D01*
X227869Y778573D01*
X225709D01*
X225219Y778083D01*
X218957D01*
X214991Y774117D01*
X212219D01*
X211729Y774607D01*
X209569D01*
X209079Y774117D01*
X202834D01*
X201797Y775154D01*
X200258D01*
X199271Y774167D01*
X198566D01*
X190637Y777451D01*
X186718D01*
X185662Y778507D01*
X184101D01*
X183055Y777461D01*
X180111D01*
X177699Y775049D01*
X175188D01*
X173591Y776646D01*
X170007Y778131D01*
X167395Y780743D01*
X164555D01*
X163379Y781919D01*
X161858D01*
X160767Y780828D01*
X158232D01*
X157217Y779813D01*
X146925D01*
X144856Y781882D01*
Y782544D01*
X143591Y783809D01*
Y784927D01*
X141641Y786877D01*
G01X324723Y875177D02*
X320641D01*
X319122Y873658D01*
Y864714D01*
X284920Y830512D01*
X274343Y804753D01*
X262486Y792896D01*
X258668D01*
X252471Y786699D01*
X247115D01*
X242518Y784794D01*
X237081Y779358D01*
X235457D01*
X232962Y776863D01*
X219463D01*
X215497Y772897D01*
X202867D01*
X201790Y771820D01*
X200286D01*
X199159Y772947D01*
X198323D01*
X190394Y776231D01*
X186761D01*
X185691Y775161D01*
X184141D01*
X183061Y776241D01*
X180617D01*
X178205Y773829D01*
X174682D01*
X172899Y775611D01*
X169315Y777096D01*
X166889Y779523D01*
X164527D01*
X163423Y778419D01*
X161880D01*
X160691Y779608D01*
X158738D01*
X157723Y778593D01*
X146419D01*
X143636Y781376D01*
Y782038D01*
X142916Y782758D01*
X142413D01*
X141641Y783530D01*
G01X324723Y887446D02*
X313044D01*
X306723Y881125D01*
Y870160D01*
X273796Y837233D01*
X268357Y824102D01*
X260397Y818784D01*
X258340Y816727D01*
Y813990D01*
X252916Y808566D01*
X250376D01*
X248045Y810897D01*
X247027D01*
X246114Y809984D01*
Y808966D01*
X247409Y807671D01*
Y806653D01*
X245975Y805219D01*
X241999D01*
X241279Y805939D01*
Y807740D01*
X240559Y808460D01*
X239363D01*
X238559Y807656D01*
Y805939D01*
X237839Y805219D01*
X235119D01*
X231719Y801819D01*
X227945D01*
X227225Y802539D01*
Y804687D01*
X226505Y805407D01*
X225225D01*
X224505Y804687D01*
Y802539D01*
X223785Y801819D01*
X219719D01*
X216490Y798590D01*
X194684D01*
X194054Y799220D01*
Y800888D01*
X193424Y801518D01*
X191954D01*
X191324Y800888D01*
Y799220D01*
X190694Y798590D01*
X188947D01*
X185610Y801927D01*
X184138D01*
X183581Y801370D01*
X180653D01*
X177717Y798434D01*
X174880D01*
X172916Y800398D01*
X169139D01*
X168419Y799678D01*
Y797601D01*
X167699Y796881D01*
X166409D01*
X165689Y797601D01*
Y799678D01*
X164969Y800398D01*
X162249D01*
X159405Y797554D01*
X151984D01*
X150935Y798603D01*
X145625D01*
X143965Y800263D01*
X141641D01*
G01X324723Y881566D02*
X315481D01*
X312603Y878688D01*
Y867296D01*
X278788Y833481D01*
X271038Y814772D01*
X262062Y805796D01*
X259996D01*
X253769Y799569D01*
X250069D01*
X246819Y796319D01*
X242981D01*
X237843Y791181D01*
X233457D01*
X232569Y792069D01*
X228541D01*
X227821Y791349D01*
Y789480D01*
X227101Y788760D01*
X225821D01*
X225101Y789480D01*
Y791349D01*
X224381Y792069D01*
X220269D01*
X216750Y788550D01*
X208051D01*
X207331Y787830D01*
Y786757D01*
X206611Y786037D01*
X205321D01*
X204601Y786757D01*
Y787830D01*
X203881Y788550D01*
X198391D01*
X197671Y787830D01*
Y785585D01*
X196951Y784865D01*
X195661D01*
X194941Y785585D01*
Y787830D01*
X194221Y788550D01*
X189595D01*
X186248Y791897D01*
X184143D01*
X182170Y789924D01*
Y788949D01*
X181540Y788319D01*
X180765D01*
X180135Y787689D01*
Y786808D01*
X179505Y786178D01*
X178035D01*
X177405Y786808D01*
Y787689D01*
X176775Y788319D01*
X175305D01*
X174675Y787689D01*
Y786808D01*
X174045Y786178D01*
X172575D01*
X171945Y786808D01*
Y787689D01*
X171315Y788319D01*
X149221D01*
X143970Y793570D01*
X141641D01*
G01X325324Y918886D02*
X297610D01*
X274084Y895360D01*
Y885221D01*
X261532Y872669D01*
X256407D01*
X251648Y867910D01*
X249150D01*
X245470Y864230D01*
X242226D01*
X237585Y859589D01*
X219770D01*
X217186Y862173D01*
X213484D01*
X212764Y861453D01*
Y859838D01*
X212044Y859118D01*
X210764D01*
X210044Y859838D01*
Y861453D01*
X209324Y862173D01*
X208044D01*
X207324Y861453D01*
Y859838D01*
X206604Y859118D01*
X205324D01*
X204604Y859838D01*
Y861453D01*
X203884Y862173D01*
X198449D01*
X191755Y855479D01*
X183664D01*
X179549Y859594D01*
X169603D01*
X165888Y855879D01*
X161476D01*
X158945Y853348D01*
X152285D01*
X151565Y852628D01*
Y851514D01*
X150845Y850794D01*
X149565D01*
X148845Y851514D01*
Y852628D01*
X148125Y853348D01*
X144530D01*
X141641Y850459D01*
G01X325324Y914966D02*
X299517D01*
X278004Y893453D01*
Y882585D01*
X261240Y865821D01*
X255377D01*
X249489Y859933D01*
X245289D01*
X238443Y853087D01*
X233523D01*
X232066Y851630D01*
X227117D01*
X226397Y850910D01*
Y849218D01*
X225677Y848498D01*
X224397D01*
X223677Y849218D01*
Y850910D01*
X222957Y851630D01*
X218345D01*
X216978Y852997D01*
X211839D01*
X211119Y852277D01*
Y851119D01*
X210399Y850399D01*
X209119D01*
X208399Y851119D01*
Y852277D01*
X207679Y852997D01*
X204814D01*
X203950Y852133D01*
X198017D01*
X194676Y848792D01*
X184189D01*
X180448Y852533D01*
X173912D01*
X171343Y849964D01*
X168578D01*
X167858Y849244D01*
Y847368D01*
X167138Y846648D01*
X165858D01*
X165138Y847368D01*
Y849244D01*
X164418Y849964D01*
X161698D01*
X158170Y846436D01*
X144311D01*
X141641Y843766D01*
G01X326124Y929188D02*
X291555D01*
X261355Y898988D01*
X259658D01*
X258605Y897935D01*
Y896047D01*
X256228Y893670D01*
X251259D01*
X249370Y891781D01*
Y889425D01*
X245541Y885596D01*
X236797D01*
X233451Y882250D01*
X232326D01*
X231606Y881530D01*
Y879887D01*
X230886Y879167D01*
X229606D01*
X228886Y879887D01*
Y881530D01*
X228166Y882250D01*
X226886D01*
X226166Y881530D01*
Y879887D01*
X225446Y879167D01*
X224166D01*
X223446Y879887D01*
Y881530D01*
X222726Y882250D01*
X221446D01*
X220726Y881530D01*
Y879887D01*
X220006Y879167D01*
X218726D01*
X218006Y879887D01*
Y881530D01*
X217286Y882250D01*
X212454D01*
X211734Y881530D01*
Y880626D01*
X211014Y879906D01*
X209734D01*
X209014Y880626D01*
Y881530D01*
X208294Y882250D01*
X197209D01*
X193863Y878904D01*
X181264D01*
X177918Y875558D01*
X166882D01*
X163902Y872578D01*
X162228D01*
X158769Y869119D01*
X152381D01*
X151661Y868399D01*
Y867292D01*
X150941Y866572D01*
X149661D01*
X148941Y867292D01*
Y868399D01*
X148221Y869119D01*
X143568D01*
X141641Y867192D01*
G01X326124Y924026D02*
X294425D01*
X268545Y898146D01*
Y889604D01*
X263604Y884669D01*
X262231D01*
X261301Y885599D01*
X259683D01*
X258674Y884590D01*
X255000D01*
X249254Y878845D01*
X246896Y873157D01*
X244431Y872135D01*
X241061D01*
X240571Y872625D01*
X238411D01*
X237921Y872135D01*
X234743D01*
X230947Y868339D01*
X228412D01*
X227922Y868829D01*
X225762D01*
X225272Y868339D01*
X219624D01*
X216883Y871080D01*
X203136D01*
X202002Y872214D01*
X200184D01*
X199027Y871057D01*
X196710D01*
X193416Y867763D01*
X186954D01*
X185852Y868865D01*
X183970D01*
X182845Y867740D01*
X180218D01*
X177495Y865017D01*
X175411D01*
X173008Y867420D01*
X169225D01*
X163835Y862030D01*
X160154D01*
X156202Y860391D01*
X144786D01*
X143880Y859485D01*
X142655D01*
X141641Y860499D01*
G01X326124Y922806D02*
X294931D01*
X269765Y897640D01*
Y889098D01*
X264109Y883449D01*
X262317D01*
X261116Y882248D01*
X259737D01*
X258615Y883370D01*
X255506D01*
X250289Y878153D01*
X247830Y872223D01*
X244674Y870915D01*
X235249D01*
X231453Y867119D01*
X219118D01*
X216377Y869860D01*
X203051D01*
X202054Y868863D01*
X200025D01*
X199051Y869837D01*
X197216D01*
X193922Y866543D01*
X186869D01*
X185845Y865519D01*
X183870D01*
X182869Y866520D01*
X180724D01*
X178001Y863797D01*
X174905D01*
X172502Y866200D01*
X169731D01*
X164341Y860810D01*
X160397D01*
X156445Y859171D01*
X145292D01*
X144386Y858265D01*
X142754D01*
X141641Y857152D01*
G01X326124Y933108D02*
X289181D01*
X261757Y905684D01*
X258034D01*
X254463Y902113D01*
Y899948D01*
X253110Y898595D01*
X249978D01*
X247019Y895636D01*
X241419D01*
X240699Y894916D01*
Y891623D01*
X239979Y890903D01*
X238699D01*
X237979Y891623D01*
Y894916D01*
X237259Y895636D01*
X233640D01*
X231068Y893064D01*
X227861D01*
X227141Y892344D01*
Y888961D01*
X226421Y888241D01*
X225225D01*
X224421Y889045D01*
Y892344D01*
X223701Y893064D01*
X220746D01*
X216625Y888943D01*
X211719D01*
X210999Y888223D01*
Y887430D01*
X210279Y886710D01*
X208999D01*
X208279Y887430D01*
Y888223D01*
X207559Y888943D01*
X197422D01*
X194075Y885596D01*
X190366D01*
X189122Y884352D01*
X187682D01*
X186438Y885596D01*
X178532D01*
X173912Y880976D01*
X161958D01*
X159846Y878864D01*
Y877140D01*
X158585Y875879D01*
X152319D01*
X151599Y875159D01*
Y873993D01*
X150879Y873273D01*
X149599D01*
X148879Y873993D01*
Y875159D01*
X148159Y875879D01*
X143635D01*
X141641Y873885D01*
G01X326124Y938188D02*
X286113D01*
X263970Y916045D01*
X259285D01*
X252904Y909664D01*
X250935D01*
X246946Y905675D01*
X240211D01*
X236870Y902334D01*
X228046D01*
X227326Y901614D01*
Y900012D01*
X226606Y899292D01*
X225326D01*
X224606Y900012D01*
Y901614D01*
X223886Y902334D01*
X220368D01*
X218254Y900220D01*
X215525D01*
X214895Y899590D01*
Y897538D01*
X214265Y896908D01*
X212932D01*
X212165Y897675D01*
Y899590D01*
X211535Y900220D01*
X210065D01*
X209435Y899590D01*
Y898598D01*
X208805Y897968D01*
X207335D01*
X206705Y898598D01*
Y899590D01*
X206075Y900220D01*
X204809D01*
X203570Y898981D01*
X197631D01*
X190938Y892288D01*
X170296D01*
X166941Y888933D01*
X160490D01*
X157021Y885464D01*
X151304D01*
X148734Y882894D01*
X143958D01*
X141641Y880577D01*
G01X327124Y942151D02*
X284386D01*
X265426Y923191D01*
X259810D01*
X252987Y916368D01*
X251329D01*
X247329Y912368D01*
X240973D01*
X239834Y911229D01*
X238343D01*
X237204Y912368D01*
X234690D01*
X232241Y909919D01*
X228353D01*
X227633Y909199D01*
Y907899D01*
X226913Y907179D01*
X225633D01*
X224913Y907899D01*
Y909199D01*
X224193Y909919D01*
X221308D01*
X217964Y906575D01*
X212557D01*
X211837Y905855D01*
Y905008D01*
X211117Y904288D01*
X209837D01*
X209117Y905008D01*
Y905855D01*
X208397Y906575D01*
X204052D01*
X203151Y905674D01*
X196186D01*
X195556Y905044D01*
Y903868D01*
X194926Y903238D01*
X193456D01*
X192826Y903868D01*
Y905044D01*
X192196Y905674D01*
X190854D01*
X187509Y902329D01*
X183170D01*
X178561Y897720D01*
X176624D01*
X175994Y898350D01*
Y899437D01*
X175364Y900067D01*
X174108D01*
X172887Y898846D01*
X169227D01*
X167006Y896625D01*
X160853D01*
X156044Y891816D01*
X153405D01*
X151270Y889681D01*
X144052D01*
X141641Y887270D01*
G01X327124Y947316D02*
X282133D01*
X265256Y930439D01*
X258699D01*
X253819Y925559D01*
X251455D01*
X246952Y921056D01*
X241129D01*
X240639Y921546D01*
X238479D01*
X237989Y921056D01*
X234288D01*
X231352Y918120D01*
X227523D01*
X227033Y918610D01*
X224873D01*
X224383Y918120D01*
X219963D01*
X216545Y914702D01*
X203158D01*
X202144Y915716D01*
X200262D01*
X199137Y914591D01*
X196595D01*
X194289Y912285D01*
X190105D01*
X189088Y911268D01*
X187104D01*
X186003Y912369D01*
X184119D01*
X182995Y911245D01*
X180415D01*
X177399Y908229D01*
X175179D01*
X172499Y905549D01*
X161683D01*
X157624Y901490D01*
X153478D01*
X148907Y896919D01*
X144704D01*
X144076Y896291D01*
X142660D01*
X141641Y897310D01*
G01X327124Y946096D02*
X282639D01*
X265762Y929219D01*
X259205D01*
X254325Y924339D01*
X251961D01*
X247458Y919836D01*
X234794D01*
X231858Y916900D01*
X220469D01*
X217051Y913482D01*
X203249D01*
X202136Y912369D01*
X200163D01*
X199161Y913371D01*
X197101D01*
X194795Y911065D01*
X190611D01*
X189594Y910048D01*
X187019D01*
X185994Y909023D01*
X184021D01*
X183019Y910025D01*
X180921D01*
X177905Y907009D01*
X175685D01*
X173005Y904329D01*
X162189D01*
X158130Y900270D01*
X153984D01*
X149413Y895699D01*
X145210D01*
X144582Y895071D01*
X142749D01*
X141641Y893963D01*
G01X327124Y960499D02*
X325447D01*
X321366Y956418D01*
X278006D01*
X263302Y941714D01*
X256806D01*
X254511Y939419D01*
X250032D01*
X247372Y936759D01*
X233293D01*
X229853Y933319D01*
X211922D01*
X211202Y932599D01*
Y930818D01*
X210482Y930098D01*
X209202D01*
X208482Y930818D01*
Y932599D01*
X207762Y933319D01*
X205042D01*
X202567Y935794D01*
X200011D01*
X197907Y933690D01*
X196889D01*
X196079Y934499D01*
X195061D01*
X194155Y933593D01*
Y932575D01*
X194965Y931765D01*
Y930748D01*
X193318Y929101D01*
X179014D01*
X177806Y927893D01*
X176294D01*
X175086Y929101D01*
X168127D01*
X166048Y927022D01*
Y926004D01*
X167894Y924158D01*
Y923140D01*
X166988Y922234D01*
X165970D01*
X164124Y924080D01*
X163106D01*
X159508Y920482D01*
Y918671D01*
X155844Y915007D01*
X153210D01*
X151069Y912866D01*
X143811D01*
X141641Y910696D01*
G01X327124Y955805D02*
X326433D01*
X323126Y952498D01*
X279844D01*
X263034Y935688D01*
X256538D01*
X253369Y932519D01*
X242006D01*
X241286Y931799D01*
Y931187D01*
X240566Y930467D01*
X239286D01*
X238566Y931187D01*
Y931799D01*
X237846Y932519D01*
X234761D01*
X231508Y929266D01*
X227061D01*
X226341Y928546D01*
Y927057D01*
X225621Y926337D01*
X224341D01*
X223621Y927057D01*
Y928546D01*
X222901Y929266D01*
X220139D01*
X216628Y925755D01*
X210869D01*
X210149Y925035D01*
Y924026D01*
X209429Y923306D01*
X208149D01*
X207429Y924026D01*
Y925035D01*
X206709Y925755D01*
X196905D01*
X193558Y922408D01*
X182338D01*
X181618Y921688D01*
Y920937D01*
X180898Y920217D01*
X179618D01*
X178898Y920937D01*
Y921688D01*
X178178Y922408D01*
X175458D01*
X173295Y920245D01*
Y919227D01*
X173981Y918541D01*
Y917523D01*
X173075Y916617D01*
X172057D01*
X171371Y917303D01*
X170353D01*
X165324Y912274D01*
X159753D01*
X156379Y908900D01*
X150749D01*
X147669Y905820D01*
X143458D01*
X141641Y904003D01*
G01X327121Y1020607D02*
X319218D01*
X306777Y1025760D01*
X251026D01*
X247778Y1029008D01*
X242358D01*
X238517Y1032849D01*
X237063D01*
X236433Y1033479D01*
Y1034838D01*
X235803Y1035468D01*
X234333D01*
X233703Y1034838D01*
Y1033479D01*
X233073Y1032849D01*
X220321D01*
X216985Y1036185D01*
X214179D01*
X213459Y1035465D01*
Y1034140D01*
X212739Y1033420D01*
X211459D01*
X210739Y1034140D01*
Y1035465D01*
X210019Y1036185D01*
X208739D01*
X208019Y1035465D01*
Y1034140D01*
X207299Y1033420D01*
X206019D01*
X205299Y1034140D01*
Y1035465D01*
X204579Y1036185D01*
X190753D01*
X187407Y1039531D01*
X177707D01*
X173619Y1043619D01*
X169721D01*
X162765Y1050575D01*
X161748D01*
X158862Y1047689D01*
X157844D01*
X156938Y1048595D01*
Y1049613D01*
X159823Y1052498D01*
Y1053517D01*
X157086Y1056254D01*
X153816D01*
X147951Y1062119D01*
X144155D01*
X141641Y1064633D01*
G01X325425Y1024677D02*
X319643D01*
X307440Y1029731D01*
X267099D01*
X264607Y1032223D01*
X259684D01*
X255719Y1036188D01*
X249847D01*
X249217Y1036818D01*
Y1039088D01*
X248587Y1039718D01*
X247117D01*
X246487Y1039088D01*
Y1036818D01*
X245857Y1036188D01*
X243543D01*
X237819Y1041912D01*
X234019D01*
X231519Y1039412D01*
X227861D01*
X227141Y1040132D01*
Y1041832D01*
X226421Y1042552D01*
X225141D01*
X224421Y1041832D01*
Y1040132D01*
X223701Y1039412D01*
X219419D01*
X215953Y1042878D01*
X211771D01*
X211051Y1043598D01*
Y1044465D01*
X210331Y1045185D01*
X209051D01*
X208331Y1044465D01*
Y1043598D01*
X207611Y1042878D01*
X189860D01*
X186514Y1046224D01*
X181886D01*
X179345Y1048765D01*
X175104D01*
X173310Y1050559D01*
Y1052151D01*
X172549Y1052912D01*
X169161D01*
X168519Y1053554D01*
Y1055819D01*
X164919Y1059419D01*
X161719D01*
X158619Y1062519D01*
X154619D01*
X148419Y1068719D01*
X144248D01*
X141641Y1071326D01*
G01X325425Y1029873D02*
X320532D01*
X308167Y1034996D01*
X282638D01*
X274721Y1038275D01*
X274081Y1038009D01*
X272084Y1038836D01*
X271819Y1039477D01*
X269824Y1040303D01*
X269184Y1040038D01*
X267187Y1040865D01*
X266922Y1041506D01*
X264927Y1042332D01*
X264287Y1042067D01*
X262290Y1042894D01*
X262025Y1043535D01*
X256542Y1045806D01*
X252549Y1049799D01*
X249762D01*
X245747Y1048136D01*
X243509D01*
X241247Y1049072D01*
X237321Y1052999D01*
X235171D01*
X230446Y1051042D01*
X221890D01*
X214867Y1053949D01*
X203177D01*
X202152Y1052924D01*
X201569Y1052923D01*
X200729D01*
X200728Y1052924D01*
X200140D01*
X199138Y1053926D01*
X196050D01*
X193641Y1056335D01*
X191672Y1057150D01*
X189090Y1059732D01*
Y1063080D01*
X188212Y1063958D01*
X187004D01*
X186010Y1062964D01*
X185409Y1062963D01*
X184589D01*
X184588Y1062964D01*
X183998D01*
X182996Y1063966D01*
X180952D01*
X178636Y1061650D01*
X173933D01*
X172283Y1063300D01*
X171161Y1064421D01*
X168765Y1065414D01*
X164136Y1070042D01*
X151850Y1075131D01*
X147151Y1079831D01*
X145757D01*
X144978Y1079052D01*
X142675D01*
X141641Y1078018D01*
G01X325426Y1039052D02*
X322061D01*
X309575Y1044223D01*
X288803D01*
X268753Y1052525D01*
X261656Y1059622D01*
X259381D01*
X253744Y1065259D01*
X248598D01*
X246302Y1062963D01*
X243540D01*
X237819Y1068684D01*
X234019D01*
X231519Y1066184D01*
X219419D01*
X215954Y1069649D01*
X211719D01*
X210999Y1070369D01*
Y1072433D01*
X210279Y1073153D01*
X208999D01*
X208279Y1072433D01*
Y1070369D01*
X207559Y1069649D01*
X199940D01*
X198096Y1071493D01*
Y1075432D01*
X193838Y1079690D01*
X177580D01*
X176860Y1080410D01*
Y1082109D01*
X176140Y1082829D01*
X174860D01*
X174140Y1082109D01*
Y1080410D01*
X173420Y1079690D01*
X170548D01*
X166009Y1084229D01*
Y1085247D01*
X167557Y1086795D01*
Y1087813D01*
X166651Y1088719D01*
X165633D01*
X164085Y1087171D01*
X163067D01*
X161140Y1089098D01*
X157040D01*
X153560Y1092578D01*
X143814D01*
X141641Y1094751D01*
G01X325426Y1035028D02*
X321527D01*
X308992Y1040220D01*
X286692D01*
X265682Y1048922D01*
X261750Y1052854D01*
X259184D01*
X253547Y1058491D01*
X249019D01*
X246719Y1056191D01*
X243475D01*
X241157Y1058509D01*
X239006D01*
X238286Y1059229D01*
Y1061331D01*
X237626Y1061991D01*
X235191D01*
X231891Y1058691D01*
X228075D01*
X227355Y1059411D01*
Y1061458D01*
X226635Y1062178D01*
X225355D01*
X224635Y1061458D01*
Y1059411D01*
X223915Y1058691D01*
X221195D01*
X218200Y1061686D01*
X212049D01*
X211329Y1062406D01*
Y1063612D01*
X210609Y1064332D01*
X209329D01*
X208609Y1063612D01*
Y1062406D01*
X207889Y1061686D01*
X205169D01*
X203899Y1062956D01*
X200020D01*
X189979Y1072997D01*
X170041D01*
X163449Y1079589D01*
X159579D01*
X156849Y1082319D01*
X152519D01*
X149319Y1085519D01*
X144180D01*
X141641Y1088058D01*
G01X325425Y1031093D02*
X320775D01*
X308410Y1036216D01*
X282887D01*
X257230Y1046845D01*
X253055Y1051019D01*
X249519D01*
X245503Y1049356D01*
X243752D01*
X241939Y1050107D01*
X237827Y1054219D01*
X234928D01*
X230203Y1052262D01*
X222133D01*
X215110Y1055169D01*
X203193D01*
X202053Y1056309D01*
X200339D01*
X199176Y1055146D01*
X196556D01*
X194333Y1057370D01*
X192364Y1058185D01*
X190310Y1060239D01*
Y1063586D01*
X188718Y1065178D01*
X187082D01*
X185952Y1066308D01*
X184156D01*
X183034Y1065186D01*
X180446D01*
X178130Y1062870D01*
X174439D01*
X171853Y1065456D01*
X169457Y1066449D01*
X164828Y1071077D01*
X152542Y1076166D01*
X147657Y1081051D01*
X145251D01*
X144472Y1080272D01*
X142734D01*
X141641Y1081365D01*
G01X326926Y1046505D02*
X322645D01*
X310780Y1051419D01*
X290976D01*
X277648Y1056940D01*
X261739Y1072849D01*
X259330D01*
X255726Y1076453D01*
X254708D01*
X253800Y1075545D01*
X252782D01*
X251876Y1076451D01*
Y1077469D01*
X252784Y1078377D01*
Y1079395D01*
X251693Y1080486D01*
X240815D01*
X240095Y1079766D01*
Y1078527D01*
X239375Y1077807D01*
X238095D01*
X237375Y1078527D01*
Y1079766D01*
X236655Y1080486D01*
X218816D01*
X215439Y1083863D01*
X213277D01*
X212279Y1084861D01*
X211261D01*
X210502Y1084102D01*
X209484D01*
X208578Y1085008D01*
Y1086026D01*
X209337Y1086785D01*
Y1087803D01*
X207410Y1089730D01*
X196895D01*
X193548Y1093077D01*
X190690D01*
X189303Y1094464D01*
X187970D01*
X186583Y1093077D01*
X182123D01*
X178677Y1096523D01*
X175437D01*
X171441Y1100519D01*
X169596D01*
X167218Y1102897D01*
X161129D01*
X158307Y1105719D01*
X154940D01*
X153463Y1107196D01*
X152474Y1107606D01*
X152084Y1108545D01*
X152361Y1109212D01*
X151971Y1110152D01*
X150788Y1110643D01*
X149848Y1110253D01*
X149571Y1109587D01*
X148631Y1109197D01*
X145863Y1110344D01*
X143848D01*
X141641Y1108137D01*
G01X326926Y1042200D02*
X322617D01*
X310093Y1047387D01*
X289463D01*
X272377Y1054466D01*
X260579Y1066264D01*
X258834D01*
X254879Y1070219D01*
X249641D01*
X246852Y1073008D01*
X241676D01*
X240487Y1071819D01*
X238956D01*
X237767Y1073008D01*
X227362D01*
X226642Y1073728D01*
Y1075781D01*
X225922Y1076501D01*
X224642D01*
X223922Y1075781D01*
Y1073728D01*
X223202Y1073008D01*
X219826D01*
X216501Y1076333D01*
X210901D01*
X204197Y1083037D01*
X202145D01*
X202144Y1083038D01*
X200262D01*
X200261Y1083037D01*
X197280D01*
X193933Y1086384D01*
X191403D01*
X190044Y1087743D01*
X188683D01*
X187324Y1086384D01*
X173402D01*
X168678Y1091108D01*
Y1094639D01*
X167108Y1096209D01*
X161339D01*
X157970Y1099578D01*
X155827D01*
X155107Y1098858D01*
Y1097191D01*
X154387Y1096471D01*
X153107D01*
X152387Y1097191D01*
Y1098858D01*
X151667Y1099578D01*
X150387D01*
X149667Y1098858D01*
Y1097191D01*
X148947Y1096471D01*
X147667D01*
X146947Y1097191D01*
Y1098858D01*
X146227Y1099578D01*
X143507D01*
X141641Y1101444D01*
G01X326926Y1057006D02*
X324394D01*
X283393Y1073986D01*
X264017Y1093362D01*
X257635D01*
X254678Y1096319D01*
X249541D01*
X246091Y1099769D01*
X241267D01*
X240547Y1099049D01*
Y1096165D01*
X239827Y1095445D01*
X238547D01*
X237827Y1096165D01*
Y1099049D01*
X237107Y1099769D01*
X224283D01*
X217880Y1106172D01*
Y1107288D01*
X215358Y1109810D01*
X212278D01*
X211558Y1109090D01*
Y1108096D01*
X210838Y1107376D01*
X209558D01*
X208838Y1108096D01*
Y1109090D01*
X208118Y1109810D01*
X198970D01*
X195624Y1113156D01*
X182828D01*
X178658Y1117326D01*
X170169D01*
X164138Y1123357D01*
X160031D01*
X156491Y1126897D01*
X152319D01*
X151599Y1126177D01*
Y1124852D01*
X150879Y1124132D01*
X149599D01*
X148879Y1124852D01*
Y1126177D01*
X148159Y1126897D01*
X143669D01*
X141641Y1124869D01*
G01X326926Y1051755D02*
X323453D01*
X311520Y1056697D01*
X309232D01*
X279336Y1069083D01*
X266675Y1081744D01*
X258923D01*
X252948Y1087719D01*
X249175D01*
X247533Y1086077D01*
X241881D01*
X241391Y1086567D01*
X239231D01*
X238741Y1086077D01*
X233689D01*
X231210Y1088556D01*
X227318D01*
X226828Y1089046D01*
X224668D01*
X224178Y1088556D01*
X220448D01*
X216286Y1092718D01*
X213217D01*
X207176Y1098759D01*
X203156D01*
X202144Y1099771D01*
X200262D01*
X199165Y1098674D01*
X196619D01*
X193277Y1102016D01*
X187104D01*
X186002Y1103118D01*
X184120D01*
X182974Y1101972D01*
X179919D01*
X173593Y1108298D01*
X170418D01*
X163338Y1115378D01*
X158988D01*
X156579Y1117787D01*
X144868D01*
X144158Y1117077D01*
X142740D01*
X141641Y1118176D01*
G01X326926Y1050535D02*
X323210D01*
X311277Y1055477D01*
X308989D01*
X278644Y1068048D01*
X266169Y1080524D01*
X258417D01*
X252442Y1086499D01*
X249681D01*
X248039Y1084857D01*
X233183D01*
X230704Y1087336D01*
X219942D01*
X215780Y1091498D01*
X212711D01*
X206670Y1097539D01*
X203251D01*
X202136Y1096424D01*
X200163D01*
X199133Y1097454D01*
X196113D01*
X192771Y1100796D01*
X187019D01*
X185994Y1099771D01*
X184021D01*
X183040Y1100752D01*
X179413D01*
X173087Y1107078D01*
X169912D01*
X162832Y1114158D01*
X158482D01*
X156073Y1116567D01*
X145374D01*
X144664Y1115857D01*
X142669D01*
X141641Y1114829D01*
G01X326926Y1061326D02*
X324229D01*
X286544Y1076926D01*
X263174Y1100296D01*
X258081D01*
X255431Y1102946D01*
X249242D01*
X246654Y1105534D01*
X234737D01*
X233452Y1106819D01*
X227366D01*
X224891Y1109294D01*
X221866D01*
X217452Y1113708D01*
Y1115554D01*
X215085Y1117921D01*
X210178D01*
X209548Y1118551D01*
Y1120548D01*
X208918Y1121178D01*
X207448D01*
X206818Y1120548D01*
Y1118551D01*
X206188Y1117921D01*
X204286D01*
X202358Y1119849D01*
X193856D01*
X193078Y1119071D01*
X191130D01*
X187005Y1123196D01*
X174011D01*
X172128Y1125079D01*
X171110D01*
X170125Y1124094D01*
X169107D01*
X168201Y1125000D01*
Y1126018D01*
X169186Y1127003D01*
Y1128021D01*
X167259Y1129948D01*
X160640D01*
X157269Y1133319D01*
X143398D01*
X141641Y1131562D01*
G01X328122Y1066678D02*
X324585D01*
X290604Y1080750D01*
X264595Y1106759D01*
X260144D01*
X257166Y1109737D01*
X250009D01*
X247875Y1111871D01*
Y1113681D01*
X244937Y1116619D01*
X229552D01*
X222278Y1123893D01*
X218224D01*
X215014Y1127103D01*
X213111D01*
X206980Y1133234D01*
X196442D01*
X193094Y1136582D01*
X180765D01*
X180135Y1135952D01*
Y1133832D01*
X179462Y1133159D01*
X178035D01*
X177405Y1133789D01*
Y1135952D01*
X176775Y1136582D01*
X172706D01*
X170279Y1139009D01*
X169389D01*
X167868Y1137488D01*
X166978D01*
X165937Y1138529D01*
Y1139419D01*
X167458Y1140940D01*
Y1141830D01*
X165668Y1143620D01*
X160706D01*
X153687Y1150639D01*
X152669D01*
X148732Y1146702D01*
X147714D01*
X146808Y1147608D01*
Y1148626D01*
X150745Y1152563D01*
Y1153581D01*
X144157Y1160169D01*
Y1172550D01*
X141641Y1175066D01*
G01X328122Y1070727D02*
X325057D01*
X294506Y1083382D01*
X264185Y1113703D01*
X258147D01*
X256028Y1115822D01*
X251356D01*
X246329Y1120849D01*
X235199D01*
X232329Y1123719D01*
X229239D01*
X222522Y1130436D01*
X219250D01*
X215734Y1133952D01*
X213236D01*
X207261Y1139927D01*
X196708D01*
X193361Y1143274D01*
X191790D01*
X190586Y1144478D01*
X189060D01*
X187856Y1143274D01*
X182743D01*
X181539Y1144478D01*
X180013D01*
X178809Y1143274D01*
X177574D01*
X176982Y1142682D01*
X176000D01*
X173667Y1145015D01*
Y1145905D01*
X174605Y1146843D01*
Y1147835D01*
X172071Y1150369D01*
X168314D01*
X167684Y1149739D01*
Y1148480D01*
X167054Y1147850D01*
X165684D01*
X164927Y1148607D01*
Y1150815D01*
X162765Y1152977D01*
X161747Y1152978D01*
X161191Y1152422D01*
X160173D01*
X159267Y1153328D01*
Y1154346D01*
X159823Y1154902D01*
Y1155919D01*
X157896Y1157846D01*
X153546D01*
X150541Y1160851D01*
Y1165178D01*
X151261Y1165898D01*
X152829D01*
X153549Y1166618D01*
Y1167898D01*
X152829Y1168618D01*
X151261D01*
X150541Y1169338D01*
Y1170618D01*
X151261Y1171338D01*
X152829D01*
X153549Y1172058D01*
Y1173338D01*
X152829Y1174058D01*
X151261D01*
X150541Y1174778D01*
Y1177554D01*
X148660Y1179435D01*
X143965D01*
X141641Y1181759D01*
G01X328122Y1076032D02*
X325688D01*
X300296Y1086550D01*
X267252Y1119605D01*
X260175D01*
X253906Y1125874D01*
X249172D01*
X245274Y1129772D01*
X234477D01*
X233017Y1130377D01*
X231799Y1131191D01*
X224904Y1138087D01*
X214630Y1142345D01*
X208109Y1148866D01*
X203110D01*
X202008Y1149968D01*
X200088D01*
X199032Y1148912D01*
X196818D01*
X194954Y1150776D01*
X191487Y1152213D01*
X186812D01*
X185710Y1153315D01*
X184120D01*
X182974Y1152169D01*
X180805D01*
X176738Y1156236D01*
X170411D01*
X164194Y1162453D01*
X162028D01*
X160523Y1163958D01*
Y1182126D01*
X157254Y1185395D01*
X151342Y1187844D01*
X147690Y1191496D01*
X144914D01*
X144146Y1190728D01*
X142711D01*
X141641Y1191798D01*
G01X328122Y1074812D02*
X325445D01*
X299604Y1085515D01*
X298078Y1087042D01*
X297384D01*
X295856Y1088571D01*
X295857Y1089264D01*
X294330Y1090791D01*
X293637D01*
X292109Y1092320D01*
Y1093013D01*
X290582Y1094540D01*
X289889D01*
X288361Y1096069D01*
Y1096762D01*
X286834Y1098289D01*
X286141D01*
X284613Y1099818D01*
X284614Y1100511D01*
X283087Y1102038D01*
X282394D01*
X280866Y1103567D01*
Y1104260D01*
X279339Y1105787D01*
X278646D01*
X277118Y1107316D01*
Y1108009D01*
X275591Y1109536D01*
X274898D01*
X273370Y1111065D01*
X273371Y1111758D01*
X271844Y1113285D01*
X271151D01*
X269623Y1114814D01*
Y1115507D01*
X266746Y1118385D01*
X259669D01*
X257148Y1120906D01*
X256455D01*
X254927Y1122434D01*
Y1123127D01*
X253400Y1124654D01*
X248666D01*
X244768Y1128552D01*
X234234D01*
X232439Y1129295D01*
X231021Y1130243D01*
X228594Y1132670D01*
X227901D01*
X226372Y1134199D01*
Y1134892D01*
X224212Y1137052D01*
X219976Y1138807D01*
X219335Y1138542D01*
X217339Y1139369D01*
X217074Y1140011D01*
X213938Y1141310D01*
X212185Y1143063D01*
X211492Y1143064D01*
X209964Y1144592D01*
Y1145285D01*
X207603Y1147646D01*
X202977D01*
X201952Y1146621D01*
X200163D01*
X199092Y1147692D01*
X196312D01*
X194262Y1149741D01*
X191244Y1150993D01*
X186913D01*
X185888Y1149968D01*
X184021D01*
X183040Y1150949D01*
X180299D01*
X176232Y1155016D01*
X169905D01*
X163688Y1161233D01*
X161522D01*
X159303Y1163452D01*
Y1181620D01*
X156562Y1184360D01*
X150650Y1186809D01*
X147184Y1190276D01*
X145420D01*
X144652Y1189508D01*
X142697D01*
X141641Y1188452D01*
G01X328122Y1085558D02*
X326808D01*
X311605Y1091855D01*
X264592Y1138870D01*
X260168D01*
X253221Y1145817D01*
X247478D01*
X243230Y1150065D01*
X241410D01*
X240159Y1148814D01*
X237594D01*
X236440Y1149968D01*
X230430D01*
X228817Y1151581D01*
Y1152471D01*
X229616Y1153270D01*
Y1154160D01*
X228575Y1155201D01*
X227685D01*
X226886Y1154402D01*
X225996D01*
X224132Y1156266D01*
X220544D01*
X217614Y1159196D01*
Y1162224D01*
X214211Y1165627D01*
X213193D01*
X212352Y1164786D01*
X211334D01*
X210428Y1165692D01*
Y1166710D01*
X211269Y1167551D01*
Y1168569D01*
X209791Y1170047D01*
X199852D01*
X193160Y1176739D01*
X190719D01*
X189999Y1176019D01*
Y1173317D01*
X189279Y1172597D01*
X187999D01*
X187279Y1173317D01*
Y1176019D01*
X186559Y1176739D01*
X181446D01*
X178063Y1180122D01*
Y1189273D01*
X174508Y1192828D01*
X170888D01*
X166141Y1197575D01*
X160069D01*
X157238Y1200406D01*
X153868D01*
X147315Y1206959D01*
X143416D01*
X141641Y1205184D01*
G01X328122Y1081571D02*
X325948D01*
X307144Y1089360D01*
X264935Y1131569D01*
X258689D01*
X249128Y1141130D01*
X241900D01*
X241180Y1140410D01*
Y1138746D01*
X240460Y1138026D01*
X239180D01*
X238460Y1138746D01*
Y1140410D01*
X237740Y1141130D01*
X234800D01*
X232116Y1143814D01*
X229138D01*
X221374Y1151578D01*
X218290D01*
X215231Y1154637D01*
X214213D01*
X213383Y1153808D01*
X212365D01*
X211459Y1154714D01*
Y1155732D01*
X212289Y1156562D01*
Y1157579D01*
X211383Y1158485D01*
X210365D01*
X209535Y1157656D01*
X208517D01*
X207611Y1158562D01*
Y1159580D01*
X208441Y1160410D01*
Y1161427D01*
X206514Y1163354D01*
X191283D01*
X187937Y1166700D01*
X181167D01*
X179832Y1165365D01*
X174739D01*
X169494Y1170610D01*
Y1186049D01*
X165719Y1189824D01*
X151980Y1195515D01*
X147162Y1200333D01*
X143483D01*
X141641Y1198491D01*
G01X383970Y995202D02*
Y994632D01*
X383418Y994080D01*
X346551D01*
X344334Y991863D01*
X321340D01*
X311080Y981603D01*
X300765D01*
X288502Y993866D01*
X270233D01*
X258677Y989080D01*
X256157Y986560D01*
X253951Y985646D01*
X248788D01*
X245596Y988838D01*
X234418D01*
X230549Y984969D01*
X217963D01*
X215258Y982264D01*
X206673Y980099D01*
X204719Y979499D01*
X203339Y978119D01*
Y977249D01*
X202039Y975949D01*
X199719D01*
X189937Y971057D01*
X186505Y969256D01*
X169331D01*
X167382Y967307D01*
X157537Y963230D01*
X155199Y960892D01*
G01X385952Y995202D02*
Y993318D01*
X384695Y992061D01*
X346586D01*
X345067Y990542D01*
X321889D01*
X311629Y980282D01*
X299314D01*
X287772Y991824D01*
X270733D01*
X264951Y989430D01*
X261669Y986148D01*
X254388Y983133D01*
X248053D01*
X244502Y986684D01*
X235238D01*
X231425Y982871D01*
X222309D01*
X220774Y982657D01*
X215249Y979875D01*
X211001Y978641D01*
X203416Y972602D01*
X199819D01*
X194423Y970205D01*
X190929Y969261D01*
X186359Y965909D01*
X183861D01*
X183088Y965136D01*
X176875Y962563D01*
X167416D01*
X166646Y963333D01*
X163451D01*
X159243Y961590D01*
X155199Y957546D01*
G01X388161Y995202D02*
Y992467D01*
X385680Y989986D01*
X346461D01*
X345696Y989221D01*
X322438D01*
X312178Y978961D01*
X297863D01*
X287235Y989589D01*
X271083D01*
X266029Y987496D01*
X262540Y984007D01*
X253560Y980287D01*
X252228Y978955D01*
X249101D01*
X245900Y982156D01*
X241604D01*
X240884Y982876D01*
Y984004D01*
X240164Y984724D01*
X238884D01*
X238164Y984004D01*
Y982876D01*
X237444Y982156D01*
X234724D01*
X233316Y980748D01*
Y977429D01*
X231934Y976047D01*
X227845D01*
X227125Y976767D01*
Y980015D01*
X226405Y980735D01*
X225125D01*
X224405Y980015D01*
Y976767D01*
X223685Y976047D01*
X219436D01*
X218478Y975089D01*
X216664D01*
X215944Y974369D01*
Y973420D01*
X215224Y972700D01*
X213944D01*
X213224Y973420D01*
Y974369D01*
X212504Y975089D01*
X209784D01*
X208035Y973340D01*
Y970248D01*
X206766Y968979D01*
X202424D01*
X202147Y969256D01*
X197332D01*
X193855Y965779D01*
X189786D01*
X184899Y960892D01*
G01X394170Y995202D02*
Y993420D01*
X388427Y987677D01*
X322764D01*
X312727Y977640D01*
X296411D01*
X286861Y987190D01*
X271702D01*
X267981Y985649D01*
X261507Y979175D01*
X254870Y976426D01*
X248134D01*
X244822Y979738D01*
X242701D01*
X241410Y978447D01*
Y977131D01*
X239579Y975300D01*
X237037D01*
X233747Y972010D01*
X228606D01*
X227976Y971380D01*
Y970094D01*
X227346Y969464D01*
X225876D01*
X225246Y970094D01*
Y971380D01*
X224616Y972010D01*
X220346D01*
X216601Y968265D01*
X214499D01*
X212813Y969951D01*
X211923D01*
X207806Y965834D01*
Y964944D01*
X208901Y963849D01*
Y959827D01*
X208304Y959230D01*
X195844D01*
X195337Y959737D01*
Y962119D01*
X194651Y962805D01*
X190158D01*
X184899Y957546D01*
G01X328821Y981486D02*
X323706D01*
X314818Y972598D01*
X293418D01*
X285689Y980327D01*
X272509D01*
X262033Y969851D01*
X258736D01*
X256908Y968023D01*
X254161D01*
X251551Y970633D01*
X247747D01*
X245267Y968153D01*
X239052D01*
X237438Y966539D01*
Y963378D01*
X236172Y962112D01*
X233986D01*
X233261Y962837D01*
X228306D01*
X227262Y961793D01*
X225676D01*
X224632Y962837D01*
X221681D01*
X216025Y960572D01*
X214919D01*
X214599Y960892D01*
G01X328821Y983956D02*
X324306D01*
X314269Y973919D01*
X294870D01*
X285749Y983040D01*
X271743D01*
X261304Y972601D01*
X243036D01*
X240699Y971633D01*
X236109Y968618D01*
X232912Y966519D01*
X231478Y965925D01*
X221323Y964862D01*
X218195Y963791D01*
X215910Y962695D01*
X215633Y962562D01*
X215630Y962565D01*
X213660D01*
X212629Y961534D01*
Y959516D01*
X214599Y957546D01*
G01X328821Y977592D02*
X321714D01*
X315389Y971267D01*
X291977D01*
X285560Y977684D01*
X273447D01*
X260604Y964841D01*
X248248D01*
X244299Y960892D01*
G01X328821Y976160D02*
X322178D01*
X315896Y969878D01*
X290594D01*
X285123Y975349D01*
X274070D01*
X261436Y962715D01*
X249468D01*
X244299Y957546D01*
G01X739699Y1061286D02*
X742013Y1058972D01*
Y1016213D01*
X741077Y1015277D01*
X598333D01*
X593776Y1019834D01*
X572852D01*
X564318Y1018136D01*
X552370Y1013188D01*
X546776D01*
X544487Y1010899D01*
G02X542637I-925J1602D01*
G03X540787I-925J-1602D01*
G02X538937I-925J1602D01*
G01X538899Y1010921D01*
G03X537086Y1010899I-887J-1624D01*
G02X535236I-925J1602D01*
G03X533386I-925J-1602D01*
G02X531536I-925J1602D01*
G03X529686I-925J-1602D01*
G02X527836I-925J1602D01*
G03X525986I-925J-1602D01*
G01X525933Y1010868D01*
G02X524136Y1010899I-871J1633D01*
G03X522286I-925J-1602D01*
G02X520436I-925J1602D01*
G03X518586I-925J-1602D01*
G01X518533Y1010868D01*
G02X516736Y1010899I-871J1633D01*
G03X514886I-925J-1602D01*
G01X514833Y1010868D01*
G02X513036Y1010899I-871J1633D01*
G03X511186I-925J-1602D01*
G01X511148Y1010877D01*
G02X509337Y1010899I-886J1624D01*
G03X507487I-925J-1602D01*
G01X507449Y1010877D01*
G02X505636Y1010899I-887J1624D01*
G03X503786I-925J-1602D01*
G02X501936I-925J1602D01*
G03X500086I-925J-1602D01*
G01X500033Y1010868D01*
G02X498236Y1010899I-871J1633D01*
G03X496386I-925J-1602D01*
G02X494536I-925J1602D01*
G03X492686I-925J-1602D01*
G02X490836I-925J1602D01*
G03X488986I-925J-1602D01*
G01X488933Y1010868D01*
G02X487136Y1010899I-871J1633D01*
G03X485286I-925J-1602D01*
G01X485248Y1010877D01*
G02X483437Y1010899I-886J1624D01*
G03X481546I-945J-1638D01*
G01X478819Y1009325D01*
X478811Y1009297D01*
G01X799099Y810302D02*
X796163Y807366D01*
X791179D01*
X790549Y807996D01*
Y809038D01*
X789919Y809668D01*
X788449D01*
X787819Y809038D01*
Y807996D01*
X787189Y807366D01*
X781876D01*
X780208Y809034D01*
X776734D01*
X775576Y807876D01*
Y806986D01*
X776687Y805875D01*
Y804985D01*
X775646Y803944D01*
X774756D01*
X774181Y804519D01*
X768519D01*
X766396Y806642D01*
X763676D01*
X762319Y805285D01*
X747553D01*
X744208Y808630D01*
X733408D01*
X729258Y812780D01*
X722319D01*
Y812719D01*
X720501Y810901D01*
X715870D01*
X715240Y811531D01*
Y813349D01*
X714610Y813979D01*
X713140D01*
X712510Y813349D01*
Y811531D01*
X711880Y810901D01*
X707644D01*
X706572Y811973D01*
X701969D01*
X698627Y815315D01*
X691495D01*
X690891Y815919D01*
X688721D01*
X684780Y811978D01*
X664653D01*
X663442Y810767D01*
X659023D01*
X657946Y811844D01*
X656293D01*
X655216Y810767D01*
X653563D01*
X652344Y811986D01*
X643787D01*
X642422Y810621D01*
X640956D01*
X638857Y812720D01*
X635521D01*
X634137Y811336D01*
X619907D01*
X603250Y827993D01*
Y829402D01*
X548867Y883785D01*
G01X799099Y840420D02*
X795613Y843906D01*
X792114D01*
X791484Y844536D01*
Y846138D01*
X790854Y846768D01*
X789384D01*
X788754Y846138D01*
Y844536D01*
X788124Y843906D01*
X782706D01*
X780734Y841934D01*
X775529D01*
X774809Y842654D01*
Y846616D01*
X774089Y847336D01*
X772799D01*
X772079Y846616D01*
Y842654D01*
X771359Y841934D01*
X768284D01*
X766697Y843521D01*
X763721D01*
X762295Y842095D01*
X747613D01*
X744271Y845437D01*
X733541D01*
X732711Y844607D01*
X723507D01*
X720819Y841919D01*
X718019D01*
X711139Y848799D01*
X684418D01*
X681098Y852119D01*
X679605D01*
X678650Y851164D01*
X674234D01*
X668364Y845294D01*
X663994D01*
X660419Y841719D01*
X657302D01*
X656582Y842439D01*
Y843881D01*
X655862Y844601D01*
X654572D01*
X653852Y843881D01*
Y842439D01*
X653132Y841719D01*
X648744D01*
X647582Y842881D01*
X644082D01*
X642119Y844844D01*
X634944D01*
X632746Y847042D01*
X627766D01*
X627046Y846322D01*
Y844358D01*
X626326Y843638D01*
X625036D01*
X624316Y844358D01*
Y846322D01*
X623596Y847042D01*
X615046D01*
X557357Y904731D01*
X551423D01*
G01X799099Y833727D02*
X797474Y835402D01*
X792284D01*
X791654Y836032D01*
Y836538D01*
X791024Y837168D01*
X789554D01*
X788924Y836538D01*
Y836032D01*
X788294Y835402D01*
X762819D01*
X762099Y834682D01*
Y833222D01*
X761379Y832502D01*
X760089D01*
X759369Y833222D01*
Y834682D01*
X758649Y835402D01*
X745835D01*
X742489Y838748D01*
X724048D01*
X720619Y835319D01*
X714919D01*
X708143Y842095D01*
X703753D01*
X703123Y841465D01*
Y838798D01*
X702493Y838168D01*
X701023D01*
X700393Y838798D01*
Y841465D01*
X699763Y842095D01*
X694874D01*
X693701Y843268D01*
X692144D01*
X690971Y842095D01*
X685441D01*
X682095Y845441D01*
X674741D01*
X667744Y838444D01*
X664344D01*
X660237Y834337D01*
X657215D01*
X656495Y835057D01*
Y836725D01*
X655775Y837445D01*
X654485D01*
X653765Y836725D01*
Y835057D01*
X653045Y834337D01*
X648701D01*
X646969Y836069D01*
X643469D01*
X641219Y838319D01*
X634719D01*
X633702Y839336D01*
X627853D01*
X627133Y838616D01*
Y836651D01*
X626413Y835931D01*
X625123D01*
X624403Y836651D01*
Y838616D01*
X623683Y839336D01*
X616483D01*
X555055Y900764D01*
X548323D01*
G01X799099Y816995D02*
X797123Y815019D01*
X792156D01*
X791526Y815649D01*
Y817080D01*
X790896Y817710D01*
X789426D01*
X788796Y817080D01*
Y815649D01*
X788166Y815019D01*
X781245D01*
X780004Y816260D01*
X776634D01*
X771793Y811419D01*
X768593D01*
X766519Y813493D01*
X760319D01*
X758804Y811978D01*
X747460D01*
X744114Y815324D01*
X732914D01*
X728136Y820102D01*
X723002D01*
X721219Y818319D01*
X717834D01*
X715857Y820296D01*
X712696D01*
X711067Y818667D01*
X702521Y818668D01*
X701891Y819298D01*
Y821238D01*
X701114Y822015D01*
X691540Y822014D01*
X691035Y822519D01*
X689321D01*
X687217Y820415D01*
X685467D01*
X684747Y821135D01*
Y822835D01*
X684027Y823555D01*
X682897D01*
X682027Y822685D01*
Y819445D01*
X681253Y818671D01*
X673888D01*
X673258Y819301D01*
Y822038D01*
X672628Y822668D01*
X671158D01*
X670528Y822038D01*
Y819301D01*
X669898Y818671D01*
X648067D01*
X646552Y820186D01*
X635087D01*
X633320Y818419D01*
X620223D01*
X550847Y887795D01*
G01X799099Y823688D02*
X798088Y824699D01*
X796526D01*
X795205Y823378D01*
X784727D01*
X778037Y826149D01*
X770843D01*
X764276Y823429D01*
X761890D01*
X758860Y826459D01*
X757623D01*
X756528Y825364D01*
X755160D01*
X754065Y826459D01*
X746482D01*
X743135Y829806D01*
X741495D01*
X740400Y828711D01*
X738994D01*
X737933Y829772D01*
X726740D01*
X720293Y827102D01*
X707709D01*
X705982Y828829D01*
X703244D01*
X698982Y833091D01*
X698157D01*
X697124Y832058D01*
X695748D01*
X694691Y833115D01*
X687124D01*
X683739Y836500D01*
X682079D01*
X680984Y835405D01*
X679614D01*
X678526Y836493D01*
X675773D01*
X668599Y829319D01*
X663237D01*
X660226Y826308D01*
X649003D01*
X646498Y828813D01*
X642322D01*
X641832Y828323D01*
X639682D01*
X639192Y828813D01*
X633154D01*
X631070Y826729D01*
X627505D01*
X627015Y826239D01*
X624865D01*
X624375Y826729D01*
X620451D01*
X614052Y833128D01*
Y834238D01*
X552727Y895563D01*
X548323D01*
G01X799099Y827034D02*
X797984Y825919D01*
X796020D01*
X794699Y824598D01*
X784970D01*
X778280Y827369D01*
X770600D01*
X764033Y824649D01*
X762396D01*
X759366Y827679D01*
X757553D01*
X756528Y828704D01*
X755162D01*
X754137Y827679D01*
X746988D01*
X743641Y831026D01*
X741411D01*
X740386Y832051D01*
X738982D01*
X737923Y830992D01*
X726497D01*
X720050Y828322D01*
X708215D01*
X706488Y830049D01*
X703750D01*
X699488Y834311D01*
X698265D01*
X697178Y835398D01*
X695716D01*
X694653Y834335D01*
X687630D01*
X684245Y837720D01*
X682027D01*
X681002Y838745D01*
X679576D01*
X678544Y837713D01*
X675267D01*
X668093Y830539D01*
X662731D01*
X659720Y827528D01*
X649509D01*
X647004Y830033D01*
X632648D01*
X630564Y827949D01*
X620957D01*
X615272Y833634D01*
Y834744D01*
X553233Y896783D01*
X548323D01*
G01X755841Y873885D02*
X751553Y878173D01*
X745987D01*
X743374Y875560D01*
X724878D01*
X721919Y878519D01*
X714583D01*
X709983Y883119D01*
X708719D01*
X705519Y886319D01*
X700718D01*
X698092Y888945D01*
X686365D01*
X683018Y892292D01*
X674443D01*
X673359Y891208D01*
X670194D01*
X669564Y891838D01*
Y891889D01*
X668934Y892519D01*
X664819D01*
X662445Y890145D01*
X650681D01*
X646304Y885768D01*
X642205D01*
X638688Y882251D01*
X633319D01*
X632020Y883550D01*
X624118D01*
X622819Y882251D01*
X612758D01*
X568083Y926926D01*
X552057D01*
G01X739699Y853806D02*
X738003Y855502D01*
X732634D01*
X731500Y854368D01*
X729904D01*
X728781Y855491D01*
X717547D01*
X712951Y860087D01*
X701406D01*
X699319Y862174D01*
X695682D01*
X694588Y863268D01*
X692952D01*
X691858Y862174D01*
X690222D01*
X689128Y863268D01*
X687492D01*
X686398Y862174D01*
X685522D01*
X682175Y865521D01*
X674445D01*
X673762Y864838D01*
Y862898D01*
X673132Y862268D01*
X671662D01*
X671032Y862898D01*
Y864838D01*
X670402Y865468D01*
X667769D01*
X667069Y866168D01*
X665268D01*
X662963Y863863D01*
Y862973D01*
X664624Y861312D01*
Y860422D01*
X663583Y859381D01*
X662693D01*
X661032Y861042D01*
X660142D01*
X654581Y855481D01*
X641468D01*
X638051Y858898D01*
X614287D01*
X560667Y912518D01*
X551867D01*
G01X739699Y847113D02*
X737189Y849623D01*
X724603D01*
X723349Y848369D01*
X718069D01*
X713319Y853119D01*
X708419D01*
X705719Y855819D01*
X703371D01*
X702741Y855189D01*
Y853585D01*
X702021Y852865D01*
X699996D01*
X697369Y855492D01*
X690923D01*
X689636Y854205D01*
X686509D01*
X681879Y858835D01*
X676561D01*
X672423Y854697D01*
X671405D01*
X669551Y856551D01*
X668533D01*
X667620Y855638D01*
Y854620D01*
X669474Y852766D01*
Y851748D01*
X668241Y850515D01*
X663015D01*
X660819Y848319D01*
X658269D01*
X656769Y849819D01*
X655169D01*
X653669Y848319D01*
X648298D01*
X647398Y849219D01*
X638622D01*
X635053Y852788D01*
X627814D01*
X627094Y852068D01*
Y851575D01*
X626374Y850855D01*
X625084D01*
X624364Y851575D01*
Y852068D01*
X623644Y852788D01*
X614586D01*
X558913Y908461D01*
X551423D01*
G01X739699Y870538D02*
X737438D01*
X735619Y868719D01*
X725319D01*
X721813Y872225D01*
X714705D01*
X711111Y875819D01*
X709419D01*
X705519Y879719D01*
X700919D01*
X698385Y882253D01*
X686686D01*
X683339Y885600D01*
X678600D01*
X677233Y886967D01*
X673478D01*
X672758Y886247D01*
Y884081D01*
X672038Y883361D01*
X670748D01*
X670028Y884081D01*
Y886247D01*
X669308Y886967D01*
X666667D01*
X662519Y882819D01*
X659019D01*
X657154Y880954D01*
X656264D01*
X654255Y882963D01*
X653365D01*
X652324Y881922D01*
Y881032D01*
X654333Y879023D01*
Y878133D01*
X651774Y875574D01*
X651112D01*
X650482Y876204D01*
Y878238D01*
X649852Y878868D01*
X648382D01*
X647752Y878238D01*
Y876277D01*
X647032Y875557D01*
X628556D01*
X627117Y874118D01*
X624275D01*
X622678Y875715D01*
X613331D01*
X566055Y922991D01*
X551424D01*
G01X739699Y860499D02*
X738669Y861529D01*
X736666D01*
X735623Y860486D01*
X723725D01*
X720012Y864199D01*
X708046D01*
X705216Y867029D01*
X703482D01*
X700613Y869898D01*
X698150D01*
X697120Y868868D01*
X695756D01*
X694641Y869983D01*
X688228D01*
X684865Y873346D01*
X682169D01*
X681038Y872215D01*
X679566D01*
X678498Y873283D01*
X668890D01*
X657899Y868730D01*
X650087Y860919D01*
X644643D01*
X639491Y866071D01*
X635271D01*
X633060Y863860D01*
X615418D01*
X562660Y916618D01*
X554500D01*
X553470Y916619D01*
X551423D01*
G01X739699Y863845D02*
X738603Y862749D01*
X736160D01*
X735117Y861706D01*
X724231D01*
X720518Y865419D01*
X708552D01*
X705722Y868249D01*
X703988D01*
X701119Y871118D01*
X698233D01*
X697143Y872208D01*
X695676D01*
X694671Y871203D01*
X688734D01*
X685371Y874566D01*
X682142D01*
X681153Y875555D01*
X679564D01*
X678512Y874503D01*
X668647D01*
X657207Y869765D01*
X654406Y866964D01*
X653713D01*
X652191Y865442D01*
Y864749D01*
X649581Y862139D01*
X645149D01*
X639997Y867291D01*
X634765D01*
X632554Y865080D01*
X626768D01*
X626278Y865570D01*
X624128D01*
X623638Y865080D01*
X615924D01*
X614404Y866600D01*
Y867293D01*
X612883Y868814D01*
X612190D01*
X563166Y917838D01*
X554501D01*
X553471Y917839D01*
X551423D01*
G01X739699Y907349D02*
X737829Y909219D01*
X734411D01*
X731591Y912039D01*
X730573D01*
X729647Y911113D01*
X728629D01*
X727716Y912026D01*
Y913044D01*
X728642Y913970D01*
Y914988D01*
X726936Y916694D01*
X724968D01*
X724247Y917415D01*
Y920705D01*
X723587Y921365D01*
X722567D01*
X721916Y920714D01*
X720898D01*
X720017Y921595D01*
Y922925D01*
X721055Y923963D01*
Y924983D01*
X719669Y926369D01*
X714669D01*
X712619Y928419D01*
X708579D01*
X705976Y931022D01*
X702635D01*
X700715Y929102D01*
X694427D01*
X693040Y927715D01*
X687995D01*
X683261Y932449D01*
X674550D01*
X673473Y931372D01*
X671072D01*
X669625Y932819D01*
X667645D01*
X666198Y931372D01*
X664182D01*
X662735Y932819D01*
X654179D01*
X650149Y928789D01*
X647615D01*
X645085Y931319D01*
X634519D01*
X631168Y927968D01*
X618366D01*
X617736Y928598D01*
Y930038D01*
X617106Y930668D01*
X615636D01*
X615006Y930038D01*
Y928598D01*
X614376Y927968D01*
X612906D01*
X612276Y928598D01*
Y930038D01*
X611646Y930668D01*
X610176D01*
X609546Y930038D01*
Y928598D01*
X608916Y927968D01*
X604365D01*
X583278Y949055D01*
X552924D01*
G01X739699Y890617D02*
X737521D01*
X735728Y892410D01*
X731520D01*
X729543Y894387D01*
X724451D01*
X720741Y898097D01*
X717493D01*
X712019Y903571D01*
Y905819D01*
X711155Y906683D01*
X708183D01*
X707119Y905619D01*
X704219D01*
X700813Y909025D01*
X686413D01*
X683067Y912371D01*
X677771D01*
X676982Y911582D01*
X673794D01*
X672308Y913068D01*
X669534D01*
X668824Y912358D01*
X657448D01*
X654109Y909019D01*
X645032D01*
X643813Y907800D01*
X639442D01*
X638217Y909025D01*
X635649D01*
X635019Y909655D01*
Y912398D01*
X634389Y913028D01*
X632919D01*
X632289Y912398D01*
Y909655D01*
X631659Y909025D01*
X625661D01*
X622316Y912370D01*
X617433D01*
X616713Y913090D01*
Y914235D01*
X615993Y914955D01*
X614703D01*
X613983Y914235D01*
Y913090D01*
X613263Y912370D01*
X611973D01*
X611253Y913090D01*
Y914235D01*
X610533Y914955D01*
X609243D01*
X608523Y914235D01*
Y913090D01*
X607803Y912370D01*
X606513D01*
X605793Y913090D01*
Y914235D01*
X605073Y914955D01*
X603783D01*
X603063Y914235D01*
Y913090D01*
X602343Y912370D01*
X599311D01*
X573110Y938571D01*
X552924D01*
G01X739699Y883924D02*
X739599D01*
X737420Y886103D01*
X732535D01*
X730119Y888519D01*
X723519D01*
X720545Y891493D01*
X715269D01*
X709594Y897168D01*
X705890D01*
X700727Y902331D01*
X694747D01*
X693610Y903468D01*
X692017D01*
X690880Y902331D01*
X686607D01*
X683261Y905677D01*
X677077D01*
X676419Y905019D01*
X673470D01*
X672750Y905739D01*
Y906339D01*
X672030Y907059D01*
X670740D01*
X670020Y906339D01*
Y905739D01*
X669300Y905019D01*
X664465D01*
X663186Y906298D01*
X658279D01*
X656833Y904852D01*
Y903962D01*
X658803Y901992D01*
Y901102D01*
X657762Y900061D01*
X656872D01*
X654902Y902031D01*
X654012D01*
X652113Y900132D01*
X650186D01*
X647148Y903170D01*
X644188D01*
X643558Y902540D01*
Y901598D01*
X642928Y900968D01*
X641458D01*
X640828Y901598D01*
Y902540D01*
X640198Y903170D01*
X638634D01*
X637795Y902331D01*
X626107D01*
X622762Y905676D01*
X615402D01*
X614682Y904956D01*
Y904350D01*
X613962Y903630D01*
X612672D01*
X611952Y904350D01*
Y904956D01*
X611232Y905676D01*
X609942D01*
X609222Y904956D01*
Y904350D01*
X608502Y903630D01*
X607212D01*
X606492Y904350D01*
Y904956D01*
X605772Y905676D01*
X600159D01*
X571289Y934546D01*
X552924D01*
G01Y943885D02*
X578588D01*
X601376Y921097D01*
X629448D01*
X636095Y922419D01*
X637857D01*
X642847Y917429D01*
X646529D01*
X648949Y919849D01*
X662397D01*
X665993Y923445D01*
X678582D01*
X679616Y922411D01*
X680988D01*
X682031Y923454D01*
X683051D01*
X686345Y920160D01*
X694577D01*
X695672Y919065D01*
X697202D01*
X698257Y920120D01*
X700818D01*
X703419Y917519D01*
X706979D01*
X709179Y919719D01*
X712131D01*
X720619Y911231D01*
Y908319D01*
X725409Y903529D01*
X727784D01*
X733556Y897757D01*
X736684D01*
X737324Y898397D01*
X738612D01*
X739699Y897310D01*
G01X552924Y945105D02*
X579094D01*
X601882Y922317D01*
X604180D01*
X604670Y922807D01*
X606820D01*
X607310Y922317D01*
X610055D01*
X610545Y922807D01*
X612695D01*
X613185Y922317D01*
X615946D01*
X616436Y922807D01*
X618586D01*
X619076Y922317D01*
X622969D01*
X623459Y922807D01*
X625609D01*
X626099Y922317D01*
X629327D01*
X635974Y923639D01*
X638363D01*
X643353Y918649D01*
X646023D01*
X648443Y921069D01*
X650922D01*
X651412Y921559D01*
X653562D01*
X654052Y921069D01*
X656611D01*
X657101Y921559D01*
X659251D01*
X659741Y921069D01*
X661891D01*
X665487Y924665D01*
X668018D01*
X668508Y925155D01*
X670658D01*
X671148Y924665D01*
X673298D01*
X673788Y925155D01*
X675938D01*
X676428Y924665D01*
X678498D01*
X679584Y925751D01*
X680999D01*
X682076Y924674D01*
X683557D01*
X686851Y921380D01*
X689155D01*
X689645Y921870D01*
X691795D01*
X692285Y921380D01*
X694673D01*
X695698Y922405D01*
X697119D01*
X698184Y921340D01*
X701324D01*
X703925Y918739D01*
X706473D01*
X708673Y920939D01*
X712637D01*
X714157Y919419D01*
X714850D01*
X716371Y917898D01*
Y917205D01*
X718105Y915471D01*
X718798D01*
X720319Y913950D01*
Y913257D01*
X721839Y911737D01*
Y908825D01*
X725915Y904749D01*
X728290D01*
X729810Y903229D01*
X730503D01*
X732024Y901708D01*
Y901015D01*
X734062Y898977D01*
X736178D01*
X736818Y899617D01*
X738660D01*
X739699Y900656D01*
G01Y914042D02*
X736143Y917598D01*
X734640D01*
X732365Y919873D01*
Y922497D01*
X734367Y924499D01*
Y925497D01*
X732418Y927446D01*
X731528D01*
X730505Y926423D01*
X729615D01*
X728428Y927610D01*
Y928628D01*
X733974Y934174D01*
Y935272D01*
X733101Y936145D01*
X732083D01*
X726497Y930559D01*
X725479D01*
X724284Y931754D01*
Y932772D01*
X725413Y933901D01*
Y934919D01*
X724500Y935832D01*
X723482D01*
X722353Y934703D01*
X721335D01*
X720243Y935795D01*
X689467D01*
X686127Y939135D01*
X677900D01*
X676989Y940046D01*
X665146D01*
X662339Y937239D01*
X651033D01*
X649152Y935358D01*
X615043D01*
X611066Y939335D01*
X599312D01*
X585670Y952977D01*
X552926D01*
X552924Y952975D01*
G01X828799Y967585D02*
X833468Y962916D01*
Y954339D01*
X831668Y952539D01*
X809389D01*
X806033Y949183D01*
X797782D01*
X796428Y947829D01*
X792185D01*
X791465Y948549D01*
Y950757D01*
X790745Y951477D01*
X789455D01*
X788735Y950757D01*
Y948549D01*
X788015Y947829D01*
X781679D01*
X779309Y945459D01*
X775854D01*
X775134Y946179D01*
Y946934D01*
X774414Y947654D01*
X773124D01*
X772404Y946934D01*
Y946179D01*
X771684Y945459D01*
X767199D01*
X765839Y946819D01*
X761339D01*
X758975Y949183D01*
X753255D01*
X749908Y945836D01*
X722117D01*
X720898Y944617D01*
X716631D01*
X715911Y945337D01*
Y947503D01*
X715191Y948223D01*
X713901D01*
X713181Y947503D01*
Y945337D01*
X712461Y944617D01*
X708317D01*
X706039Y942339D01*
X703889D01*
X700392Y945836D01*
X693089D01*
X689743Y949182D01*
X664392D01*
X660529Y945319D01*
X650219D01*
X647369Y948169D01*
X643929D01*
X638254Y942494D01*
X621280D01*
X621279Y942493D01*
X618246D01*
X614888Y945851D01*
X604268D01*
X591275Y958844D01*
X547039D01*
X545779Y960104D01*
X542571D01*
G01X799099Y967585D02*
Y967485D01*
X802969Y963615D01*
Y957920D01*
X800925Y955876D01*
X776786D01*
X773427Y952517D01*
X762063D01*
X758704Y955876D01*
X753636D01*
X750289Y952529D01*
X709449D01*
X705779Y948859D01*
X703839D01*
X700169Y952529D01*
X694741D01*
X691395Y955875D01*
X664055D01*
X660309Y952129D01*
X649999D01*
X647260Y954868D01*
X643804D01*
X637936Y949000D01*
X634588D01*
X632846Y950742D01*
X605181D01*
X593159Y962764D01*
X557220D01*
X553264Y966720D01*
X550205D01*
X548470Y967438D01*
X544310D01*
X542299Y965427D01*
X540045D01*
G01X650499Y960892D02*
X648829Y962562D01*
X639460D01*
X625453Y968364D01*
X621664D01*
X621034Y968606D01*
X616379Y970534D01*
X601455D01*
X597036Y972364D01*
X562590D01*
X553916Y981038D01*
X549097D01*
X547724Y979665D01*
X542036D01*
G01X620799Y960892D02*
X616396D01*
X614789Y962499D01*
Y965343D01*
X614069Y966063D01*
X598032D01*
X595651Y968444D01*
X559836D01*
X553516Y974764D01*
X547623D01*
X547014Y975373D01*
X537521D01*
G01X650499Y957546D02*
X648824Y959221D01*
X636297D01*
X635959Y959361D01*
X628414Y962486D01*
X627518Y963382D01*
X626789Y964063D01*
X617212Y968029D01*
X598903D01*
X596528Y970404D01*
X561041D01*
X554680Y976765D01*
X550654D01*
X550053Y977366D01*
X542093D01*
G01X620799Y957546D02*
X616213D01*
X614579Y959180D01*
X602077D01*
X594773Y966484D01*
X559018D01*
X554762Y970740D01*
X550574D01*
X549473Y971196D01*
X547396D01*
X546766Y971826D01*
Y972535D01*
X546136Y973165D01*
X542070D01*
X540313Y971408D01*
X538600D01*
G01X680299Y957546D02*
X680199D01*
X678930Y958815D01*
X671753D01*
X667807Y962761D01*
X665972D01*
X665371Y962160D01*
X659869D01*
X659149Y961440D01*
Y956379D01*
X658429Y955659D01*
X657139D01*
X656419Y956379D01*
Y961440D01*
X655699Y962160D01*
X655037D01*
X650846Y966351D01*
X649547D01*
X645847Y970051D01*
X643334D01*
X642614Y969331D01*
Y967774D01*
X641894Y967054D01*
X640604D01*
X639884Y967774D01*
Y969331D01*
X639164Y970051D01*
X633347D01*
X630771Y972627D01*
X621254D01*
X616466Y974610D01*
X601904D01*
X598345Y976084D01*
X564725D01*
X554495Y986314D01*
X545897D01*
G01X739699Y1091404D02*
X737614Y1089319D01*
X731912D01*
X729512Y1086919D01*
X724475D01*
X720103Y1082547D01*
X710833D01*
X707855Y1079569D01*
Y1076838D01*
X708575Y1076118D01*
X711028D01*
X711748Y1075398D01*
Y1074108D01*
X711028Y1073388D01*
X708575D01*
X707855Y1072668D01*
Y1070206D01*
X708575Y1069486D01*
X710970D01*
X711690Y1068766D01*
Y1067476D01*
X710970Y1066756D01*
X708575D01*
X707855Y1066036D01*
Y1060377D01*
X705862Y1058384D01*
X703405D01*
X702214Y1059575D01*
X691138D01*
X690569Y1060144D01*
X686744D01*
X684004Y1057404D01*
Y1055766D01*
X684657Y1055113D01*
Y1053837D01*
X683739Y1052919D01*
X673686D01*
X672467Y1054138D01*
X669791D01*
X668051Y1052398D01*
X663044D01*
X659799Y1049153D01*
X655413D01*
X651253Y1053313D01*
X647974D01*
X646320Y1051659D01*
X643552D01*
X642832Y1052379D01*
Y1053334D01*
X642112Y1054054D01*
X640822D01*
X640102Y1053334D01*
Y1052379D01*
X639382Y1051659D01*
X634394D01*
X632289Y1053764D01*
X629031D01*
X624145Y1048878D01*
X619622D01*
X610744Y1040000D01*
X570935D01*
X561276Y1038079D01*
X553526D01*
G01X739699Y1074672D02*
X737246Y1072219D01*
X733018D01*
X728425Y1067626D01*
Y1040584D01*
X727333Y1039492D01*
X724565D01*
X720599Y1035526D01*
X716373D01*
X715653Y1036246D01*
Y1038261D01*
X714933Y1038981D01*
X713643D01*
X712923Y1038261D01*
Y1036246D01*
X712203Y1035526D01*
X708740D01*
X707168Y1037098D01*
X703070D01*
X698816Y1032844D01*
X694572D01*
X691969Y1035447D01*
X686670D01*
X684067Y1032844D01*
X677299D01*
X675933Y1031478D01*
X662541D01*
X661102Y1032917D01*
X656934D01*
X656214Y1032197D01*
Y1031594D01*
X655494Y1030874D01*
X654204D01*
X653484Y1031594D01*
Y1032197D01*
X652764Y1032917D01*
X648424D01*
X647575Y1032068D01*
X643558D01*
X642928Y1032698D01*
Y1034235D01*
X642298Y1034865D01*
X640519D01*
X639889Y1034235D01*
Y1032595D01*
X639259Y1031965D01*
X634421D01*
X633414Y1032972D01*
X619970D01*
X616454Y1029456D01*
X571998D01*
X562948Y1027656D01*
X553026D01*
G01X739699Y1081365D02*
X738705Y1082355D01*
X737082D01*
X736084Y1081357D01*
X732384D01*
X728280Y1077253D01*
X725159D01*
X721222Y1073316D01*
X717713D01*
X716985Y1072588D01*
Y1070272D01*
X717475Y1069782D01*
Y1067632D01*
X716985Y1067142D01*
Y1063524D01*
X717475Y1063034D01*
Y1060884D01*
X716985Y1060394D01*
Y1053934D01*
X714833Y1051782D01*
Y1051089D01*
X713311Y1049567D01*
X712618D01*
X710708Y1047657D01*
X708182D01*
X706182Y1049657D01*
X703492D01*
X701041Y1047206D01*
X698479D01*
X697502Y1046229D01*
X695420D01*
X694325Y1047324D01*
X688575D01*
X685111Y1043860D01*
X682337D01*
X681360Y1042883D01*
X679278D01*
X678266Y1043895D01*
X666901D01*
X659235Y1040720D01*
X649412D01*
X646703Y1043429D01*
X633506D01*
X630611Y1040534D01*
X619583D01*
X613798Y1034749D01*
X571934D01*
X562360Y1032844D01*
X553526D01*
G01X739699Y1084711D02*
X738558Y1083575D01*
X736576D01*
X735578Y1082577D01*
X731878D01*
X727774Y1078473D01*
X724653D01*
X720716Y1074536D01*
X717207D01*
X715765Y1073094D01*
Y1054440D01*
X710202Y1048877D01*
X708688D01*
X706688Y1050877D01*
X702986D01*
X700535Y1048426D01*
X698444D01*
X697300Y1049570D01*
X695442D01*
X694416Y1048544D01*
X688069D01*
X684605Y1045080D01*
X682328D01*
X681184Y1046224D01*
X679397D01*
X678288Y1045115D01*
X666658D01*
X658992Y1041940D01*
X649918D01*
X647209Y1044649D01*
X633000D01*
X630105Y1041754D01*
X619077D01*
X613292Y1035969D01*
X571813D01*
X562239Y1034064D01*
X553526D01*
G01X739699Y1128215D02*
X737664Y1126180D01*
X733537D01*
X732158Y1127559D01*
X730145D01*
X728225Y1125639D01*
X725324D01*
X723833Y1127130D01*
X722991D01*
X722361Y1127760D01*
Y1129338D01*
X721731Y1129968D01*
X720261D01*
X719631Y1129338D01*
Y1127760D01*
X719001Y1127130D01*
X717531D01*
X716901Y1127760D01*
Y1129338D01*
X716271Y1129968D01*
X714801D01*
X714171Y1129338D01*
Y1127760D01*
X713541Y1127130D01*
X713209D01*
X710985Y1129354D01*
X708029D01*
X706812Y1130571D01*
X698924D01*
X698243Y1129890D01*
X689584D01*
X686271Y1126577D01*
Y1125687D01*
X687135Y1124823D01*
Y1123933D01*
X686094Y1122892D01*
X685204D01*
X684340Y1123756D01*
X683450D01*
X682893Y1123199D01*
X679386D01*
X678516Y1122329D01*
Y1117929D01*
X677502Y1116915D01*
Y1116025D01*
X678418Y1115108D01*
Y1114218D01*
X677377Y1113177D01*
X676487D01*
X675571Y1114094D01*
X674681D01*
X672701Y1112114D01*
Y1110398D01*
X671628Y1109325D01*
X669912D01*
X668769Y1108182D01*
X666588D01*
X662305Y1103899D01*
Y1101818D01*
X658997Y1098510D01*
X656751D01*
X656031Y1099230D01*
Y1100205D01*
X655311Y1100925D01*
X654021D01*
X653301Y1100205D01*
Y1099230D01*
X652581Y1098510D01*
X649186D01*
X646862Y1096186D01*
X643630D01*
X642607Y1095163D01*
X640993D01*
X639970Y1096186D01*
X635559D01*
X631298Y1091925D01*
X619507D01*
X591076Y1063494D01*
X569658D01*
X559559Y1061485D01*
X553526D01*
G01X739699Y1111483D02*
X738747Y1110531D01*
X737141D01*
X735793Y1109183D01*
X723483D01*
X720722Y1106422D01*
X707461D01*
X706710Y1107173D01*
X704649D01*
X702884Y1105408D01*
X701866D01*
X700359Y1106915D01*
X699341D01*
X698428Y1106002D01*
Y1104984D01*
X699935Y1103477D01*
Y1102459D01*
X697246Y1099770D01*
X695218D01*
X694364Y1098916D01*
Y1096502D01*
X690640Y1092778D01*
X686839D01*
X685033Y1090972D01*
Y1088127D01*
X684313Y1087407D01*
X682816D01*
X682096Y1086687D01*
Y1085397D01*
X682816Y1084677D01*
X684313D01*
X685033Y1083957D01*
Y1081361D01*
X683367Y1079695D01*
X677350D01*
X676630Y1080415D01*
Y1082184D01*
X675910Y1082904D01*
X674620D01*
X673900Y1082184D01*
Y1080415D01*
X673180Y1079695D01*
X668442D01*
X664859Y1076112D01*
X658663D01*
X657143Y1077632D01*
X653009D01*
X651489Y1076112D01*
X648825D01*
X647873Y1077064D01*
X643589D01*
X642869Y1076344D01*
Y1075217D01*
X642149Y1074497D01*
X640859D01*
X640139Y1075217D01*
Y1076344D01*
X639419Y1077064D01*
X634644D01*
X633243Y1075663D01*
X627468D01*
X626748Y1076383D01*
Y1077297D01*
X626028Y1078017D01*
X624738D01*
X624018Y1077297D01*
Y1076383D01*
X623298Y1075663D01*
X618566D01*
X595923Y1053168D01*
X570797D01*
X560248Y1051070D01*
X553526D01*
G01X739699Y1121522D02*
X738680Y1120503D01*
X737042D01*
X736226Y1119687D01*
X703808D01*
X701446Y1122049D01*
X698438D01*
X697295Y1123192D01*
X695286D01*
X694240Y1122146D01*
X691729D01*
X685593Y1116010D01*
Y1103758D01*
X683806Y1101971D01*
X682296D01*
X681153Y1103114D01*
X679144D01*
X678008Y1101978D01*
X674526D01*
X667864Y1095316D01*
X663294Y1093422D01*
X660999Y1091129D01*
X648101D01*
X645260Y1088288D01*
X636921D01*
X632092Y1086288D01*
X620041D01*
X593281Y1059528D01*
X570154D01*
X559777Y1057463D01*
X553526D01*
G01X739699Y1185105D02*
X737633D01*
X735469Y1182941D01*
X733404D01*
X726882Y1176419D01*
X724016D01*
X720469Y1172872D01*
X717122D01*
X710269Y1166019D01*
X708769D01*
X704889Y1162139D01*
X700440D01*
X698310Y1160009D01*
X686859D01*
X684363Y1157513D01*
Y1156280D01*
X681399Y1153316D01*
X678775D01*
X676672Y1155419D01*
X672863D01*
X672233Y1156049D01*
Y1158438D01*
X671603Y1159068D01*
X670133D01*
X669503Y1158438D01*
Y1156049D01*
X668873Y1155419D01*
X662179D01*
X661227Y1154467D01*
Y1151052D01*
X659159Y1148984D01*
X654923D01*
X653726Y1147787D01*
X649197D01*
X646905Y1145495D01*
X643109D01*
X642389Y1146215D01*
Y1148033D01*
X641669Y1148753D01*
X640379D01*
X639659Y1148033D01*
Y1146215D01*
X638939Y1145495D01*
X632769D01*
X629599Y1142325D01*
X627824D01*
X627104Y1143045D01*
Y1144906D01*
X626384Y1145626D01*
X625094D01*
X624374Y1144906D01*
Y1143045D01*
X623654Y1142325D01*
X619848D01*
X612263Y1134740D01*
Y1104084D01*
X584743Y1076564D01*
X560467D01*
X556551Y1074942D01*
X553526D01*
G01X739699Y1201837D02*
X737882Y1200020D01*
X733069D01*
X730368Y1197319D01*
X725720D01*
X722171Y1193770D01*
X721153D01*
X720511Y1194412D01*
X719494D01*
X718581Y1193499D01*
Y1192481D01*
X719222Y1191839D01*
Y1190821D01*
X718569Y1190168D01*
X715688D01*
X711839Y1186319D01*
X709069D01*
X705486Y1182736D01*
X703786D01*
X701137Y1180087D01*
X694747D01*
X693528Y1178868D01*
X692017D01*
X690798Y1180087D01*
X687573D01*
X684227Y1176741D01*
X677341D01*
X676719Y1176119D01*
X673209D01*
X672579Y1176749D01*
Y1178138D01*
X671949Y1178768D01*
X670479D01*
X669849Y1178138D01*
Y1176749D01*
X669219Y1176119D01*
X664319D01*
X661419Y1173219D01*
X658843D01*
X657394Y1171770D01*
X655772D01*
X654652Y1170650D01*
Y1169028D01*
X652325Y1166701D01*
X648187D01*
X646953Y1167935D01*
X645457D01*
X644582Y1167060D01*
X642852D01*
X639035Y1163243D01*
X634820D01*
X631323Y1159746D01*
X627372D01*
X626742Y1160376D01*
Y1161319D01*
X626112Y1161949D01*
X624642D01*
X624012Y1161319D01*
Y1160376D01*
X623382Y1159746D01*
X618640D01*
X601983Y1143089D01*
Y1108351D01*
X580481Y1086844D01*
X558416D01*
X554891Y1085384D01*
X552003D01*
X551197Y1084578D01*
G01X739699Y1191798D02*
X738646Y1192851D01*
X737229D01*
X735911Y1191533D01*
X730184D01*
X722140Y1183489D01*
X717976D01*
X711776Y1177289D01*
X708214D01*
X701937Y1171012D01*
X698465D01*
X697502Y1170049D01*
X695420D01*
X694325Y1171144D01*
X688391D01*
X684927Y1167680D01*
X682337D01*
X681360Y1166703D01*
X679278D01*
X678176Y1167805D01*
X664585D01*
X660284Y1163504D01*
X658771D01*
X652856Y1157589D01*
X647801D01*
X646671Y1156459D01*
X644997D01*
X643723Y1157733D01*
X641444D01*
X640256Y1156544D01*
X632524Y1153338D01*
X620204D01*
X607123Y1140257D01*
Y1106215D01*
X582612Y1081704D01*
X559440D01*
X555853Y1080218D01*
X553526D01*
G01X799099Y1221916D02*
X797029Y1219846D01*
X792265D01*
X791545Y1220566D01*
Y1221977D01*
X790825Y1222697D01*
X789535D01*
X788815Y1221977D01*
Y1220566D01*
X788095Y1219846D01*
X784159D01*
X783737Y1220268D01*
X777436D01*
X774068Y1216900D01*
X768198D01*
X767568Y1217530D01*
Y1219177D01*
X766938Y1219807D01*
X765468D01*
X764838Y1219177D01*
Y1217530D01*
X764208Y1216900D01*
X762378D01*
X761748Y1217530D01*
Y1218482D01*
X761118Y1219112D01*
X759648D01*
X759018Y1218482D01*
Y1217530D01*
X758388Y1216900D01*
X747460D01*
X744114Y1220246D01*
X724596D01*
X720469Y1216119D01*
X717469D01*
X710569Y1209219D01*
X708569D01*
X705569Y1206219D01*
X701975D01*
X699269Y1203513D01*
X685866D01*
X682519Y1206860D01*
X677260D01*
X676519Y1206119D01*
X673411D01*
X672729Y1206801D01*
Y1208604D01*
X672122Y1209211D01*
X670304D01*
X669624Y1208531D01*
Y1207018D01*
X668725Y1206119D01*
X664119D01*
X660991Y1202991D01*
X658507D01*
X657648Y1202132D01*
X656758D01*
X656412Y1202478D01*
X655522D01*
X654481Y1201437D01*
Y1200547D01*
X654827Y1200201D01*
Y1199311D01*
X651170Y1195654D01*
X650280D01*
X649690Y1196244D01*
X648800D01*
X647759Y1195203D01*
Y1194313D01*
X648349Y1193723D01*
Y1192833D01*
X646406Y1190890D01*
X641662D01*
X640663Y1191889D01*
X639773D01*
X638732Y1190848D01*
Y1189958D01*
X639731Y1188959D01*
Y1188069D01*
X638442Y1186780D01*
X636127D01*
X634587Y1188320D01*
Y1189210D01*
X635268Y1189892D01*
Y1190782D01*
X634227Y1191823D01*
X633337D01*
X632656Y1191141D01*
X631766D01*
X630375Y1192532D01*
X625746D01*
X624696Y1191482D01*
Y1186225D01*
X621899Y1183428D01*
X620179D01*
X588463Y1151712D01*
Y1113952D01*
X574875Y1100364D01*
X555720D01*
X553655Y1099508D01*
X553217D01*
G01X799099Y1228609D02*
X798071Y1229637D01*
X796171D01*
X794415Y1227881D01*
X783307D01*
X780656Y1230532D01*
X775469D01*
X773288Y1228351D01*
X762798D01*
X759768Y1231381D01*
X757631D01*
X756536Y1230286D01*
X755156D01*
X754061Y1231381D01*
X746082D01*
X742779Y1234684D01*
X741471D01*
X740412Y1233625D01*
X738961D01*
X737908Y1234678D01*
X733155D01*
X726396Y1227919D01*
X718370D01*
X711580Y1221129D01*
X708668D01*
X702159Y1214620D01*
X698207D01*
X697140Y1213553D01*
X695720D01*
X694692Y1214581D01*
X686638D01*
X683247Y1217972D01*
X682102D01*
X681030Y1216900D01*
X679564D01*
X678573Y1217891D01*
X664995D01*
X648018Y1206545D01*
X642685Y1201212D01*
X638848D01*
X637804Y1200168D01*
X636330D01*
X635231Y1201267D01*
X627105D01*
X623782Y1204590D01*
X622762D01*
X621696Y1203524D01*
X620085D01*
X619103Y1204506D01*
X617668D01*
X614285Y1201123D01*
Y1184916D01*
X583323Y1153954D01*
Y1116083D01*
X572787Y1105547D01*
X552627D01*
G01X815241Y813648D02*
X811497Y817392D01*
X807224D01*
X801810Y811978D01*
X796760D01*
X795804Y812934D01*
X793708D01*
X792408Y811634D01*
X786808D01*
X785608Y812834D01*
X783234D01*
X781519Y811119D01*
X775019D01*
X772532Y808632D01*
X747807D01*
X744462Y811977D01*
X736861D01*
X736019Y812819D01*
X732420D01*
X730120Y815119D01*
X721219D01*
X720319Y816019D01*
X707906D01*
X706201Y814314D01*
X703518D01*
X699177Y818655D01*
X692255D01*
X691824Y818224D01*
X688226D01*
X685326Y815324D01*
X659668D01*
X658226Y813882D01*
X653937D01*
X651743Y816076D01*
X648276D01*
X647092Y814892D01*
X643800D01*
X642884Y815808D01*
Y817434D01*
X642108Y818210D01*
X640556D01*
X639925Y817579D01*
Y815857D01*
X638960Y814892D01*
X634745D01*
X633818Y815819D01*
X619016D01*
X605479Y829356D01*
Y830029D01*
X546541Y888967D01*
G01X815241Y806955D02*
X810913Y811283D01*
X808933D01*
X802935Y805285D01*
X792185D01*
X791465Y804565D01*
Y803123D01*
X790745Y802403D01*
X789455D01*
X788735Y803123D01*
Y804565D01*
X788015Y805285D01*
X782457D01*
X779111Y801939D01*
X754955D01*
X754075Y802819D01*
X747019D01*
X740619Y805285D01*
X733853D01*
X730511Y808627D01*
X704111D01*
X703046Y809692D01*
X700700D01*
X698407Y811985D01*
X694174D01*
X692765Y810576D01*
X688297D01*
X686352Y808631D01*
X634206D01*
X633510Y809327D01*
X618318D01*
X601006Y826639D01*
Y828813D01*
X554189Y875630D01*
X553399D01*
X552381Y875631D01*
X551361Y876651D01*
Y877441D01*
X551362Y878457D01*
X549434Y880385D01*
X547548D01*
X546507Y881426D01*
G01X815241Y820341D02*
X814143Y821439D01*
X811872D01*
X810399Y822912D01*
X807239D01*
X804093Y819766D01*
X800935D01*
X799840Y818671D01*
X798266D01*
X797168Y819769D01*
X785004D01*
X778896Y822299D01*
X776618D01*
X771548Y817229D01*
X769219D01*
X765776Y818655D01*
X762382D01*
X760147Y816420D01*
X757661D01*
X756566Y815325D01*
X755156D01*
X754054Y816427D01*
X747184D01*
X743845Y819766D01*
X741485D01*
X740390Y818671D01*
X738942D01*
X737878Y819735D01*
X735599D01*
X728769Y822564D01*
X703386D01*
X699489Y826461D01*
X698254D01*
X697158Y825365D01*
X695714D01*
X694702Y826377D01*
X687773D01*
X684343Y829807D01*
X682099D01*
X681004Y828712D01*
X679588D01*
X678521Y829779D01*
X675345D01*
X667895Y822329D01*
X620144D01*
X610599Y831874D01*
Y832685D01*
X550948Y892336D01*
X548323D01*
G01X815241Y837074D02*
X813566Y838749D01*
X805807D01*
X805087Y839469D01*
Y841584D01*
X804367Y842304D01*
X803077D01*
X802357Y841584D01*
Y839469D01*
X801637Y838749D01*
X792369D01*
X791739Y839379D01*
Y841338D01*
X791109Y841968D01*
X789639D01*
X789009Y841338D01*
Y839379D01*
X788379Y838749D01*
X747489D01*
X744143Y842095D01*
X723895D01*
X721719Y839919D01*
X717195D01*
X715261Y841853D01*
X714371D01*
X713211Y840693D01*
X712321D01*
X711280Y841734D01*
Y842624D01*
X712440Y843784D01*
Y844674D01*
X711495Y845619D01*
X707519D01*
X706438Y844538D01*
X699207D01*
X698303Y845442D01*
X684925D01*
X681588Y848779D01*
X674707D01*
X668447Y842519D01*
X664418D01*
X661418Y839519D01*
X647719D01*
X646719Y838519D01*
X644519D01*
X640819Y842219D01*
X635419D01*
X634772Y841572D01*
X617160D01*
X555976Y902756D01*
X550001D01*
X548808Y903949D01*
G01X815241Y830381D02*
X810628Y834994D01*
X805045D01*
X802107Y832056D01*
X791901D01*
X791271Y831426D01*
Y830398D01*
X790641Y829768D01*
X789171D01*
X788541Y830398D01*
Y831426D01*
X787911Y832056D01*
X768147D01*
X765483Y829392D01*
X760346D01*
X757681Y832057D01*
X750881D01*
X750019Y832919D01*
X745219D01*
X742735Y835403D01*
X724203D01*
X721689Y832889D01*
X708525D01*
X705246Y836168D01*
X700126D01*
X697544Y838750D01*
X685989D01*
X682643Y842096D01*
X674296D01*
X668319Y836119D01*
X665487D01*
X661419Y832051D01*
X657360D01*
X656640Y831331D01*
Y830212D01*
X655920Y829492D01*
X654630D01*
X653910Y830212D01*
Y831331D01*
X653190Y832051D01*
X643777D01*
X639908Y835920D01*
X635320D01*
X633354Y833954D01*
X627607D01*
X626887Y833234D01*
Y830690D01*
X626167Y829970D01*
X624877D01*
X624157Y830690D01*
Y833234D01*
X623437Y833954D01*
X618889D01*
X554078Y898765D01*
X548323D01*
G01X815241Y823688D02*
X814212Y822659D01*
X812378D01*
X810905Y824132D01*
X806733D01*
X803587Y820986D01*
X800863D01*
X799838Y822011D01*
X798244D01*
X797222Y820989D01*
X785247D01*
X779139Y823519D01*
X776112D01*
X771042Y818449D01*
X769462D01*
X766019Y819875D01*
X761876D01*
X759641Y817640D01*
X757601D01*
X756576Y818665D01*
X755108D01*
X754090Y817647D01*
X747690D01*
X744351Y820986D01*
X741427D01*
X740402Y822011D01*
X738946D01*
X737890Y820955D01*
X735842D01*
X729012Y823784D01*
X709172D01*
X708682Y824274D01*
X706532D01*
X706042Y823784D01*
X703892D01*
X699995Y827681D01*
X698176D01*
X697152Y828705D01*
X695736D01*
X694628Y827597D01*
X688279D01*
X684849Y831027D01*
X682005D01*
X680980Y832052D01*
X679622D01*
X678569Y830999D01*
X674839D01*
X671991Y828151D01*
X671298D01*
X669776Y826629D01*
Y825936D01*
X667389Y823549D01*
X664102D01*
X663612Y824039D01*
X661462D01*
X660972Y823549D01*
X658822D01*
X658332Y824039D01*
X656182D01*
X655692Y823549D01*
X653542D01*
X653052Y824039D01*
X650902D01*
X650412Y823549D01*
X648262D01*
X647772Y824039D01*
X645622D01*
X645132Y823549D01*
X642982D01*
X642492Y824039D01*
X640342D01*
X639852Y823549D01*
X637702D01*
X637212Y824039D01*
X635062D01*
X634572Y823549D01*
X632422D01*
X631932Y824039D01*
X629782D01*
X629292Y823549D01*
X625930D01*
X625440Y824039D01*
X623290D01*
X622800Y823549D01*
X620650D01*
X611819Y832380D01*
Y833191D01*
X551454Y893556D01*
X548323D01*
G01X755841Y867192D02*
X750820Y872213D01*
X739021D01*
X737685Y873549D01*
X732567D01*
X731847Y872829D01*
Y871535D01*
X731127Y870815D01*
X729837D01*
X729117Y871535D01*
Y872829D01*
X728397Y873549D01*
X723539D01*
X720819Y876269D01*
X713521D01*
X711871Y877919D01*
X710119D01*
X706219Y881819D01*
X702082D01*
X698303Y885598D01*
X686140D01*
X682793Y888945D01*
X665045D01*
X661029Y884929D01*
X657031D01*
X656311Y885649D01*
Y887350D01*
X655591Y888070D01*
X654301D01*
X653581Y887350D01*
Y885649D01*
X652861Y884929D01*
X649631D01*
X643607Y878905D01*
X635005D01*
X633919Y877819D01*
X627664D01*
X627034Y878449D01*
Y879585D01*
X626303Y880316D01*
X624933D01*
X624262Y879645D01*
Y878449D01*
X623632Y877819D01*
X614077D01*
X566938Y924958D01*
X552057D01*
G01X755841Y850459D02*
X752475D01*
X744107Y858827D01*
X737530D01*
X736582Y857879D01*
X722659D01*
X718386Y862152D01*
X703986D01*
X700622Y865516D01*
X686422D01*
X683066Y868872D01*
X664772D01*
X659711Y863811D01*
X658693D01*
X657738Y864766D01*
X656720D01*
X655807Y863853D01*
Y862835D01*
X656762Y861880D01*
Y860862D01*
X654819Y858919D01*
X642519D01*
X640519Y860919D01*
X634821D01*
X633917Y861823D01*
X632191D01*
X631287Y860919D01*
X615372D01*
X562025Y914266D01*
G03X561376Y914535I-649J-648D01*
G01X551867D01*
G01X755841Y843766D02*
X753404Y846203D01*
X751642D01*
X741419Y852134D01*
X723716D01*
X720630Y853319D01*
X716819D01*
X713819Y855219D01*
X709119D01*
X706219Y858119D01*
X699342D01*
X698636Y858825D01*
X691673D01*
X690973Y859525D01*
X685196D01*
X682536Y862185D01*
X678230D01*
X677593Y861548D01*
X664079Y857452D01*
X659785Y853158D01*
X649430D01*
X648191Y851919D01*
X642163D01*
X637814Y856268D01*
X635468D01*
X633959Y854759D01*
X628003D01*
X627283Y855479D01*
Y856206D01*
X626563Y856926D01*
X625273D01*
X624553Y856206D01*
Y855479D01*
X623833Y854759D01*
X615452D01*
X559653Y910558D01*
X551867D01*
G01X739699Y877231D02*
X737917Y879013D01*
X724325D01*
X720919Y882419D01*
X713991D01*
X711191Y885219D01*
X709419D01*
X706019Y888619D01*
X701530D01*
X697857Y892292D01*
X687646D01*
X684299Y895639D01*
X664539D01*
X661034Y892134D01*
X649685D01*
X645619Y888068D01*
X640968D01*
X638498Y885598D01*
X635188D01*
X634558Y886228D01*
Y892038D01*
X633928Y892668D01*
X632458D01*
X631828Y892038D01*
Y886228D01*
X631198Y885598D01*
X627371D01*
X627370Y885599D01*
X627074D01*
X626444Y886229D01*
Y892438D01*
X625814Y893068D01*
X624344D01*
X623714Y892438D01*
Y886229D01*
X623084Y885599D01*
X621280D01*
X621279Y885598D01*
X612295D01*
X568985Y928908D01*
X552057D01*
G01X755841Y860499D02*
X754965Y859623D01*
X751683D01*
X751417Y859733D01*
X743940Y867210D01*
X742774Y867701D01*
X741714D01*
X740560Y868855D01*
X738752D01*
X736650Y866753D01*
X724900D01*
X723998Y867127D01*
X721692Y869433D01*
X719932Y870162D01*
X712500D01*
X707703Y873368D01*
X703820Y874977D01*
X701583Y877214D01*
X700075Y877839D01*
X698211D01*
X697149Y878901D01*
X695750D01*
X694731Y877882D01*
X688805D01*
X687135Y878572D01*
X685401Y880306D01*
X683177Y881231D01*
X682129D01*
X681113Y882247D01*
X679616D01*
X678516Y881147D01*
X665274D01*
X664826Y880962D01*
X664377Y880776D01*
X660629Y877028D01*
X657129D01*
X652183Y872082D01*
X650133D01*
X646906Y873419D01*
X634220D01*
X632854Y872053D01*
X614204D01*
X565234Y921023D01*
X551424D01*
G01X755841Y857152D02*
X755753D01*
X754502Y858403D01*
X751440D01*
X750726Y858698D01*
X749206Y860218D01*
X748513D01*
X746992Y861739D01*
Y862432D01*
X743246Y866178D01*
X742527Y866481D01*
X741719D01*
X740760Y865522D01*
X738678D01*
X738667Y865533D01*
X730651D01*
X730161Y865043D01*
X728011D01*
X727521Y865533D01*
X724657D01*
X723306Y866092D01*
X721000Y868398D01*
X719689Y868942D01*
X712129D01*
X707125Y872286D01*
X705295Y873044D01*
X703128Y873942D01*
X700891Y876179D01*
X699831Y876619D01*
X698200D01*
X697142Y875561D01*
X695756D01*
X694655Y876662D01*
X688562D01*
X686444Y877537D01*
X684711Y879270D01*
X682933Y880011D01*
X682094D01*
X680990Y878907D01*
X679618D01*
X678598Y879927D01*
X676077D01*
X675587Y879437D01*
X673437D01*
X672947Y879927D01*
X670797D01*
X670307Y879437D01*
X668157D01*
X667667Y879927D01*
X665517D01*
X665068Y879741D01*
X661135Y875808D01*
X657635D01*
X652689Y870862D01*
X649890D01*
X646663Y872199D01*
X642114D01*
X641624Y871709D01*
X639474D01*
X638984Y872199D01*
X634726D01*
X633360Y870833D01*
X630974D01*
X630484Y870343D01*
X628334D01*
X627844Y870833D01*
X623982D01*
X623492Y870343D01*
X621342D01*
X620852Y870833D01*
X618702D01*
X618212Y870343D01*
X616062D01*
X615572Y870833D01*
X613698D01*
X612178Y872353D01*
X611485D01*
X609964Y873874D01*
Y874567D01*
X608444Y876087D01*
X607751D01*
X606230Y877608D01*
Y878301D01*
X604710Y879821D01*
X604017D01*
X602496Y881342D01*
Y882035D01*
X600976Y883555D01*
X600283D01*
X598762Y885076D01*
Y885769D01*
X564728Y919803D01*
X551424D01*
G01X755841Y904003D02*
X753603D01*
X751932Y902332D01*
X736819D01*
X735432Y903719D01*
X733219D01*
X731558Y905380D01*
Y906270D01*
X732618Y907330D01*
Y908220D01*
X731577Y909261D01*
X730687D01*
X729627Y908201D01*
X728737D01*
X724219Y912719D01*
Y914393D01*
X718493Y920119D01*
X718119D01*
X712485Y925753D01*
X687072D01*
X683721Y929104D01*
X675481D01*
X674296Y927919D01*
X671502D01*
X670082Y929339D01*
X663741D01*
X660456Y926054D01*
X658098D01*
X657378Y926774D01*
Y928414D01*
X656658Y929134D01*
X655368D01*
X654648Y928414D01*
Y926774D01*
X653928Y926054D01*
X649654D01*
X648419Y924819D01*
X642973D01*
X638473Y929319D01*
X635319D01*
X631919Y925919D01*
X621280D01*
X621279Y925918D01*
X602653D01*
X581493Y947078D01*
X552924D01*
G01X755841Y887270D02*
X754181Y885610D01*
X747706D01*
X744371Y888945D01*
X733873D01*
X732399Y890419D01*
X730667D01*
X728667Y892419D01*
X723590D01*
X719890Y896119D01*
X713625D01*
X712622Y897122D01*
Y898140D01*
X713116Y898634D01*
Y899652D01*
X712203Y900565D01*
X711185D01*
X710691Y900071D01*
X709673D01*
X706122Y903622D01*
X702575D01*
X700519Y905678D01*
X693807D01*
X692456Y907029D01*
X691077D01*
X689726Y905678D01*
X686364D01*
X683018Y909024D01*
X657715D01*
X655440Y906749D01*
X649719D01*
X648153Y905183D01*
X644545D01*
X644050Y905678D01*
X634651D01*
X633295Y907034D01*
X631921D01*
X630565Y905678D01*
X626160D01*
X624060Y907778D01*
Y907838D01*
X622876Y909022D01*
X619836D01*
X618874Y908060D01*
X614184D01*
X613464Y908780D01*
Y909638D01*
X612744Y910358D01*
X611454D01*
X610734Y909638D01*
Y908780D01*
X610014Y908060D01*
X608724D01*
X608004Y908780D01*
Y909638D01*
X607284Y910358D01*
X605994D01*
X605274Y909638D01*
Y908780D01*
X604554Y908060D01*
X600653D01*
X572132Y936581D01*
X552924D01*
G01X755841Y880577D02*
X754165Y882253D01*
X733285D01*
X729219Y886319D01*
X722819D01*
X720119Y889019D01*
X711067D01*
X701100Y898986D01*
X686353D01*
X683007Y902332D01*
X678306D01*
X677819Y902819D01*
X673518D01*
X672798Y902099D01*
Y899829D01*
X672078Y899109D01*
X670788D01*
X670068Y899829D01*
Y902099D01*
X669348Y902819D01*
X663807D01*
X658992Y898004D01*
X642614D01*
X641632Y898986D01*
X633124D01*
X632404Y898266D01*
Y896599D01*
X631684Y895879D01*
X630394D01*
X629674Y896599D01*
Y898266D01*
X628954Y898986D01*
X626265D01*
X622920Y902331D01*
X619397D01*
X618664Y901598D01*
X600733D01*
X570262Y932069D01*
X552057D01*
G01X755841Y897310D02*
X754777Y896246D01*
X754305D01*
X752500Y896991D01*
X748100D01*
X745283Y895716D01*
X742356Y894504D01*
X741682D01*
X740553Y895633D01*
X732852D01*
X730736Y897749D01*
X728763D01*
X724758Y899405D01*
X722224Y901939D01*
X718410D01*
X717022Y903327D01*
Y907893D01*
X714943Y909972D01*
Y910665D01*
X713422Y912186D01*
X712729D01*
X710752Y914163D01*
X708364D01*
X706450Y912249D01*
X703682D01*
X701272Y914659D01*
X698188D01*
X697135Y915712D01*
X695754D01*
X694729Y914687D01*
X691718D01*
X691228Y915177D01*
X689078D01*
X688588Y914687D01*
X686438D01*
X683107Y918018D01*
X682050D01*
X681009Y919059D01*
X679616D01*
X678560Y918003D01*
X675137D01*
X674647Y918493D01*
X672497D01*
X672007Y918003D01*
X669857D01*
X669367Y918493D01*
X667217D01*
X666727Y918003D01*
X664577D01*
X662231Y915657D01*
X657391D01*
X656901Y916147D01*
X654751D01*
X654261Y915657D01*
X651984D01*
X649809Y914754D01*
X647363Y912309D01*
X642981D01*
X641451Y913839D01*
Y914532D01*
X639930Y916053D01*
X639237D01*
X637717Y917573D01*
X632142D01*
X630167Y915598D01*
X628439D01*
X625989Y918048D01*
X622612D01*
X621596Y919064D01*
X620108D01*
X619213Y918169D01*
X614288D01*
X613798Y918659D01*
X611648D01*
X611158Y918169D01*
X609008D01*
X608518Y918659D01*
X606368D01*
X605878Y918169D01*
X600360D01*
X598840Y919689D01*
Y920382D01*
X597319Y921903D01*
X596626D01*
X595106Y923423D01*
Y924116D01*
X593585Y925637D01*
X592892D01*
X591372Y927157D01*
Y927850D01*
X589851Y929371D01*
X589158D01*
X576614Y941915D01*
X552924D01*
G01X755841Y893963D02*
X754778Y895026D01*
X754062D01*
X752257Y895771D01*
X748364D01*
X745768Y894596D01*
X742599Y893284D01*
X741751D01*
X740760Y892293D01*
X738678D01*
X736558Y894413D01*
X732346D01*
X730230Y896529D01*
X728520D01*
X724067Y898370D01*
X721718Y900719D01*
X717904D01*
X715802Y902821D01*
Y907387D01*
X710246Y912943D01*
X708870D01*
X706956Y911029D01*
X703176D01*
X700766Y913439D01*
X698193D01*
X697126Y912372D01*
X695750D01*
X694655Y913467D01*
X685932D01*
X682601Y916798D01*
X682073D01*
X680994Y915719D01*
X679614D01*
X678550Y916783D01*
X665083D01*
X662737Y914437D01*
X652228D01*
X650501Y913720D01*
X647869Y911089D01*
X642475D01*
X637211Y916353D01*
X632648D01*
X630673Y914378D01*
X627933D01*
X625483Y916828D01*
X622701D01*
X621592Y915719D01*
X620195D01*
X618965Y916949D01*
X599854D01*
X576108Y940695D01*
X552924D01*
G01X755841Y910696D02*
X752196D01*
X750521Y912371D01*
X745529D01*
X744809Y911651D01*
Y910365D01*
X744089Y909645D01*
X742799D01*
X742079Y910365D01*
Y911651D01*
X741359Y912371D01*
X734067D01*
X731419Y915019D01*
Y917905D01*
X720556Y928768D01*
X716170D01*
X711819Y933119D01*
X699846D01*
X699162Y932435D01*
X686647D01*
X683289Y935793D01*
X678130D01*
X677156Y934819D01*
X673455D01*
X672735Y935539D01*
Y937227D01*
X672015Y937947D01*
X670725D01*
X670005Y937227D01*
Y935539D01*
X669285Y934819D01*
X651813D01*
X650313Y933319D01*
X628172D01*
X627542Y932689D01*
Y930598D01*
X626912Y929968D01*
X625442D01*
X624812Y930598D01*
Y932689D01*
X624182Y933319D01*
X602349D01*
X584653Y951015D01*
X552924D01*
G01X844941Y964239D02*
X842026Y961324D01*
Y951889D01*
X839317Y949180D01*
X812830D01*
X809486Y945836D01*
X782886D01*
X780189Y943139D01*
X776823D01*
X776103Y942419D01*
Y939577D01*
X775383Y938857D01*
X774093D01*
X773373Y939577D01*
Y942419D01*
X772653Y943139D01*
X767679D01*
X766669Y942129D01*
X762439D01*
X758732Y945836D01*
X754526D01*
X751180Y942490D01*
X709000D01*
X706830Y940320D01*
X702826D01*
X700646Y942500D01*
X695586D01*
X694420Y943666D01*
X691826D01*
X689656Y945836D01*
X664296D01*
X661481Y943021D01*
X647711D01*
X643821Y939131D01*
X616547D01*
X612426Y943252D01*
X603837D01*
X590392Y956697D01*
X542177D01*
G01X815241Y964239D02*
X807033Y956031D01*
X805369D01*
X801867Y952529D01*
X796259D01*
X795259Y953529D01*
X787511D01*
X786511Y952529D01*
X780549D01*
X777659Y949639D01*
X767239D01*
X766609Y949009D01*
X762659D01*
X759139Y952529D01*
X753519D01*
X750173Y949183D01*
X720322D01*
X719040Y950465D01*
X710345D01*
X706646Y946766D01*
X702972D01*
X700555Y949183D01*
X693841D01*
X690495Y952529D01*
X663959D01*
X661261Y949831D01*
X649303D01*
X646543Y952591D01*
X644649D01*
X638756Y946698D01*
X633858D01*
X631698Y944538D01*
X619972D01*
X616492Y948018D01*
X604969D01*
X592183Y960804D01*
X554397D01*
X551045Y964156D01*
X549247D01*
X546829Y963155D01*
X540955D01*
X540593Y962793D01*
G01X709899Y960892D02*
X707692Y963099D01*
X703689D01*
X700873Y965915D01*
X686923D01*
X683577Y969261D01*
X677497D01*
X676709Y970049D01*
X671059D01*
X669087Y972021D01*
X663929D01*
X660399Y975551D01*
X649917D01*
X646453Y979015D01*
X644480D01*
X643887Y979608D01*
X639438D01*
X638759Y978929D01*
X634343D01*
X631186Y982086D01*
X614382D01*
X611929Y984539D01*
X585523D01*
X582359Y981375D01*
X570386D01*
X561435Y990326D01*
X513784D01*
X510106Y994004D01*
Y996900D01*
G01X680299Y960892D02*
X678156D01*
X676139Y962909D01*
X670909D01*
X669091Y964727D01*
X664452D01*
X663088Y966091D01*
X659168D01*
X658448Y966811D01*
Y969298D01*
X657728Y970018D01*
X656438D01*
X655718Y969298D01*
Y966811D01*
X654998Y966091D01*
X654095D01*
X651537Y968649D01*
X650149D01*
X646449Y972349D01*
X643490D01*
X642770Y973069D01*
Y974286D01*
X642050Y975006D01*
X640760D01*
X640040Y974286D01*
Y973069D01*
X639320Y972349D01*
X633837D01*
X631145Y975041D01*
X627612D01*
X626892Y975761D01*
Y977254D01*
X626172Y977974D01*
X624882D01*
X624162Y977254D01*
Y975761D01*
X623442Y975041D01*
X620953D01*
X619179Y976815D01*
X612052D01*
X610789Y978078D01*
X609423D01*
X609408Y978063D01*
X608203D01*
X607483Y978783D01*
Y979843D01*
X606763Y980563D01*
X605473D01*
X604753Y979843D01*
Y978783D01*
X604033Y978063D01*
X602743D01*
X602023Y978783D01*
Y979843D01*
X601303Y980563D01*
X600013D01*
X599293Y979843D01*
Y978783D01*
X598573Y978063D01*
X597283D01*
X596563Y978783D01*
Y979843D01*
X595843Y980563D01*
X594553D01*
X593833Y979843D01*
Y978783D01*
X593113Y978063D01*
X591823D01*
X591103Y978783D01*
Y979843D01*
X590383Y980563D01*
X589093D01*
X588373Y979843D01*
Y978783D01*
X587653Y978063D01*
X566832D01*
X557209Y987686D01*
X512074D01*
X506306Y993454D01*
Y999429D01*
X506561Y999684D01*
G01X709899Y957546D02*
X709086Y958359D01*
X705655D01*
X700558Y960470D01*
X698460Y962568D01*
X695804D01*
X695755Y962519D01*
X689699D01*
X689649Y962569D01*
X687917D01*
X683304Y964480D01*
X681869Y965915D01*
X674450D01*
X670216Y967668D01*
X667174Y969701D01*
X663185D01*
X659545Y973341D01*
X649113D01*
X645485Y976969D01*
X632997D01*
X630018Y979948D01*
X612571D01*
X609988Y982531D01*
X587275D01*
X584579Y979835D01*
X568091D01*
X558920Y989006D01*
X513204D01*
X508036Y994174D01*
Y996900D01*
G01X739699Y960892D02*
X736402Y964189D01*
X733303D01*
X722239Y975253D01*
X708339D01*
X707343Y976249D01*
X702669D01*
X699618Y979300D01*
X668705D01*
X668384Y978979D01*
X665295D01*
X662239Y982035D01*
X655445D01*
X650535Y986945D01*
X648193D01*
X646983Y985735D01*
X643440D01*
X642810Y986365D01*
Y989737D01*
X642180Y990367D01*
X640529D01*
X639899Y989737D01*
Y986416D01*
X639218Y985735D01*
X636099D01*
X633301Y988533D01*
X627239D01*
X626609Y989163D01*
Y990589D01*
X625979Y991219D01*
X624234D01*
X623604Y990589D01*
Y989163D01*
X622974Y988533D01*
X618836D01*
X618364Y989005D01*
Y990637D01*
X617734Y991267D01*
X614278D01*
X612849Y992696D01*
X590465D01*
X580386Y1002775D01*
X573908D01*
X570672Y1002132D01*
X568011Y1001029D01*
X562364Y995382D01*
X518515D01*
X516736Y997161D01*
Y998759D01*
X517661Y999684D01*
G01X739699Y957546D02*
X735102D01*
X730072Y962576D01*
X724484D01*
X723179Y963881D01*
Y965709D01*
X722107Y966781D01*
X715666D01*
X715166Y967281D01*
Y970114D01*
X714536Y970744D01*
X713166D01*
X711668Y969246D01*
X706062D01*
X703914Y971394D01*
X702896D01*
X701138Y969636D01*
X700120D01*
X699207Y970549D01*
Y971567D01*
X700965Y973325D01*
Y974343D01*
X699354Y975954D01*
X665282D01*
X661499Y979737D01*
X651983D01*
X648283Y983437D01*
X635147D01*
X632350Y986234D01*
X615937D01*
X613712Y988459D01*
X591504D01*
X578858Y1001105D01*
X574117D01*
X570999Y1000483D01*
X569136Y999713D01*
X563485Y994062D01*
X516476D01*
X513962Y996576D01*
Y999684D01*
G01X769399Y957546D02*
X765372D01*
X757003Y965915D01*
X747933D01*
X744587Y969261D01*
X733637D01*
X726690Y976208D01*
X717450Y980035D01*
X708659D01*
X707413Y978789D01*
X703549D01*
X699691Y982647D01*
X665517D01*
X661774Y986390D01*
X657890D01*
X650945Y993335D01*
X615126D01*
X611486Y996975D01*
X589477D01*
X581741Y1004711D01*
X574309D01*
X570370Y1003928D01*
X566989Y1002527D01*
X561287Y996825D01*
X536471D01*
G01X739699Y1067979D02*
X737800Y1066080D01*
X733880D01*
X732444Y1064644D01*
Y1059764D01*
X733164Y1059044D01*
X735040D01*
X735760Y1058324D01*
Y1057034D01*
X735040Y1056314D01*
X733164D01*
X732444Y1055594D01*
Y1053184D01*
X733164Y1052464D01*
X734941D01*
X735661Y1051744D01*
Y1050454D01*
X734941Y1049734D01*
X733164D01*
X732444Y1049014D01*
Y1034205D01*
X730686Y1032447D01*
X724919D01*
X721399Y1028927D01*
X707839D01*
X706319Y1030447D01*
X703070D01*
X698774Y1026151D01*
X693773D01*
X690069Y1022447D01*
X685773D01*
X682069Y1026151D01*
X647723D01*
X645646Y1024074D01*
X633213D01*
X630584Y1026703D01*
X627745D01*
X627025Y1025983D01*
Y1024357D01*
X626305Y1023637D01*
X625015D01*
X624295Y1024357D01*
Y1025983D01*
X623575Y1026703D01*
X620692D01*
X619500Y1025511D01*
X595526D01*
X595523Y1025514D01*
X572283D01*
X562926Y1023653D01*
X550025D01*
G01X755676Y1071326D02*
Y1071192D01*
X754139Y1069655D01*
X746520D01*
X745800Y1068935D01*
Y1067256D01*
X745080Y1066536D01*
X743790D01*
X743070Y1067256D01*
Y1068935D01*
X742350Y1069655D01*
X733356D01*
X730437Y1066736D01*
Y1039414D01*
X728321Y1037298D01*
X725571D01*
X721720Y1033447D01*
X716760D01*
X716040Y1032727D01*
Y1031636D01*
X715320Y1030916D01*
X714030D01*
X713310Y1031636D01*
Y1032727D01*
X712590Y1033447D01*
X708219D01*
X707419Y1032647D01*
X702411D01*
X699261Y1029497D01*
X694519D01*
X690869Y1033147D01*
X688052D01*
X684401Y1029496D01*
X683299Y1029497D01*
X662694D01*
X662105Y1028908D01*
X648574D01*
X647472Y1030010D01*
X643910D01*
X643280Y1029380D01*
Y1027432D01*
X642568Y1026720D01*
X641198D01*
X640298Y1027620D01*
Y1029313D01*
X639668Y1029943D01*
X631429D01*
X630525Y1029039D01*
X620256D01*
X618691Y1027474D01*
X572086D01*
X563035Y1025674D01*
X553025D01*
G01X755741Y1064633D02*
X754070Y1062962D01*
X738457D01*
X737737Y1062242D01*
Y1033484D01*
X734700Y1030447D01*
X725919D01*
X722219Y1026747D01*
X708565D01*
X701268Y1019450D01*
X684473D01*
X681119Y1022804D01*
X668626D01*
X667483Y1021661D01*
X597300D01*
X595407Y1023554D01*
X572481D01*
X563210Y1021710D01*
X563169Y1021693D01*
X550025D01*
G01X739699Y1098097D02*
Y1097117D01*
X738353Y1095771D01*
X724880D01*
X723595Y1094486D01*
Y1091867D01*
X722623Y1090895D01*
X708356D01*
X700740Y1083279D01*
Y1080233D01*
X700110Y1079603D01*
X699000D01*
X698370Y1078973D01*
Y1077503D01*
X699000Y1076873D01*
X700110D01*
X700740Y1076243D01*
Y1074773D01*
X700110Y1074143D01*
X699000D01*
X698370Y1073513D01*
Y1072043D01*
X699000Y1071413D01*
X700110D01*
X700740Y1070783D01*
Y1068092D01*
X698954Y1066306D01*
X686017D01*
X682674Y1062963D01*
X678787D01*
X678067Y1063683D01*
Y1065548D01*
X677347Y1066268D01*
X676057D01*
X675337Y1065548D01*
Y1063683D01*
X674617Y1062963D01*
X673325D01*
X669969Y1059607D01*
X663648D01*
X662928Y1060327D01*
Y1061723D01*
X662208Y1062443D01*
X660918D01*
X660198Y1061723D01*
Y1060327D01*
X659478Y1059607D01*
X655417D01*
X654697Y1060327D01*
Y1062858D01*
X653977Y1063578D01*
X652687D01*
X651967Y1062858D01*
Y1060327D01*
X651247Y1059607D01*
X631753D01*
X631074Y1060286D01*
Y1062238D01*
X630444Y1062868D01*
X628974D01*
X628344Y1062238D01*
Y1060286D01*
X627714Y1059656D01*
X627508D01*
X623897Y1056045D01*
X620487D01*
X608505Y1044063D01*
X571168D01*
X560865Y1042014D01*
X553526D01*
G01X755841Y1094751D02*
X754164Y1093074D01*
X747752D01*
X747032Y1092354D01*
Y1090300D01*
X746312Y1089580D01*
X745022D01*
X744302Y1090300D01*
Y1092354D01*
X743582Y1093074D01*
X737063D01*
X736466Y1093671D01*
X734341D01*
X725825Y1089092D01*
X723490D01*
X719430Y1085032D01*
X716644D01*
X715924Y1085752D01*
Y1088154D01*
X715204Y1088874D01*
X713914D01*
X713194Y1088154D01*
Y1085752D01*
X712474Y1085032D01*
X708056D01*
X702804Y1079780D01*
Y1073334D01*
X703524Y1072614D01*
X705109D01*
X705829Y1071894D01*
Y1070604D01*
X705109Y1069884D01*
X703524D01*
X702804Y1069164D01*
Y1064847D01*
X700919Y1062962D01*
X693236D01*
X692385Y1062111D01*
X685932D01*
X685864Y1062043D01*
X681519Y1059616D01*
X678480D01*
X675289Y1056425D01*
X664416D01*
X662756Y1054765D01*
X655891D01*
X655189Y1055467D01*
X648575D01*
X647081Y1056961D01*
X644101D01*
X643408Y1056268D01*
X627278D01*
X624409Y1053399D01*
X620613D01*
X609278Y1042064D01*
X571261D01*
X561115Y1040046D01*
X553526D01*
G01X755841Y1088058D02*
X754089D01*
X753335Y1087304D01*
Y1085287D01*
X752667Y1084619D01*
X750429D01*
X749709Y1083899D01*
Y1081481D01*
X748989Y1080761D01*
X747699D01*
X746979Y1081481D01*
Y1083899D01*
X746259Y1084619D01*
X744282D01*
X742518Y1086383D01*
X732276D01*
X726360Y1080467D01*
X716570D01*
X713788Y1077685D01*
Y1058494D01*
X711568Y1056274D01*
X687466D01*
X686746Y1055554D01*
Y1050678D01*
X685644Y1049576D01*
X678428D01*
X677685Y1050319D01*
X663922D01*
X659958Y1046355D01*
X649679D01*
X646380Y1049654D01*
X631638D01*
X628831Y1046847D01*
X620445D01*
X611631Y1038033D01*
X571708D01*
X561929Y1036088D01*
X553526D01*
G01X739699Y1104790D02*
X737723Y1102814D01*
X724014D01*
X720719Y1099519D01*
X706947D01*
X706151Y1100315D01*
X704313D01*
X701698Y1097700D01*
Y1093731D01*
X697694Y1089727D01*
X694799D01*
X691705Y1086633D01*
X689954D01*
X689324Y1086003D01*
Y1084533D01*
X689954Y1083903D01*
X691705D01*
X692335Y1083273D01*
Y1081803D01*
X691705Y1081173D01*
X690088D01*
X689458Y1080543D01*
Y1079073D01*
X690088Y1078443D01*
X691705D01*
X692335Y1077813D01*
Y1075453D01*
X689884Y1073002D01*
X686550D01*
X685316Y1071768D01*
X683820D01*
X682586Y1073002D01*
X677564D01*
X676330Y1071768D01*
X674834D01*
X673600Y1073002D01*
X672198D01*
X669442Y1070246D01*
X665970D01*
X665226Y1069502D01*
X647812D01*
X647215Y1070099D01*
X643574D01*
X642854Y1069379D01*
Y1066694D01*
X642134Y1065974D01*
X640844D01*
X640124Y1066694D01*
Y1069379D01*
X639404Y1070099D01*
X633328D01*
X631653Y1068424D01*
X624089D01*
X623061Y1069452D01*
X618554D01*
X598287Y1049185D01*
X570872D01*
X560458Y1047114D01*
X553526D01*
G01X755841Y1101444D02*
X753316Y1098919D01*
X751799D01*
X751169Y1099549D01*
Y1102919D01*
X750469Y1103619D01*
X746440D01*
X745669Y1102848D01*
Y1100619D01*
X744823Y1099773D01*
X739009D01*
X738063Y1100719D01*
X725019D01*
X721447Y1097147D01*
X707849D01*
X703384Y1092682D01*
Y1091901D01*
X697873Y1086390D01*
X695317D01*
X694398Y1085471D01*
Y1071074D01*
X692973Y1069649D01*
X672488D01*
X668533Y1065694D01*
X661317D01*
X660040Y1066971D01*
X649441D01*
X646360Y1063890D01*
X634157D01*
X631682Y1066365D01*
X618467D01*
X599285Y1047183D01*
X570856D01*
X560583Y1045140D01*
X553526D01*
G01X755841Y1081365D02*
X754819Y1080343D01*
X753211D01*
X749226Y1076358D01*
X748067D01*
X742538Y1078649D01*
X741593D01*
X740554Y1079688D01*
X738543D01*
X737609Y1078754D01*
X735482D01*
X732110Y1077352D01*
X728971Y1074215D01*
X724705Y1071929D01*
X723253Y1069505D01*
X722993Y1069070D01*
Y1061533D01*
X722503Y1061043D01*
Y1058893D01*
X722993Y1058403D01*
Y1056253D01*
X722503Y1055763D01*
Y1053613D01*
X722993Y1053123D01*
Y1050973D01*
X722503Y1050483D01*
Y1048333D01*
X722993Y1047843D01*
Y1046273D01*
X719119Y1042399D01*
X715844D01*
X715354Y1042889D01*
X713204D01*
X712714Y1042399D01*
X708174D01*
X706196Y1044377D01*
X703828D01*
X701364Y1041913D01*
X698466D01*
X697502Y1042877D01*
X695644D01*
X695614Y1042847D01*
X695518D01*
X694442Y1041771D01*
X688044D01*
X684660Y1038387D01*
X682379D01*
X681235Y1039531D01*
X679302D01*
X678329Y1038558D01*
X672420D01*
X671930Y1039048D01*
X669780D01*
X669290Y1038558D01*
X662911D01*
X660490Y1036137D01*
X655987D01*
X655497Y1036627D01*
X653347D01*
X652857Y1036137D01*
X648986D01*
X646603Y1038520D01*
X644453D01*
X643963Y1039010D01*
X641813D01*
X641323Y1038520D01*
X639173D01*
X638683Y1039010D01*
X636533D01*
X636043Y1038520D01*
X633458D01*
X631134Y1036196D01*
X626639D01*
X626149Y1036686D01*
X623999D01*
X623509Y1036196D01*
X618460D01*
X614912Y1032648D01*
X571480D01*
X562487Y1030859D01*
X554726D01*
G01X755841Y1078018D02*
X754736Y1079123D01*
X753717D01*
X749732Y1075138D01*
X747824D01*
X742295Y1077429D01*
X741572D01*
X740495Y1076352D01*
X738675D01*
X737493Y1077534D01*
X735726D01*
X732802Y1076317D01*
X729707Y1073224D01*
X725579Y1071012D01*
X724676Y1069505D01*
X724213Y1068732D01*
Y1045767D01*
X719625Y1041179D01*
X707668D01*
X705690Y1043157D01*
X704334D01*
X701870Y1040693D01*
X698659D01*
X697502Y1039536D01*
X695420D01*
X694405Y1040551D01*
X688550D01*
X685166Y1037167D01*
X682337D01*
X681360Y1036190D01*
X679278D01*
X678130Y1037338D01*
X663417D01*
X660996Y1034917D01*
X648480D01*
X646097Y1037300D01*
X633964D01*
X631640Y1034976D01*
X618966D01*
X615418Y1031428D01*
X571601D01*
X562608Y1029639D01*
X554726D01*
G01X739699Y1134908D02*
X737719Y1132928D01*
X725010D01*
X721365Y1136573D01*
X688100D01*
X681424Y1129897D01*
X672529D01*
X670863Y1128231D01*
Y1118544D01*
X668218Y1115899D01*
X663708D01*
X654211Y1106402D01*
X649843D01*
X646212Y1102771D01*
X642993D01*
X642273Y1103491D01*
Y1106691D01*
X641553Y1107411D01*
X640263D01*
X639543Y1106691D01*
Y1103491D01*
X638823Y1102771D01*
X634744D01*
X631240Y1099267D01*
X627810D01*
X627090Y1099987D01*
Y1103492D01*
X626370Y1104212D01*
X625080D01*
X624360Y1103492D01*
Y1099987D01*
X623640Y1099267D01*
X620177D01*
X588474Y1067564D01*
X568960D01*
X558350Y1065454D01*
X553526D01*
G01X755841Y1131562D02*
X754479Y1131168D01*
X750065Y1129891D01*
X724946D01*
X720818Y1134019D01*
X716364D01*
X715734Y1133389D01*
Y1132832D01*
X715104Y1132202D01*
X713634D01*
X713004Y1132832D01*
Y1133389D01*
X712374Y1134019D01*
X707985D01*
X706552Y1132586D01*
X698309D01*
X697652Y1133243D01*
X687626D01*
X684693Y1130310D01*
Y1129158D01*
X682072Y1126537D01*
X675728D01*
X673344Y1124153D01*
Y1117459D01*
X669535Y1113650D01*
X665677D01*
X662620Y1110593D01*
Y1107036D01*
X659841Y1104257D01*
X650863D01*
X647021Y1100415D01*
X643179D01*
X642116Y1099352D01*
X640549D01*
X639486Y1100415D01*
X636147D01*
X632339Y1096607D01*
X627741D01*
X627021Y1095887D01*
Y1094608D01*
X626301Y1093888D01*
X625011D01*
X624291Y1094608D01*
Y1095887D01*
X623571Y1096607D01*
X620289D01*
X589272Y1065590D01*
X570119D01*
X559500Y1063478D01*
X553526D01*
G01X755841Y1124869D02*
X753152Y1127558D01*
X748255D01*
X743895Y1123198D01*
X736141D01*
X735191Y1124148D01*
X733162D01*
X731544Y1122530D01*
X729683D01*
X728565Y1123648D01*
X725114D01*
X724428Y1122962D01*
X714336D01*
X710755Y1126543D01*
X707021D01*
X706301Y1125823D01*
Y1124042D01*
X705581Y1123322D01*
X704291D01*
X703571Y1124042D01*
Y1125823D01*
X702851Y1126543D01*
X693242D01*
X683350Y1116651D01*
Y1111339D01*
X681826Y1109815D01*
X678369D01*
X675985Y1107431D01*
X672829D01*
X671187Y1105789D01*
Y1104771D01*
X672329Y1103629D01*
Y1102611D01*
X671416Y1101698D01*
X670398D01*
X669256Y1102840D01*
X668238D01*
X661887Y1096489D01*
X649963D01*
X646674Y1093200D01*
X635446D01*
X632202Y1089956D01*
X620378D01*
X591917Y1061495D01*
X569813D01*
X559450Y1059434D01*
X553526D01*
G01X755676Y1108137D02*
X755675Y1108136D01*
X751329D01*
X750969Y1107776D01*
Y1106619D01*
X750269Y1105919D01*
X747224D01*
X746504Y1106639D01*
Y1109062D01*
X745784Y1109782D01*
X744494D01*
X743774Y1109062D01*
Y1106639D01*
X743054Y1105919D01*
X741368D01*
X740821Y1106466D01*
X737472D01*
X736919Y1107019D01*
X732885D01*
X732165Y1106299D01*
Y1105601D01*
X731445Y1104881D01*
X730155D01*
X729435Y1105601D01*
Y1106299D01*
X728715Y1107019D01*
X724855D01*
X721955Y1104119D01*
X716341D01*
X715621Y1103399D01*
Y1102257D01*
X714901Y1101537D01*
X713611D01*
X712891Y1102257D01*
Y1103399D01*
X712171Y1104119D01*
X708361D01*
X706717Y1102475D01*
X703436D01*
X699576Y1098615D01*
Y1094808D01*
X697852Y1093084D01*
X694274D01*
X691588Y1090398D01*
X688100D01*
X687148Y1089446D01*
Y1079676D01*
X683820Y1076348D01*
X678836D01*
X677865Y1077319D01*
X673193D01*
X668107Y1072233D01*
X662120D01*
X660892Y1073461D01*
X649667D01*
X648740Y1072534D01*
X634959D01*
X634057Y1073436D01*
X619446D01*
X597218Y1051208D01*
X570993D01*
X560385Y1049098D01*
X553526D01*
G01X739699Y1118176D02*
X738592Y1119283D01*
X737548D01*
X736732Y1118467D01*
X734582D01*
X734092Y1117977D01*
X731942D01*
X731452Y1118467D01*
X729302D01*
X728812Y1117977D01*
X726662D01*
X726172Y1118467D01*
X724022D01*
X723532Y1117977D01*
X721382D01*
X720892Y1118467D01*
X718742D01*
X718252Y1117977D01*
X716102D01*
X715612Y1118467D01*
X713462D01*
X712972Y1117977D01*
X710822D01*
X710332Y1118467D01*
X703302D01*
X700940Y1120829D01*
X698479D01*
X697502Y1119852D01*
X695420D01*
X694346Y1120926D01*
X692235D01*
X686813Y1115504D01*
Y1113139D01*
X687303Y1112649D01*
Y1110499D01*
X686813Y1110009D01*
Y1103252D01*
X684312Y1100751D01*
X682337D01*
X681360Y1099774D01*
X679278D01*
X678294Y1100758D01*
X675032D01*
X673258Y1098984D01*
Y1098291D01*
X671736Y1096769D01*
X671044D01*
X668556Y1094281D01*
X663985Y1092387D01*
X661505Y1089909D01*
X658809D01*
X658319Y1089419D01*
X656169D01*
X655679Y1089909D01*
X648607D01*
X645766Y1087068D01*
X642783D01*
X642293Y1086578D01*
X640143D01*
X639653Y1087068D01*
X637164D01*
X632335Y1085068D01*
X625872D01*
X625382Y1084578D01*
X623232D01*
X622742Y1085068D01*
X620547D01*
X593787Y1058308D01*
X570275D01*
X559898Y1056243D01*
X553526D01*
G01X755841Y1118176D02*
X754750Y1117085D01*
X751452D01*
X749688Y1118849D01*
X746682D01*
X743189Y1115356D01*
X741696D01*
X740557Y1116495D01*
X738806D01*
X737666Y1115355D01*
X723856D01*
X720940Y1112439D01*
X716636D01*
X716146Y1112929D01*
X713996D01*
X713506Y1112439D01*
X709207D01*
X707272Y1114374D01*
X703820D01*
X701455Y1112009D01*
X698438D01*
X697295Y1113152D01*
X695286D01*
X694351Y1112217D01*
X692842D01*
X691628Y1111003D01*
Y1106726D01*
X691138Y1106236D01*
Y1104086D01*
X691628Y1103596D01*
Y1101261D01*
X687968Y1097601D01*
X685706D01*
X683574Y1095469D01*
X682104D01*
X681153Y1096420D01*
X679144D01*
X678209Y1095485D01*
X675406D01*
X672491Y1092570D01*
Y1088819D01*
X670922Y1087250D01*
X670229D01*
X668707Y1085728D01*
Y1085035D01*
X665676Y1082004D01*
X663970Y1081297D01*
X661820D01*
X661330Y1081787D01*
X659180D01*
X658690Y1081297D01*
X655599D01*
X655109Y1081787D01*
X652959D01*
X652469Y1081297D01*
X650319D01*
X649829Y1081787D01*
X647679D01*
X647189Y1081297D01*
X640866D01*
X640376Y1081787D01*
X638226D01*
X637736Y1081297D01*
X633130D01*
X632640Y1081787D01*
X630490D01*
X630000Y1081297D01*
X626527D01*
X626037Y1081787D01*
X623887D01*
X623397Y1081297D01*
X619550D01*
X594601Y1056348D01*
X570477D01*
X559966Y1054257D01*
X553526D01*
G01X755841Y1114829D02*
X754805Y1115865D01*
X750946D01*
X749182Y1117629D01*
X747188D01*
X743695Y1114136D01*
X741737D01*
X740760Y1113159D01*
X738742D01*
X737766Y1114135D01*
X724362D01*
X721446Y1111219D01*
X708701D01*
X706766Y1113154D01*
X704326D01*
X701961Y1110789D01*
X698479D01*
X697502Y1109812D01*
X695420D01*
X694235Y1110997D01*
X693348D01*
X692848Y1110497D01*
Y1100755D01*
X688474Y1096381D01*
X686212D01*
X684080Y1094249D01*
X682281D01*
X681112Y1093080D01*
X679278D01*
X678093Y1094265D01*
X675912D01*
X673711Y1092064D01*
Y1088313D01*
X666368Y1080969D01*
X664438Y1080170D01*
X664345Y1080077D01*
X620056D01*
X595107Y1055128D01*
X570598D01*
X560087Y1053037D01*
X553526D01*
G01X755841Y1198491D02*
X754170Y1196820D01*
X745724D01*
X745094Y1197450D01*
Y1199538D01*
X744464Y1200168D01*
X742994D01*
X742364Y1199538D01*
Y1197450D01*
X741734Y1196820D01*
X736141D01*
X735691Y1197270D01*
X733969D01*
X731928Y1195229D01*
X728669D01*
X720208Y1186768D01*
X715708D01*
X712509Y1183569D01*
X709119D01*
X706219Y1180669D01*
X704819D01*
X700892Y1176742D01*
X687383D01*
X684037Y1173396D01*
X676442D01*
X675996Y1173842D01*
X673033D01*
X672403Y1173212D01*
Y1172098D01*
X671773Y1171468D01*
X670303D01*
X669673Y1172098D01*
Y1173212D01*
X669043Y1173842D01*
X665142D01*
X661854Y1170554D01*
X658953D01*
X651751Y1163352D01*
X642528D01*
X639297Y1160121D01*
X635382D01*
X632881Y1157620D01*
X619286D01*
X603943Y1142277D01*
Y1107538D01*
X581293Y1084884D01*
X558807D01*
X555248Y1083410D01*
X553526D01*
G01X739699Y1178412D02*
X737440D01*
X735569Y1176541D01*
X733157D01*
X729569Y1172953D01*
Y1170819D01*
X727469Y1168719D01*
X722269D01*
X719269Y1165719D01*
X717269D01*
X707369Y1155819D01*
X704557D01*
X702951Y1154213D01*
X701933D01*
X700507Y1155639D01*
X699489D01*
X698576Y1154726D01*
Y1153708D01*
X700002Y1152282D01*
Y1151264D01*
X698708Y1149970D01*
X693470D01*
X692839Y1150601D01*
Y1153269D01*
X691899Y1154209D01*
X689359D01*
X681763Y1146613D01*
X673416D01*
X672696Y1147333D01*
Y1150372D01*
X671976Y1151092D01*
X670686D01*
X669966Y1150372D01*
Y1147333D01*
X669246Y1146613D01*
X664583D01*
X660789Y1142819D01*
X655219D01*
X652868Y1140468D01*
X648814D01*
X648170Y1139824D01*
X634215D01*
X630485Y1136094D01*
X620265D01*
X616183Y1132012D01*
Y1102459D01*
X586368Y1072644D01*
X561251D01*
X557236Y1070981D01*
X553526D01*
G01X755676Y1181759D02*
X754000Y1183435D01*
X746526D01*
X745896Y1182805D01*
Y1181598D01*
X745266Y1180968D01*
X743796D01*
X743166Y1181598D01*
Y1182805D01*
X742532Y1183439D01*
X739020D01*
X736222Y1180641D01*
X733891D01*
X727369Y1174119D01*
X724969D01*
X721469Y1170619D01*
X718469D01*
X711669Y1163819D01*
X709469D01*
X705811Y1160161D01*
X701235D01*
X697736Y1156662D01*
X688112D01*
X681419Y1149969D01*
X679319D01*
X675972Y1153316D01*
X666930D01*
X660528Y1146914D01*
X656519D01*
X652373Y1142768D01*
X648460D01*
X647709Y1143519D01*
X634001D01*
X630836Y1140354D01*
X627368D01*
X626738Y1139724D01*
Y1139723D01*
X626108Y1139093D01*
X624738D01*
X624108Y1139723D01*
Y1139724D01*
X623508Y1140324D01*
X620620D01*
X614223Y1133927D01*
Y1103271D01*
X585556Y1074604D01*
X560859D01*
X556904Y1072966D01*
X553526D01*
G01X755841Y1175066D02*
X754166Y1176741D01*
X739019D01*
X735913Y1173635D01*
X733363D01*
X731769Y1172041D01*
Y1167919D01*
X726269Y1162419D01*
X722569D01*
X718669Y1158519D01*
X712869D01*
X707969Y1153619D01*
X705469D01*
X698473Y1146623D01*
X695542D01*
X694160Y1148005D01*
X686355D01*
X681627Y1143277D01*
X679061D01*
X678419Y1143919D01*
X664969D01*
X661569Y1140519D01*
X655697D01*
X651622Y1136444D01*
X649635D01*
X648247Y1137832D01*
X635779D01*
X631986Y1134039D01*
X620983D01*
X618143Y1131199D01*
Y1101647D01*
X587180Y1070684D01*
X561671D01*
X557653Y1069020D01*
X553526D01*
G01X755841Y1191798D02*
X754610Y1190567D01*
X752821D01*
X752047Y1191341D01*
X746358D01*
X744013Y1188996D01*
X741667D01*
X740542Y1190121D01*
X738700D01*
X737637Y1189058D01*
X733109D01*
X726100Y1182049D01*
X724900D01*
X721922Y1179071D01*
X718095D01*
X711508Y1172484D01*
X709898D01*
X705363Y1167949D01*
X703600D01*
X701193Y1165542D01*
X698450D01*
X697295Y1166697D01*
X695286D01*
X694217Y1165628D01*
X687929D01*
X684550Y1162249D01*
X682255D01*
X681153Y1163351D01*
X679144D01*
X678128Y1162335D01*
X675026D01*
X674536Y1162825D01*
X672386D01*
X671896Y1162335D01*
X669746D01*
X669256Y1162825D01*
X667106D01*
X666616Y1162335D01*
X664222D01*
X661494Y1159607D01*
X660801D01*
X659280Y1158086D01*
Y1157393D01*
X657760Y1155873D01*
X657067D01*
X655546Y1154352D01*
Y1153659D01*
X654026Y1152139D01*
X652453D01*
X651255Y1153337D01*
X649554D01*
X648414Y1152197D01*
X646264D01*
X645774Y1152687D01*
X643624D01*
X643134Y1152197D01*
X640984D01*
X640494Y1152687D01*
X638344D01*
X637854Y1152197D01*
X635696D01*
X627917Y1148972D01*
X626382D01*
X625892Y1149462D01*
X623742D01*
X623252Y1148972D01*
X620849D01*
X616551Y1144674D01*
X615858D01*
X614337Y1143153D01*
Y1142460D01*
X612817Y1140940D01*
X612124D01*
X610603Y1139419D01*
Y1138726D01*
X609083Y1137206D01*
Y1105403D01*
X583424Y1079744D01*
X559834D01*
X555959Y1078139D01*
X553526D01*
G01X739699Y1195144D02*
X738626Y1194071D01*
X736723D01*
X735405Y1192753D01*
X729678D01*
X721634Y1184709D01*
X717470D01*
X715441Y1182680D01*
X714748D01*
X713226Y1181158D01*
Y1180465D01*
X711270Y1178509D01*
X707708D01*
X705165Y1175966D01*
X704472D01*
X702951Y1174445D01*
Y1173752D01*
X701431Y1172232D01*
X698452D01*
X697295Y1173389D01*
X695286D01*
X694261Y1172364D01*
X687885D01*
X684421Y1168900D01*
X682296D01*
X681153Y1170043D01*
X679144D01*
X678126Y1169025D01*
X675976D01*
X675486Y1169515D01*
X673336D01*
X672846Y1169025D01*
X669359D01*
X668869Y1169515D01*
X666719D01*
X666229Y1169025D01*
X664079D01*
X659778Y1164724D01*
X658265D01*
X656505Y1162964D01*
X655812D01*
X654290Y1161442D01*
Y1160749D01*
X652350Y1158809D01*
X647862D01*
X646472Y1160199D01*
X644855D01*
X643609Y1158953D01*
X640938D01*
X639564Y1157579D01*
X632281Y1154558D01*
X629794D01*
X629304Y1155048D01*
X627154D01*
X626664Y1154558D01*
X624514D01*
X624024Y1155048D01*
X621874D01*
X621384Y1154558D01*
X619698D01*
X617105Y1151965D01*
X616412D01*
X614891Y1150444D01*
Y1149751D01*
X613371Y1148231D01*
X612678D01*
X611157Y1146710D01*
Y1146017D01*
X609637Y1144497D01*
X608944D01*
X607423Y1142976D01*
Y1142283D01*
X605903Y1140763D01*
Y1106721D01*
X582106Y1082924D01*
X559197D01*
X555610Y1081438D01*
X553526D01*
G01X755676Y1188452D02*
X754781Y1189347D01*
X752315D01*
X751541Y1190121D01*
X746864D01*
X744519Y1187776D01*
X741756D01*
X740760Y1186780D01*
X738678D01*
X737620Y1187838D01*
X733615D01*
X726606Y1180829D01*
X725406D01*
X722428Y1177851D01*
X718601D01*
X712014Y1171264D01*
X710404D01*
X705869Y1166729D01*
X704106D01*
X701699Y1164322D01*
X698467D01*
X697502Y1163357D01*
X696786D01*
X696779Y1163350D01*
X695919D01*
X695912Y1163357D01*
X695420D01*
X694369Y1164408D01*
X688435D01*
X685056Y1161029D01*
X682378D01*
X681360Y1160011D01*
X680627D01*
X680619Y1160003D01*
X679789D01*
X679781Y1160011D01*
X679278D01*
X678174Y1161115D01*
X664728D01*
X654532Y1150919D01*
X652444D01*
X651453Y1149928D01*
X649459D01*
X648410Y1150977D01*
X635939D01*
X628160Y1147752D01*
X621355D01*
X610303Y1136700D01*
Y1104897D01*
X583930Y1078524D01*
X560077D01*
X556202Y1076919D01*
X553526D01*
G01X755841Y1205184D02*
Y1204057D01*
X755121Y1203337D01*
X751478D01*
X750857Y1202716D01*
X748812D01*
X748015Y1203513D01*
X731822D01*
X728270Y1199961D01*
X725113D01*
X721720Y1196568D01*
X717942D01*
X711649Y1190275D01*
X707612D01*
X700771Y1183434D01*
X687428D01*
X684082Y1180088D01*
X676450D01*
X675718Y1180820D01*
X665721D01*
X662520Y1177619D01*
X658755D01*
X651178Y1170042D01*
X642948D01*
X639874Y1166968D01*
X637562D01*
X637559Y1166965D01*
X634459D01*
X631703Y1164209D01*
X620331D01*
X600023Y1143901D01*
Y1109163D01*
X579669Y1088804D01*
X558025D01*
X554652Y1087407D01*
X551246D01*
X549807Y1085968D01*
G01X739699Y1208530D02*
X737525Y1206356D01*
X728284D01*
X726769Y1204841D01*
X725751D01*
X725329Y1205263D01*
X724311D01*
X723398Y1204350D01*
Y1203332D01*
X723820Y1202910D01*
Y1201892D01*
X722647Y1200719D01*
X718441D01*
X717284Y1199562D01*
X715624D01*
X714523Y1198461D01*
Y1196801D01*
X713479Y1195757D01*
X712589D01*
X711673Y1196673D01*
X710783D01*
X709742Y1195632D01*
Y1194742D01*
X710658Y1193826D01*
Y1192936D01*
X709993Y1192271D01*
X702725D01*
X697235Y1186781D01*
X694619D01*
X693989Y1187411D01*
Y1188930D01*
X693359Y1189560D01*
X691889D01*
X691259Y1188930D01*
Y1187411D01*
X690629Y1186781D01*
X686413D01*
X683067Y1183435D01*
X674059D01*
X673429Y1184065D01*
Y1186339D01*
X672799Y1186969D01*
X671329D01*
X670699Y1186339D01*
Y1184065D01*
X670069Y1183435D01*
X665497D01*
X661781Y1179719D01*
X657831D01*
X651501Y1173389D01*
X648437D01*
X647807Y1174019D01*
Y1175050D01*
X647177Y1175680D01*
X645707D01*
X645077Y1175050D01*
Y1174019D01*
X644447Y1173389D01*
X643069D01*
X638651Y1168971D01*
X633407D01*
X630625Y1166189D01*
X619539D01*
X598063Y1144713D01*
Y1109975D01*
X578852Y1090764D01*
X557635D01*
X555363Y1089823D01*
X552627D01*
G01X799099Y1238648D02*
X795267Y1234816D01*
X792563D01*
X791843Y1234096D01*
Y1232250D01*
X791123Y1231530D01*
X789833D01*
X789113Y1232250D01*
Y1234096D01*
X788393Y1234816D01*
X782372D01*
X779791Y1237397D01*
X776512D01*
X775850Y1236735D01*
Y1234719D01*
X774984Y1233853D01*
X773614D01*
X772835Y1234632D01*
Y1236751D01*
X772205Y1237381D01*
X768292D01*
X765678Y1234767D01*
X762907D01*
X760702Y1236972D01*
X750888D01*
X750019Y1237841D01*
X745219D01*
X742735Y1240325D01*
X737135D01*
X736219Y1241241D01*
X734120D01*
X727498Y1234619D01*
X724498D01*
X721524Y1231645D01*
X716769D01*
X712492Y1227368D01*
X707647D01*
X700515Y1220236D01*
X688952D01*
X685595Y1223593D01*
X675333D01*
X674277Y1224649D01*
X672603D01*
X671547Y1223593D01*
X669873D01*
X668817Y1224649D01*
X667143D01*
X666087Y1223593D01*
X664593D01*
X661719Y1220719D01*
X658917D01*
X656154Y1217956D01*
X655264D01*
X654261Y1218959D01*
X653371D01*
X652330Y1217918D01*
Y1217028D01*
X653333Y1216025D01*
Y1215135D01*
X653017Y1214819D01*
X649917D01*
X647417Y1217319D01*
X645411D01*
X643260Y1215168D01*
X640788D01*
X640172Y1214552D01*
Y1213662D01*
X642213Y1211621D01*
Y1210731D01*
X641172Y1209690D01*
X640282D01*
X638241Y1211731D01*
X637351D01*
X633184Y1207564D01*
X631316D01*
X630686Y1208194D01*
Y1209483D01*
X630056Y1210113D01*
X628586D01*
X627956Y1209483D01*
Y1208194D01*
X627326Y1207564D01*
X625370D01*
X622723Y1210211D01*
X618504D01*
X611065Y1202772D01*
Y1186228D01*
X580143Y1155306D01*
Y1117682D01*
X571251Y1108790D01*
X552627D01*
G01X815241Y1235302D02*
X810776D01*
X810210Y1235868D01*
Y1236886D01*
X811674Y1238350D01*
Y1239368D01*
X810761Y1240281D01*
X809743D01*
X808279Y1238817D01*
X807261D01*
X805754Y1240324D01*
X792474D01*
X788969Y1236819D01*
X784069D01*
X781520Y1239368D01*
X767691D01*
X766735Y1240324D01*
X751302D01*
X750819Y1239841D01*
X746318D01*
X742489Y1243670D01*
X733720D01*
X726669Y1236619D01*
X723669D01*
X720681Y1233631D01*
X715902D01*
X711731Y1229460D01*
X706862D01*
X700993Y1223591D01*
X688998D01*
X685651Y1226938D01*
X677433D01*
X676713Y1227658D01*
Y1228469D01*
X675993Y1229189D01*
X674703D01*
X673983Y1228469D01*
Y1227658D01*
X673263Y1226938D01*
X664938D01*
X661519Y1223519D01*
X658020D01*
X657300Y1222799D01*
Y1221912D01*
X656580Y1221192D01*
X655290D01*
X654570Y1221912D01*
Y1222799D01*
X653850Y1223519D01*
X651419D01*
X647319Y1219419D01*
X644619D01*
X642780Y1217580D01*
X635591D01*
X632395Y1214384D01*
X627108D01*
X626288Y1213564D01*
X624478D01*
X623658Y1214384D01*
X619051D01*
X609033Y1204366D01*
Y1187064D01*
X578183Y1156214D01*
Y1118767D01*
X570176Y1110760D01*
X552516D01*
G01X799099Y1215223D02*
X796901D01*
X794020Y1212342D01*
X781822D01*
X780208Y1213956D01*
X777626D01*
X773111Y1209441D01*
X768519D01*
X767219Y1210741D01*
X764225D01*
X762390Y1208906D01*
X759128D01*
X758498Y1209536D01*
Y1209577D01*
X757868Y1210207D01*
X754094D01*
X752862Y1211439D01*
X751364D01*
X750132Y1210207D01*
X746877D01*
X745319Y1211765D01*
Y1212833D01*
X744600Y1213552D01*
X732107D01*
X730740Y1212185D01*
X729421D01*
X728054Y1213552D01*
X724202D01*
X720469Y1209819D01*
X717169D01*
X709969Y1202619D01*
X708569D01*
X705569Y1199619D01*
X701293D01*
X698493Y1196819D01*
X694322D01*
X693135Y1198006D01*
X691592D01*
X690405Y1196819D01*
X685419D01*
X682072Y1200166D01*
X677016D01*
X676367Y1199517D01*
X673259D01*
X672539Y1200237D01*
Y1201414D01*
X671819Y1202134D01*
X670529D01*
X669809Y1201414D01*
Y1200237D01*
X669089Y1199517D01*
X667417D01*
X664554Y1196654D01*
X663536D01*
X662191Y1197999D01*
X661173D01*
X660260Y1197086D01*
Y1196068D01*
X661605Y1194723D01*
Y1193705D01*
X660692Y1192792D01*
X659674D01*
X658329Y1194137D01*
X657311D01*
X656398Y1193224D01*
Y1192206D01*
X657743Y1190861D01*
Y1189843D01*
X656830Y1188930D01*
X655812D01*
X654467Y1190275D01*
X653449D01*
X652536Y1189362D01*
Y1188344D01*
X653881Y1186999D01*
Y1185981D01*
X653039Y1185139D01*
X649009D01*
X646999Y1183129D01*
X644981Y1182293D01*
X644041Y1182683D01*
X643434Y1184149D01*
X642495Y1184539D01*
X641301Y1184044D01*
X640911Y1183104D01*
X641518Y1181638D01*
X641128Y1180698D01*
X639659Y1180089D01*
X635776D01*
X634628Y1181237D01*
X632934D01*
X631786Y1180089D01*
X628674D01*
X627631Y1179046D01*
X626741D01*
X625508Y1180279D01*
X624618D01*
X623577Y1179238D01*
Y1178348D01*
X624810Y1177115D01*
Y1176225D01*
X621700Y1173115D01*
X618419D01*
X592383Y1147079D01*
Y1112328D01*
X576499Y1096444D01*
X556503D01*
X554323Y1095541D01*
X552627D01*
G01X815241Y1218570D02*
X812565Y1215894D01*
X811384D01*
X810469Y1216809D01*
Y1221946D01*
X809838Y1222577D01*
X808575D01*
X806015Y1222581D01*
X805294Y1221862D01*
Y1217530D01*
X804664Y1216900D01*
X798380D01*
X797424Y1217856D01*
X792646D01*
X791926Y1217136D01*
Y1215525D01*
X791206Y1214805D01*
X789916D01*
X789196Y1215525D01*
Y1217136D01*
X788476Y1217856D01*
X782164D01*
X780349Y1216041D01*
X776715D01*
X774915Y1214241D01*
X768819D01*
X767419Y1212841D01*
X760725D01*
X760012Y1213554D01*
X751906D01*
X751119Y1214341D01*
X747020D01*
X744420Y1216941D01*
X741603D01*
X741561Y1216899D01*
X724078D01*
X721298Y1214119D01*
X718298D01*
X711398Y1207219D01*
X709398D01*
X706398Y1204219D01*
X702780D01*
X698727Y1200166D01*
X685866D01*
X682519Y1203513D01*
X677225D01*
X676619Y1204119D01*
X665319D01*
X661763Y1200563D01*
X658910D01*
X647089Y1188742D01*
X643190D01*
X637882Y1183434D01*
X635826D01*
X635196Y1184064D01*
Y1184694D01*
X634194Y1185696D01*
X633096D01*
X632466Y1185066D01*
Y1184064D01*
X631836Y1183434D01*
X630366D01*
X629736Y1184064D01*
Y1186913D01*
X629106Y1187543D01*
X627636D01*
X627006Y1186913D01*
Y1184064D01*
X626376Y1183434D01*
X624939D01*
X621589Y1180084D01*
X620123D01*
X590423Y1150384D01*
Y1113140D01*
X575687Y1098404D01*
X556111D01*
X553992Y1097526D01*
X553217D01*
G01X815241Y1211877D02*
X813564Y1213554D01*
X798306D01*
X795072Y1210320D01*
X781919D01*
X773243Y1206861D01*
X755190D01*
X754833Y1207009D01*
X753065Y1207741D01*
X745809D01*
X743343Y1210207D01*
X723969D01*
X721381Y1207619D01*
X718081D01*
X710881Y1200419D01*
X709191D01*
X706191Y1197419D01*
X702069D01*
X698124Y1193474D01*
X694152D01*
X692925Y1194701D01*
X691422D01*
X690195Y1193474D01*
X685764D01*
X682419Y1196819D01*
X672993D01*
X672567Y1196393D01*
X671549D01*
X670463Y1197479D01*
X669445D01*
X668532Y1196566D01*
Y1195548D01*
X669618Y1194462D01*
Y1193444D01*
X668544Y1192370D01*
X667654D01*
X666632Y1193392D01*
X665742D01*
X664701Y1192351D01*
Y1191461D01*
X665723Y1190439D01*
Y1189549D01*
X664682Y1188508D01*
X663792D01*
X663004Y1189296D01*
X662114D01*
X661073Y1188255D01*
Y1187365D01*
X661861Y1186577D01*
Y1185687D01*
X660993Y1184819D01*
X657169D01*
X651449Y1179099D01*
X648679D01*
X647690Y1180088D01*
X644798D01*
X641451Y1176741D01*
X635898D01*
X635523Y1176366D01*
X634505D01*
X632789Y1178082D01*
X631771D01*
X630858Y1177169D01*
Y1176151D01*
X632574Y1174435D01*
Y1173417D01*
X629327Y1170170D01*
X627866D01*
X627146Y1170890D01*
Y1172994D01*
X626426Y1173714D01*
X625136D01*
X624416Y1172994D01*
Y1170890D01*
X623696Y1170170D01*
X618252D01*
X594343Y1146261D01*
Y1111516D01*
X577311Y1094484D01*
X556894D01*
X554627Y1093545D01*
X552627D01*
G01X815241Y1228609D02*
X814153Y1227521D01*
X811430D01*
X809829Y1228184D01*
X805863D01*
X803587Y1225908D01*
X800915D01*
X799890Y1226933D01*
X798366D01*
X797343Y1225910D01*
X782425D01*
X779804Y1228531D01*
X776435D01*
X771365Y1223461D01*
X768325D01*
X766752Y1225034D01*
X763294D01*
X760775Y1222515D01*
X757602D01*
X756530Y1223587D01*
X755026D01*
X754039Y1222600D01*
X751686D01*
X751196Y1223090D01*
X749046D01*
X748556Y1222600D01*
X746406D01*
X743158Y1225848D01*
X741479D01*
X740394Y1226933D01*
X738924D01*
X737854Y1225863D01*
X735704D01*
X735214Y1226353D01*
X733064D01*
X732574Y1225863D01*
X730424D01*
X729934Y1226353D01*
X727784D01*
X727294Y1225863D01*
X725260D01*
X721606Y1222209D01*
X717858D01*
X715786Y1220137D01*
X715093D01*
X713571Y1218615D01*
Y1217922D01*
X711858Y1216209D01*
X709208D01*
X704395Y1211396D01*
X702619D01*
X700320Y1209097D01*
X698309D01*
X697205Y1210201D01*
X695686D01*
X694677Y1209192D01*
X692202D01*
X691712Y1209682D01*
X689562D01*
X689072Y1209192D01*
X686922D01*
X683693Y1212421D01*
X682136D01*
X681009Y1213548D01*
X679320D01*
X678480Y1212708D01*
X676408D01*
X675918Y1213198D01*
X673768D01*
X673278Y1212708D01*
X671128D01*
X670638Y1213198D01*
X668488D01*
X667998Y1212708D01*
X664682D01*
X661113Y1209139D01*
X657031D01*
X654777Y1206885D01*
X654084D01*
X652563Y1205364D01*
Y1204671D01*
X649771Y1201879D01*
X648389D01*
X646123Y1199613D01*
X645430D01*
X643909Y1198092D01*
Y1197399D01*
X642249Y1195739D01*
X638807D01*
X637731Y1196815D01*
X636358D01*
X635352Y1195809D01*
X629550D01*
X626199Y1199160D01*
X622630D01*
X621637Y1200153D01*
X620109D01*
X619136Y1199180D01*
X617892D01*
X616262Y1197550D01*
Y1184058D01*
X585283Y1153079D01*
Y1115270D01*
X573557Y1103544D01*
X555042D01*
X553004Y1102700D01*
X552627D01*
G01X799099Y1231955D02*
X798001Y1230857D01*
X795665D01*
X793909Y1229101D01*
X789869D01*
X789379Y1229591D01*
X787229D01*
X786739Y1229101D01*
X783813D01*
X781162Y1231752D01*
X774963D01*
X772782Y1229571D01*
X770632D01*
X770142Y1230061D01*
X767992D01*
X767502Y1229571D01*
X763304D01*
X760274Y1232601D01*
X757567D01*
X756542Y1233626D01*
X755152D01*
X754127Y1232601D01*
X751993D01*
X751503Y1233091D01*
X749353D01*
X748863Y1232601D01*
X746588D01*
X743285Y1235904D01*
X741467D01*
X740398Y1236973D01*
X739004D01*
X737929Y1235898D01*
X732649D01*
X731095Y1234344D01*
X730402D01*
X728881Y1232823D01*
Y1232130D01*
X725890Y1229139D01*
X723740D01*
X723250Y1229629D01*
X721100D01*
X720610Y1229139D01*
X717864D01*
X716103Y1227378D01*
X715410D01*
X713888Y1225856D01*
Y1225163D01*
X711074Y1222349D01*
X708162D01*
X705387Y1219574D01*
X704694D01*
X703173Y1218053D01*
Y1217360D01*
X701653Y1215840D01*
X698232D01*
X697179Y1216893D01*
X695682D01*
X694590Y1215801D01*
X692024D01*
X691534Y1216291D01*
X689384D01*
X688894Y1215801D01*
X687144D01*
X683753Y1219192D01*
X682057D01*
X681009Y1220240D01*
X679454D01*
X678325Y1219111D01*
X676383D01*
X675893Y1219601D01*
X673743D01*
X673253Y1219111D01*
X670391D01*
X669901Y1219601D01*
X667751D01*
X667261Y1219111D01*
X664624D01*
X659076Y1215404D01*
X658397Y1215539D01*
X656608Y1214343D01*
X656473Y1213663D01*
X647240Y1207493D01*
X642179Y1202432D01*
X638843D01*
X637767Y1203508D01*
X636302D01*
X635281Y1202487D01*
X632891D01*
X632401Y1202977D01*
X630251D01*
X629761Y1202487D01*
X627611D01*
X624288Y1205810D01*
X622707D01*
X621673Y1206844D01*
X620203D01*
X619085Y1205726D01*
X617162D01*
X613065Y1201629D01*
Y1185422D01*
X582103Y1154460D01*
Y1116589D01*
X572281Y1106767D01*
X552627D01*
G01X815241Y1225263D02*
X814203Y1226301D01*
X811187D01*
X809586Y1226964D01*
X806369D01*
X804093Y1224688D01*
X800891D01*
X799796Y1223593D01*
X798394D01*
X797297Y1224690D01*
X781919D01*
X779298Y1227311D01*
X776941D01*
X771871Y1222241D01*
X767819D01*
X766246Y1223814D01*
X763800D01*
X761281Y1221295D01*
X757592D01*
X756537Y1220240D01*
X755131D01*
X753991Y1221380D01*
X745900D01*
X742652Y1224628D01*
X741447D01*
X740412Y1223593D01*
X738946D01*
X737896Y1224643D01*
X725766D01*
X722112Y1220989D01*
X718364D01*
X712364Y1214989D01*
X709714D01*
X704901Y1210176D01*
X703125D01*
X700826Y1207877D01*
X698190D01*
X697177Y1206864D01*
X695681D01*
X694573Y1207972D01*
X686416D01*
X683187Y1211201D01*
X682213D01*
X681220Y1210208D01*
X679620D01*
X678340Y1211488D01*
X665188D01*
X661619Y1207919D01*
X657537D01*
X650277Y1200659D01*
X648895D01*
X642755Y1194519D01*
X638782D01*
X637738Y1193475D01*
X636354D01*
X635240Y1194589D01*
X629044D01*
X625693Y1197940D01*
X622777D01*
X621641Y1196804D01*
X620158D01*
X619002Y1197960D01*
X618398D01*
X617482Y1197044D01*
Y1183552D01*
X586503Y1152573D01*
Y1114764D01*
X574063Y1102324D01*
X555285D01*
X553247Y1101480D01*
X552627D01*
G01X799099Y1245341D02*
X797423Y1247017D01*
X790447D01*
X786749Y1243319D01*
X784146D01*
X781766Y1245699D01*
X776749D01*
X776029Y1246419D01*
Y1250957D01*
X775309Y1251677D01*
X774019D01*
X773299Y1250957D01*
Y1246419D01*
X772579Y1245699D01*
X767638D01*
X766320Y1247017D01*
X764536D01*
X763520Y1248033D01*
Y1249942D01*
X762738Y1250724D01*
X760684D01*
X759785Y1249825D01*
Y1247840D01*
X758962Y1247017D01*
X754367D01*
X753197Y1245847D01*
X748631D01*
X743987Y1250491D01*
X738463D01*
X736957Y1248985D01*
X732765D01*
X727879Y1244099D01*
X726311Y1243388D01*
X723118D01*
X719549Y1239819D01*
X708969D01*
X706254Y1237104D01*
X704809Y1236409D01*
X700409D01*
X697617Y1233617D01*
X687768D01*
X684407Y1236978D01*
X673105D01*
X672385Y1237698D01*
Y1239908D01*
X671665Y1240628D01*
X670375D01*
X669655Y1239908D01*
Y1237698D01*
X668935Y1236978D01*
X667378D01*
X661356Y1230956D01*
X656903D01*
X656183Y1231676D01*
Y1234890D01*
X655463Y1235610D01*
X654173D01*
X653453Y1234890D01*
Y1231676D01*
X652733Y1230956D01*
X648856D01*
X641795Y1223895D01*
X632422D01*
X630511Y1221984D01*
X619502D01*
X605100Y1207582D01*
Y1188808D01*
X574263Y1157971D01*
Y1120974D01*
X567982Y1114693D01*
X549208D01*
X548895Y1114380D01*
G01X815241Y1241995D02*
X813563Y1243673D01*
X806220D01*
X805500Y1244393D01*
Y1246500D01*
X804780Y1247220D01*
X803490D01*
X802770Y1246500D01*
Y1244393D01*
X802050Y1243673D01*
X792932D01*
X787109Y1241319D01*
X783355D01*
X778925Y1243658D01*
X776437D01*
X775717Y1242938D01*
Y1242048D01*
X774997Y1241328D01*
X773707D01*
X772987Y1242048D01*
Y1242938D01*
X772267Y1243658D01*
X748724D01*
X740617Y1247017D01*
X733767D01*
X729074Y1242324D01*
X726399Y1241319D01*
X724109Y1240659D01*
X721169Y1237719D01*
X716453D01*
X715733Y1236999D01*
Y1236098D01*
X715013Y1235378D01*
X713723D01*
X713003Y1236098D01*
Y1236999D01*
X712283Y1237719D01*
X711499D01*
X709310Y1237264D01*
X707405Y1235359D01*
X698439Y1230285D01*
X695764D01*
X693939Y1230386D01*
X692611Y1230565D01*
X691903Y1230025D01*
X691601Y1227794D01*
X690893Y1227254D01*
X689534Y1227439D01*
X688994Y1228147D01*
X689296Y1230378D01*
X688756Y1231086D01*
X686774Y1231355D01*
X681557Y1233527D01*
X681307Y1233631D01*
X674505D01*
X670828Y1231960D01*
X670515Y1231127D01*
X670874Y1230339D01*
X670561Y1229506D01*
X669312Y1228937D01*
X668479Y1229250D01*
X668120Y1230038D01*
X667287Y1230351D01*
X665600Y1229583D01*
X658832Y1228512D01*
X658234Y1227690D01*
X658403Y1226630D01*
X657804Y1225807D01*
X656529Y1225604D01*
X655706Y1226203D01*
X655537Y1227262D01*
X654714Y1227861D01*
X648515Y1226879D01*
X647771Y1226471D01*
X641380Y1220080D01*
X635264D01*
X631835Y1216651D01*
X628031D01*
X627311Y1217371D01*
Y1219222D01*
X626591Y1219942D01*
X625301D01*
X624581Y1219222D01*
Y1217371D01*
X623861Y1216651D01*
X617394D01*
X607067Y1206324D01*
Y1187936D01*
X576223Y1157092D01*
Y1119886D01*
X569070Y1112733D01*
X551195D01*
X550869Y1112407D01*
G01X739699Y796916D02*
X738038Y795255D01*
X703543D01*
X700206Y798592D01*
X693892D01*
X690545Y795245D01*
X687015D01*
X685792Y796468D01*
X684285D01*
X683062Y795245D01*
X677345D01*
X676819Y794719D01*
X672842D01*
X672122Y795439D01*
Y796690D01*
X671402Y797410D01*
X670112D01*
X669392Y796690D01*
Y795439D01*
X668672Y794719D01*
X665119D01*
X663819Y796019D01*
X657363D01*
X656733Y795389D01*
Y794498D01*
X656103Y793868D01*
X654633D01*
X654003Y794498D01*
Y795389D01*
X653373Y796019D01*
X648819D01*
X647419Y794619D01*
X635919D01*
X635119Y795419D01*
X627713D01*
X627083Y794789D01*
Y791235D01*
X626453Y790605D01*
X624983D01*
X624353Y791235D01*
Y794789D01*
X623723Y795419D01*
X619719D01*
X593174Y821964D01*
Y825719D01*
X560703Y858190D01*
G01X769399Y960892D02*
X769299D01*
X768261Y961930D01*
X756779Y969261D01*
X754549D01*
X749458Y972607D01*
X733881D01*
X729035Y977453D01*
X717864Y982080D01*
X716394D01*
X715674Y982800D01*
Y986075D01*
X714954Y986795D01*
X713664D01*
X712944Y986075D01*
Y982800D01*
X712224Y982080D01*
X708212D01*
X704299Y985993D01*
X665305D01*
X662613Y988685D01*
X658965D01*
X651532Y996118D01*
X616756D01*
X612471Y1000403D01*
X589810D01*
X583703Y1006510D01*
X574155D01*
X569705Y1005625D01*
X565997Y1004089D01*
X560223Y998315D01*
X542062D01*
G01X828799Y960892D02*
X828699D01*
X826316Y958509D01*
X823737D01*
X818573Y963673D01*
Y970604D01*
X816569Y972608D01*
X806832D01*
X800139Y979301D01*
X789959D01*
X784831Y984429D01*
X780766D01*
X755778Y1009417D01*
X754654D01*
X754653Y1009416D01*
X749852D01*
X749132Y1008696D01*
Y1005588D01*
X748412Y1004868D01*
X747122D01*
X746402Y1005588D01*
Y1008696D01*
X745682Y1009416D01*
X595890D01*
X591152Y1014154D01*
X573417D01*
X566666Y1012811D01*
X557282Y1008924D01*
X554958Y1006600D01*
X550925D01*
G01X799099Y960892D02*
X797964Y960422D01*
X797321D01*
X788645Y969098D01*
X770789Y978749D01*
X763544Y985994D01*
X750513D01*
X739902Y996605D01*
X738884D01*
X734707Y992428D01*
X733689D01*
X732776Y993341D01*
Y994359D01*
X736953Y998536D01*
Y999554D01*
X736040Y1000467D01*
X735022D01*
X730845Y996290D01*
X729827D01*
X728914Y997203D01*
Y998221D01*
X733091Y1002398D01*
Y1003416D01*
X731068Y1005439D01*
X649231D01*
Y1005438D01*
X590140D01*
X585348Y1010230D01*
X573786D01*
X568342Y1009147D01*
X562275Y1006634D01*
X557915Y1002274D01*
X550925D01*
G01X828799Y957546D02*
Y957646D01*
X831009Y959856D01*
Y961489D01*
X829930Y962568D01*
X826320D01*
X821919Y966969D01*
Y970972D01*
X816937Y975954D01*
X806640D01*
X799947Y982647D01*
X795021D01*
X786079Y991589D01*
X779999D01*
X775969Y995619D01*
X772812D01*
X757048Y1011383D01*
X596842D01*
X592111Y1016114D01*
X573222D01*
X565430Y1014564D01*
X555713Y1010539D01*
X554002Y1008828D01*
X550925D01*
G01X799099Y957546D02*
Y957646D01*
X800969Y959516D01*
Y961662D01*
X800069Y962562D01*
X798311D01*
X796419Y964454D01*
Y969957D01*
X795027Y971349D01*
X790931D01*
X784751Y977529D01*
X782919D01*
X779519Y980929D01*
X776249D01*
X767838Y989340D01*
X762969D01*
X762249Y990060D01*
Y991815D01*
X761529Y992535D01*
X760239D01*
X759519Y991815D01*
Y990060D01*
X758799Y989340D01*
X753449D01*
X743320Y999469D01*
Y1000487D01*
X744473Y1001640D01*
Y1002658D01*
X743560Y1003571D01*
X742542D01*
X741389Y1002418D01*
X740371D01*
X739458Y1003331D01*
Y1004349D01*
X740611Y1005502D01*
Y1006520D01*
X739698Y1007433D01*
X738680D01*
X737527Y1006280D01*
X736509D01*
X735340Y1007449D01*
X591583D01*
X586838Y1012194D01*
X573613D01*
X567363Y1010951D01*
X559922Y1007869D01*
X556668Y1004615D01*
X550925D01*
G01X739699Y773491D02*
X734682Y768474D01*
X694673D01*
X691158Y764959D01*
X673308D01*
X672588Y765679D01*
Y766389D01*
X671868Y767109D01*
X670578D01*
X669858Y766389D01*
Y765679D01*
X669138Y764959D01*
X661151D01*
X660431Y765679D01*
Y767668D01*
X659711Y768388D01*
X658421D01*
X657701Y767668D01*
Y765679D01*
X656981Y764959D01*
X643369D01*
X639294Y769034D01*
X631210D01*
X631095Y768919D01*
X631069D01*
X630374Y768224D01*
X620388D01*
X577783Y810829D01*
Y820233D01*
X553195Y844821D01*
G01X755841Y776837D02*
X755805Y776856D01*
X750228Y775168D01*
X725215D01*
X721867Y771820D01*
X694220D01*
X690874Y768474D01*
X677264D01*
X676619Y769119D01*
X666289D01*
X661631Y770515D01*
X659927Y772219D01*
X657353D01*
X656633Y771499D01*
Y769574D01*
X655913Y768854D01*
X654623D01*
X653903Y769574D01*
Y771499D01*
X653183Y772219D01*
X648819D01*
X648019Y771419D01*
X646269D01*
X645639Y770789D01*
Y769098D01*
X645009Y768468D01*
X643539D01*
X642909Y769098D01*
Y770789D01*
X642279Y771419D01*
X634319D01*
X633886Y771852D01*
X620024D01*
X579985Y811989D01*
X579996Y820842D01*
X554634Y846260D01*
G01X755841Y770144D02*
X750450Y767911D01*
X733678Y762822D01*
X718086Y762794D01*
X717365Y763513D01*
X717363Y764365D01*
X717360Y765737D01*
X716640Y766455D01*
X715349Y766451D01*
X714630Y765730D01*
X714633Y764365D01*
X714635Y763506D01*
X713917Y762786D01*
X641102Y762651D01*
X638939Y764814D01*
X621020D01*
X575795Y810039D01*
Y819323D01*
X551746Y843372D01*
G01X739699Y803609D02*
X737344Y801254D01*
X724866D01*
X724236Y801884D01*
Y803935D01*
X723606Y804565D01*
X722136D01*
X721506Y803935D01*
Y801884D01*
X720876Y801254D01*
X720158D01*
X717539Y803873D01*
X708973D01*
X706898Y801798D01*
X704406D01*
X700919Y805285D01*
X693385D01*
X690038Y801938D01*
X687634D01*
X686914Y802658D01*
Y803935D01*
X686194Y804655D01*
X684904D01*
X684184Y803935D01*
Y802658D01*
X683464Y801938D01*
X673143D01*
X672423Y802658D01*
Y804171D01*
X671703Y804891D01*
X670413D01*
X669693Y804171D01*
Y802658D01*
X668973Y801938D01*
X665100D01*
X663919Y803119D01*
X650119D01*
X648521Y801521D01*
X643826D01*
X643106Y802241D01*
Y804036D01*
X642386Y804756D01*
X641096D01*
X640376Y804036D01*
Y802241D01*
X639656Y801521D01*
X634517D01*
X633704Y802334D01*
X626841D01*
X626121Y803054D01*
Y804743D01*
X625401Y805463D01*
X624111D01*
X623391Y804743D01*
Y803054D01*
X622671Y802334D01*
X619204D01*
X597167Y824371D01*
Y827327D01*
X560623Y863871D01*
G01X755841Y800263D02*
Y799231D01*
X754892Y798282D01*
X745606D01*
X745303Y798585D01*
X703773D01*
X700419Y801939D01*
X693839D01*
X690492Y798592D01*
X677146D01*
X676319Y799419D01*
X665019D01*
X663669Y798069D01*
X657151D01*
X656521Y798699D01*
Y799722D01*
X655891Y800352D01*
X654421D01*
X653791Y799722D01*
Y798699D01*
X653161Y798069D01*
X648869D01*
X647388Y799550D01*
X644265D01*
X643545Y798830D01*
Y797456D01*
X642825Y796736D01*
X641535D01*
X640815Y797456D01*
Y798830D01*
X640095Y799550D01*
X636750D01*
X634744Y797544D01*
X628358D01*
X627638Y798264D01*
Y799403D01*
X626918Y800123D01*
X625628D01*
X624908Y799403D01*
Y798264D01*
X624188Y797544D01*
X621205D01*
X595163Y823586D01*
Y826542D01*
X561109Y860596D01*
G01X755841Y793570D02*
X754164Y791893D01*
X703559D01*
X700206Y795246D01*
X694246D01*
X690899Y791899D01*
X687051D01*
X686421Y791269D01*
Y788998D01*
X685791Y788368D01*
X684321D01*
X683691Y788998D01*
Y791269D01*
X683061Y791899D01*
X673713D01*
X673083Y791269D01*
Y788898D01*
X672453Y788268D01*
X670983D01*
X670353Y788898D01*
Y791269D01*
X669723Y791899D01*
X647939D01*
X647319Y792519D01*
X644031D01*
X643401Y791889D01*
Y790150D01*
X642771Y789520D01*
X641301D01*
X640671Y790150D01*
Y791889D01*
X640041Y792519D01*
X636773D01*
X632871Y788617D01*
X622567D01*
X591068Y820116D01*
Y824961D01*
X560751Y855278D01*
G01X739699Y780184D02*
X737234Y777719D01*
X724650D01*
X722098Y775167D01*
X693067D01*
X689720Y771820D01*
X677120D01*
X676619Y771319D01*
X673376D01*
X672656Y772039D01*
Y773491D01*
X671936Y774211D01*
X670646D01*
X669926Y773491D01*
Y772039D01*
X669206Y771319D01*
X665853D01*
X662993Y774179D01*
X657161D01*
X656441Y774899D01*
Y775969D01*
X655721Y776689D01*
X654431D01*
X653711Y775969D01*
Y774899D01*
X652991Y774179D01*
X648459D01*
X647419Y775219D01*
X632419D01*
X631091Y773891D01*
X627470D01*
X626750Y774611D01*
Y776086D01*
X626030Y776806D01*
X624740D01*
X624020Y776086D01*
Y774611D01*
X623300Y773891D01*
X620920D01*
X582067Y812744D01*
Y821830D01*
X556135Y847762D01*
G01X739699Y786877D02*
X738693Y787883D01*
X737104D01*
X735468Y786247D01*
X725266D01*
X723033Y788480D01*
X720245D01*
X717843Y786078D01*
X715343D01*
X712889Y788532D01*
X710573D01*
X708209Y786168D01*
X703932D01*
X700452Y789648D01*
X698313D01*
X697218Y788553D01*
X695750D01*
X694655Y789648D01*
X693675D01*
X690976Y786949D01*
X689436D01*
X685442Y782955D01*
X682141D01*
X681046Y781860D01*
X679564D01*
X678593Y782831D01*
X667280D01*
X664837Y785274D01*
X620365D01*
X587773Y817866D01*
Y823637D01*
X559892Y851518D01*
G01X755841Y786877D02*
X754849Y785885D01*
X753573D01*
X749862Y786623D01*
X748292D01*
X742366Y784175D01*
X741489D01*
X740464Y785200D01*
X738820D01*
X737795Y784175D01*
X726137D01*
X719881Y781582D01*
X709201D01*
X708438Y781899D01*
X707674Y782662D01*
X706133Y783302D01*
X703246D01*
X701954Y782764D01*
X700516Y781326D01*
X699324Y780829D01*
X698285D01*
X697260Y781854D01*
X695694D01*
X694699Y780859D01*
X690634D01*
X686733Y779238D01*
X685515Y778020D01*
X684086Y777425D01*
X682096D01*
X681014Y778507D01*
X679576D01*
X678526Y777457D01*
X666691D01*
X660556Y779999D01*
X650240D01*
X647003Y778447D01*
X634299D01*
X630467Y780039D01*
X621426D01*
X585414Y816051D01*
Y823185D01*
X558487Y850112D01*
G01X739699Y790223D02*
X738579Y789103D01*
X736598D01*
X734962Y787467D01*
X725772D01*
X723539Y789700D01*
X719739D01*
X717337Y787298D01*
X715849D01*
X713395Y789752D01*
X710067D01*
X707703Y787388D01*
X704438D01*
X700958Y790868D01*
X698227D01*
X697202Y791893D01*
X695638D01*
X694613Y790868D01*
X693169D01*
X690470Y788169D01*
X688930D01*
X684936Y784175D01*
X682111D01*
X681086Y785200D01*
X679500D01*
X678351Y784051D01*
X667786D01*
X665343Y786494D01*
X620871D01*
X588993Y818372D01*
Y824143D01*
X560755Y852381D01*
G01X755841Y783530D02*
X754706Y784665D01*
X753452D01*
X749741Y785403D01*
X748535D01*
X742609Y782955D01*
X741531D01*
X740436Y781860D01*
X739018D01*
X737923Y782955D01*
X726380D01*
X720124Y780362D01*
X708958D01*
X707748Y780863D01*
X706978Y781630D01*
X705889Y782082D01*
X703491D01*
X702646Y781730D01*
X701209Y780292D01*
X699569Y779609D01*
X698317D01*
X697222Y778514D01*
X695730D01*
X694605Y779639D01*
X690878D01*
X687425Y778203D01*
X686816Y777595D01*
X686207Y776986D01*
X684330Y776205D01*
X682076D01*
X681038Y775167D01*
X679502D01*
X678432Y776237D01*
X666448D01*
X660313Y778779D01*
X650518D01*
X647281Y777227D01*
X634055D01*
X630223Y778819D01*
X620920D01*
X584194Y815545D01*
Y822679D01*
X557624Y849249D01*
G01X1303082Y1011170D02*
X1293574D01*
X1284107Y1015091D01*
X1281033D01*
X1280158Y1015966D01*
X1257054D01*
X1256178Y1015090D01*
X1237856D01*
X1237855Y1015091D01*
X1034783D01*
X1024512Y1004820D01*
Y995720D01*
X1015912Y987120D01*
X1011912D01*
X1007412Y982620D01*
Y966021D01*
X1012541Y960892D01*
G01X1303667Y969370D02*
X1300531D01*
X1294648Y963487D01*
X1263030D01*
X1261887Y964630D01*
X1250754D01*
X1240845Y954721D01*
X1234790D01*
X1229244Y949175D01*
X1223697D01*
X1223253Y949619D01*
X1208951D01*
X1208151Y948819D01*
X1195476D01*
X1192120Y945463D01*
X1188265D01*
X1184551Y949177D01*
X1090785D01*
X1089870Y948262D01*
X1076655D01*
X1073913Y945520D01*
X1071350D01*
X1064347Y952523D01*
X1039409D01*
X1035112Y956820D01*
Y960119D01*
X1032038Y963193D01*
X1031441Y964634D01*
X1030150Y965925D01*
X1025989D01*
X1025269Y966645D01*
Y968625D01*
X1024549Y969345D01*
X1023159D01*
X1022439Y968625D01*
Y966645D01*
X1021719Y965925D01*
X1018980D01*
X1017320Y967585D01*
X1012541D01*
G01X1303263Y1009210D02*
X1294853D01*
X1285493Y1013087D01*
X1256179D01*
X1256178Y1013086D01*
X1237856D01*
X1237855Y1013087D01*
X1036086D01*
X1026839Y1003840D01*
Y991447D01*
X1016912Y981520D01*
X1011912D01*
X1009912Y979520D01*
Y966920D01*
X1010923Y965909D01*
X1013292D01*
X1015863Y963338D01*
Y960868D01*
X1012541Y957546D01*
G01X1303666Y968001D02*
X1301058D01*
X1295211Y962154D01*
X1251142D01*
X1241619Y952631D01*
X1235586D01*
X1229623Y946668D01*
X1226050D01*
X1225226Y945844D01*
X1209986D01*
X1209444Y946386D01*
X1195851D01*
X1192943Y943478D01*
X1182461D01*
X1180109Y945830D01*
X1176877D01*
X1176874Y945833D01*
X1165081D01*
X1165079Y945831D01*
X1123942D01*
X1123222Y945111D01*
Y943265D01*
X1122502Y942545D01*
X1121222D01*
X1120502Y943265D01*
Y945111D01*
X1119782Y945831D01*
X1094919D01*
X1090850Y941762D01*
X1085203D01*
X1084483Y942482D01*
Y945411D01*
X1083763Y946131D01*
X1082483D01*
X1081763Y945411D01*
Y942482D01*
X1081043Y941762D01*
X1076687D01*
X1075019Y943430D01*
X1070630D01*
X1064883Y949177D01*
X1044363D01*
X1044362Y949176D01*
X1035956D01*
X1030712Y954420D01*
Y961079D01*
X1029912Y963010D01*
X1028683Y964239D01*
G01X1303263Y1007249D02*
X1295563D01*
X1286531Y1010990D01*
X1256179D01*
X1256178Y1010989D01*
X1237856D01*
X1237855Y1010990D01*
X1057006D01*
X1054002Y1007986D01*
X1040799D01*
X1036991Y1004178D01*
Y1001664D01*
X1036271Y1000944D01*
X1032300D01*
X1031580Y1000224D01*
Y998944D01*
X1032300Y998224D01*
X1036271D01*
X1036991Y997504D01*
Y996224D01*
X1036271Y995504D01*
X1032300D01*
X1031580Y994784D01*
Y993504D01*
X1032300Y992784D01*
X1036271D01*
X1036991Y992064D01*
Y963171D01*
X1039270Y960892D01*
X1042241D01*
G01X1300865Y897046D02*
X1284833D01*
X1273106Y885319D01*
Y874783D01*
X1240021Y841698D01*
X1238574Y838205D01*
X1234248Y833879D01*
X1233356Y831726D01*
X1229635Y826158D01*
X1228296Y824819D01*
X1212862D01*
X1209934Y821891D01*
X1195932D01*
X1192260Y818219D01*
X1189184D01*
X1182940Y811975D01*
X1174350D01*
X1171001Y815324D01*
X1149320D01*
X1148384Y814388D01*
X1144423D01*
X1143514Y815297D01*
X1141793D01*
X1140884Y814388D01*
X1135770D01*
X1133354Y811972D01*
X1115551D01*
X1113330Y814193D01*
X1108713D01*
X1107582Y815324D01*
X1101296D01*
X1101292Y815328D01*
X1069547D01*
X1068917Y815958D01*
Y817268D01*
X1068287Y817898D01*
X1066817D01*
X1066187Y817268D01*
Y815958D01*
X1065557Y815328D01*
X1055479D01*
X1054732Y814581D01*
X1050474D01*
X1049754Y813861D01*
Y812828D01*
X1049034Y812108D01*
X1047754D01*
X1047034Y812828D01*
Y813861D01*
X1046314Y814581D01*
X1044655D01*
X1042241Y816995D01*
G01X1300865Y893126D02*
X1286833D01*
X1277185Y883478D01*
Y873069D01*
X1244911Y840795D01*
X1241342Y832178D01*
X1238109Y828945D01*
X1236916D01*
X1235504Y827533D01*
Y825917D01*
X1229190Y819603D01*
X1225566D01*
X1224382Y818419D01*
X1215669D01*
X1213038Y815788D01*
X1209580D01*
X1208411Y814619D01*
X1195761D01*
X1192661Y811519D01*
X1189498D01*
X1183261Y805282D01*
X1174571D01*
X1171222Y808631D01*
X1159672D01*
X1158285Y810018D01*
X1149857D01*
X1148470Y808631D01*
X1137981D01*
X1134634Y805284D01*
X1116374D01*
X1115590Y806068D01*
X1112894D01*
X1110331Y808631D01*
X1053722D01*
X1053050Y807959D01*
X1050747D01*
X1050027Y807239D01*
Y806162D01*
X1049307Y805442D01*
X1048027D01*
X1047307Y806162D01*
Y807239D01*
X1046587Y807959D01*
X1044584D01*
X1042241Y810302D01*
G01X1301465Y907326D02*
X1278994D01*
X1262235Y890567D01*
Y878710D01*
X1241249Y857724D01*
X1235594D01*
X1233226Y855356D01*
Y853564D01*
X1229005Y849343D01*
X1225122D01*
X1221818Y846039D01*
X1220150D01*
X1215770Y841659D01*
X1210725D01*
X1207585Y838519D01*
X1196161D01*
X1191930Y834288D01*
X1181525D01*
X1180416Y835397D01*
X1173824D01*
X1170472Y838749D01*
X1151492D01*
X1148143Y835400D01*
X1145162D01*
X1144442Y834680D01*
Y833391D01*
X1143722Y832671D01*
X1142442D01*
X1141722Y833391D01*
Y834680D01*
X1141002Y835400D01*
X1107632D01*
X1104286Y838746D01*
X1100080D01*
X1096578Y835244D01*
X1091161D01*
X1090296Y836109D01*
X1085138D01*
X1084418Y835389D01*
Y834907D01*
X1083698Y834187D01*
X1082418D01*
X1081698Y834907D01*
Y835389D01*
X1080978Y836109D01*
X1076098D01*
X1074728Y834739D01*
X1060108D01*
X1059450Y835397D01*
X1050790D01*
X1050070Y836117D01*
Y837334D01*
X1049350Y838054D01*
X1048070D01*
X1047350Y837334D01*
Y836117D01*
X1046630Y835397D01*
X1043910D01*
X1042241Y833727D01*
G01X1301465Y902186D02*
X1281585D01*
X1267669Y888270D01*
Y876826D01*
X1240954Y850111D01*
X1237129D01*
X1233894Y846875D01*
X1230506Y838700D01*
X1228348Y836541D01*
X1225155Y835219D01*
X1224889Y834577D01*
X1222893Y833751D01*
X1222253Y834016D01*
X1217749Y832151D01*
X1210932D01*
X1208085Y830971D01*
X1205967Y830550D01*
X1205582Y829973D01*
X1203462Y829552D01*
X1202886Y829937D01*
X1196047Y828577D01*
X1193118Y827365D01*
X1188644D01*
X1188154Y826875D01*
X1185994D01*
X1185504Y827365D01*
X1183344D01*
X1182347Y826368D01*
X1179019D01*
X1178009Y825358D01*
X1176360D01*
X1175340Y826378D01*
X1172544D01*
X1170321Y828600D01*
X1167399Y829811D01*
X1162953D01*
X1161854Y828712D01*
X1160246D01*
X1159165Y829793D01*
X1156488D01*
X1154655Y827960D01*
Y827267D01*
X1153127Y825739D01*
X1152434D01*
X1150631Y823936D01*
X1148471D01*
X1147981Y823446D01*
X1145821D01*
X1145331Y823936D01*
X1143171D01*
X1142681Y823446D01*
X1140521D01*
X1140031Y823936D01*
X1137261D01*
X1131416Y826356D01*
X1129256D01*
X1128766Y825866D01*
X1126606D01*
X1126116Y826356D01*
X1119717D01*
X1118722Y825361D01*
X1116905D01*
X1115919Y826347D01*
X1112855D01*
X1111057Y828144D01*
X1109517Y828784D01*
X1105826D01*
X1104913Y829697D01*
X1103569D01*
X1102580Y828708D01*
X1100763D01*
X1099687Y829784D01*
X1098321D01*
X1096991Y829232D01*
X1094013Y826255D01*
X1088071Y823793D01*
X1084291D01*
X1083801Y823303D01*
X1081641D01*
X1081151Y823793D01*
X1078382D01*
X1072156Y826374D01*
X1068840D01*
X1068350Y825884D01*
X1066190D01*
X1065700Y826374D01*
X1060335D01*
X1059322Y825361D01*
X1057505D01*
X1056519Y826347D01*
X1053871D01*
X1052356Y824834D01*
X1049873Y823805D01*
X1048317D01*
X1046141Y824706D01*
X1043259D01*
X1042241Y823688D01*
G01X1301465Y903406D02*
X1281079D01*
X1266449Y888776D01*
Y877332D01*
X1240448Y851331D01*
X1236623D01*
X1232859Y847567D01*
X1229471Y839392D01*
X1227656Y837576D01*
X1217506Y833371D01*
X1210689D01*
X1207729Y832145D01*
X1195691Y829751D01*
X1192875Y828585D01*
X1182838D01*
X1181841Y827588D01*
X1179091D01*
X1177973Y828706D01*
X1176358D01*
X1175250Y827598D01*
X1173050D01*
X1171013Y829635D01*
X1167642Y831031D01*
X1162868D01*
X1161848Y832051D01*
X1160193D01*
X1159155Y831013D01*
X1155982D01*
X1150125Y825156D01*
X1137504D01*
X1131660Y827576D01*
X1119768D01*
X1118637Y828707D01*
X1117003D01*
X1115863Y827567D01*
X1113361D01*
X1111749Y829179D01*
X1109761Y830004D01*
X1106332D01*
X1105419Y830917D01*
X1103667D01*
X1103624Y830960D01*
X1103589D01*
X1102495Y832054D01*
X1100861D01*
X1099811Y831004D01*
X1098078D01*
X1096299Y830267D01*
X1093321Y827290D01*
X1090574Y826151D01*
X1087828Y825013D01*
X1078625D01*
X1072400Y827594D01*
X1060350D01*
X1059237Y828707D01*
X1057603D01*
X1056463Y827567D01*
X1053365D01*
X1051665Y825869D01*
X1049629Y825025D01*
X1048560D01*
X1046385Y825926D01*
X1043349D01*
X1042241Y827034D01*
G01X1301466Y911246D02*
X1277201D01*
X1257916Y891961D01*
Y880919D01*
X1239011Y862014D01*
X1233329D01*
X1227009Y855694D01*
X1225351D01*
X1223635Y853978D01*
X1221083D01*
X1215166Y848061D01*
X1210747D01*
X1207337Y844651D01*
X1194919D01*
X1191766Y841498D01*
X1187861D01*
X1187141Y842218D01*
Y844342D01*
X1186421Y845062D01*
X1185141D01*
X1184421Y844342D01*
Y842218D01*
X1183701Y841498D01*
X1180662D01*
X1180070Y842090D01*
X1175051D01*
X1172551Y844590D01*
X1162579D01*
X1161727Y845442D01*
X1160365D01*
X1159575Y844652D01*
X1154614D01*
X1153824Y845442D01*
X1151553D01*
X1148203Y842092D01*
X1107633D01*
X1105661Y844064D01*
X1103779D01*
X1102404Y845439D01*
X1100080D01*
X1096439Y841798D01*
X1091626D01*
X1089148Y844276D01*
X1077231D01*
X1074364Y841409D01*
X1061310D01*
X1060629Y842090D01*
X1056231D01*
X1055511Y842810D01*
Y844137D01*
X1054791Y844857D01*
X1053511D01*
X1052791Y844137D01*
Y842810D01*
X1052071Y842090D01*
X1050791D01*
X1050071Y842810D01*
Y844137D01*
X1049351Y844857D01*
X1048071D01*
X1047351Y844137D01*
Y842810D01*
X1046631Y842090D01*
X1043911D01*
X1042241Y840420D01*
G01X1303263Y1005247D02*
X1295665D01*
X1295563Y1005289D01*
X1295512Y1005268D01*
X1287268Y1008682D01*
X1286888Y1008840D01*
X1286759Y1008893D01*
X1256179D01*
X1256178Y1008892D01*
X1237856D01*
X1237855Y1008893D01*
X1077071D01*
X1076351Y1008173D01*
Y1006859D01*
X1075631Y1006139D01*
X1074351D01*
X1073631Y1006859D01*
Y1008173D01*
X1072911Y1008893D01*
X1071631D01*
X1070911Y1008173D01*
Y1006859D01*
X1070191Y1006139D01*
X1068911D01*
X1068191Y1006859D01*
Y1008173D01*
X1067471Y1008893D01*
X1066191D01*
X1065471Y1008173D01*
Y1006859D01*
X1064751Y1006139D01*
X1063471D01*
X1062751Y1006859D01*
Y1008173D01*
X1062031Y1008893D01*
X1058872D01*
X1055692Y1005713D01*
X1041492D01*
X1039058Y1003279D01*
Y965059D01*
X1041555Y962562D01*
X1043684D01*
X1044427Y961819D01*
Y959732D01*
X1042241Y957546D01*
G01X1304963Y972439D02*
X1299862D01*
X1293580Y966157D01*
X1265159D01*
X1262397Y968919D01*
X1249195D01*
X1239232Y958956D01*
X1232153D01*
X1229059Y955862D01*
X1213796D01*
X1213139Y956519D01*
X1208125D01*
X1207476Y955870D01*
X1196539D01*
X1193003Y952334D01*
X1189611D01*
X1185698Y956247D01*
X1180288D01*
X1179911Y955870D01*
X1173023D01*
X1172576Y955423D01*
X1162397D01*
X1161950Y955870D01*
X1144070D01*
X1142241Y957699D01*
X1137841D01*
X1135304Y955162D01*
X1133179D01*
X1132471Y955870D01*
X1129589D01*
X1129080Y956379D01*
X1120696D01*
X1120187Y955870D01*
X1116722D01*
X1116071Y955219D01*
X1108678D01*
X1108027Y955870D01*
X1076827D01*
X1073292Y952335D01*
X1071064D01*
X1068611Y954788D01*
Y956398D01*
X1064897Y965367D01*
X1064355Y965909D01*
X1055909D01*
X1053440Y968378D01*
X1049720Y969919D01*
X1047876D01*
X1043596Y968146D01*
X1042241Y967585D01*
G01X1304265Y1093767D02*
X1303486D01*
X1293769Y1097792D01*
X1237207Y1154354D01*
X1235438D01*
X1225445Y1164347D01*
X1216083D01*
X1214912Y1165518D01*
X1211970D01*
X1207843Y1169645D01*
X1206059D01*
X1199322Y1176382D01*
X1196784D01*
X1193212Y1179954D01*
Y1182036D01*
X1191589Y1183659D01*
X1189605D01*
X1186485Y1186779D01*
X1172353D01*
X1165712Y1193420D01*
Y1196321D01*
X1161869Y1200164D01*
X1158468D01*
X1155711Y1202921D01*
X1151911D01*
X1148473Y1206359D01*
X1146821D01*
X1140298Y1212882D01*
X1138218D01*
X1134202Y1216898D01*
X1131155D01*
X1129921Y1215664D01*
X1128435D01*
X1127201Y1216898D01*
X1125715D01*
X1124481Y1215664D01*
X1122995D01*
X1121761Y1216898D01*
X1107098D01*
X1103749Y1213549D01*
X1056235D01*
X1055515Y1212829D01*
Y1208961D01*
X1054795Y1208241D01*
X1053584D01*
X1052795Y1209030D01*
Y1212829D01*
X1052075Y1213549D01*
X1050795D01*
X1050075Y1212829D01*
Y1211080D01*
X1049355Y1210360D01*
X1048075D01*
X1047355Y1211080D01*
Y1212829D01*
X1046635Y1213549D01*
X1043915D01*
X1042241Y1215223D01*
G01X1304869Y1098175D02*
X1303810D01*
X1296645Y1101143D01*
X1241649Y1156139D01*
Y1159226D01*
X1238342Y1162533D01*
X1236118D01*
X1228908Y1169743D01*
X1224987D01*
X1224548Y1170182D01*
X1216556D01*
X1213822Y1172916D01*
X1211213D01*
X1207990Y1176139D01*
X1206353D01*
X1200884Y1181608D01*
Y1185174D01*
X1198665Y1187393D01*
X1195930D01*
X1192340Y1190983D01*
X1188287D01*
X1182452Y1196818D01*
X1173914D01*
X1170971Y1199761D01*
X1168025D01*
X1166212Y1201574D01*
Y1203422D01*
X1162777Y1206857D01*
X1157675D01*
X1154800Y1209732D01*
X1151568D01*
X1148198Y1213102D01*
X1147052D01*
X1140436Y1219718D01*
X1137622D01*
X1133749Y1223591D01*
X1128644D01*
X1127715Y1224520D01*
X1126014D01*
X1125085Y1223591D01*
X1115996D01*
X1115366Y1224221D01*
Y1225050D01*
X1114736Y1225680D01*
X1113266D01*
X1112636Y1225050D01*
Y1224221D01*
X1112006Y1223591D01*
X1107764D01*
X1106436Y1223041D01*
X1103637Y1220242D01*
X1077069D01*
X1073946Y1223365D01*
X1063777D01*
X1060654Y1220242D01*
X1055503D01*
X1054783Y1220962D01*
Y1225710D01*
X1054063Y1226430D01*
X1052783D01*
X1052063Y1225710D01*
Y1220962D01*
X1051343Y1220242D01*
X1043915D01*
X1042241Y1221916D01*
G01X1309064Y1110144D02*
X1307302D01*
X1248566Y1168880D01*
Y1176859D01*
X1238656Y1186769D01*
X1235063D01*
X1230712Y1191120D01*
X1224285D01*
X1223290Y1190125D01*
X1217417D01*
X1216167Y1191375D01*
Y1192265D01*
X1216764Y1192862D01*
Y1193752D01*
X1215723Y1194793D01*
X1214833D01*
X1214236Y1194196D01*
X1213346D01*
X1207923Y1199619D01*
X1206164D01*
X1199224Y1206559D01*
X1196149D01*
X1192927Y1209781D01*
X1190044D01*
X1182928Y1216897D01*
X1176242D01*
X1166203Y1226936D01*
X1157094D01*
X1153936Y1230094D01*
X1152178D01*
X1148218Y1234054D01*
X1143640D01*
X1141278Y1236416D01*
X1136800D01*
X1133478Y1239738D01*
X1130742D01*
X1123466Y1247014D01*
X1113545D01*
X1110199Y1243668D01*
X1098884D01*
X1095054Y1239838D01*
X1091837D01*
X1088709Y1236710D01*
X1077667D01*
X1074055Y1240322D01*
X1053130D01*
X1050682Y1242770D01*
X1046363D01*
X1042241Y1238648D01*
G01X1307065Y1104924D02*
X1304426D01*
X1301198Y1108152D01*
X1300505D01*
X1298977Y1109680D01*
Y1110373D01*
X1297450Y1111900D01*
X1296757D01*
X1295229Y1113428D01*
Y1114121D01*
X1293702Y1115648D01*
X1293009D01*
X1291481Y1117176D01*
Y1117869D01*
X1289954Y1119396D01*
X1289261D01*
X1287733Y1120924D01*
Y1121617D01*
X1286206Y1123144D01*
X1285513D01*
X1283985Y1124672D01*
Y1125365D01*
X1282458Y1126892D01*
X1281765D01*
X1280237Y1128420D01*
Y1129113D01*
X1278710Y1130640D01*
X1278017D01*
X1276489Y1132168D01*
Y1132861D01*
X1274962Y1134388D01*
X1274269D01*
X1272741Y1135916D01*
Y1136609D01*
X1271214Y1138136D01*
X1270521D01*
X1268993Y1139664D01*
Y1140357D01*
X1267466Y1141884D01*
X1266773D01*
X1265245Y1143412D01*
Y1144105D01*
X1263718Y1145632D01*
X1263025D01*
X1261497Y1147160D01*
Y1147853D01*
X1242158Y1167192D01*
Y1175198D01*
X1239642Y1177714D01*
X1238378D01*
X1237406Y1176742D01*
X1235850D01*
X1234680Y1177912D01*
X1230933D01*
X1228709Y1180136D01*
X1225364D01*
X1224345Y1181155D01*
X1222505D01*
X1221435Y1180085D01*
X1219464D01*
X1218482Y1181067D01*
X1216363D01*
X1213818Y1183611D01*
X1210960Y1184795D01*
X1206084Y1189671D01*
X1205272Y1191627D01*
X1198950Y1197949D01*
X1188731Y1202186D01*
X1184071Y1206846D01*
X1181572Y1207882D01*
X1179303D01*
X1178278Y1206857D01*
X1176305D01*
X1175371Y1207791D01*
X1173210D01*
X1170614Y1210386D01*
X1168142Y1211410D01*
X1165232Y1214321D01*
Y1216855D01*
X1164165Y1217922D01*
X1163161D01*
X1162136Y1216897D01*
X1160163D01*
X1159182Y1217878D01*
X1157691D01*
X1155670Y1219898D01*
X1151945Y1221441D01*
X1149358Y1224026D01*
X1129207Y1232373D01*
X1124847Y1236733D01*
X1121785Y1238001D01*
X1119663D01*
X1118637Y1236975D01*
X1116906D01*
X1115949Y1237932D01*
X1114648D01*
X1112083Y1235366D01*
X1110678Y1234784D01*
X1103666D01*
X1102510Y1233628D01*
X1100763D01*
X1099796Y1234595D01*
X1098318D01*
X1094552Y1230828D01*
X1089407Y1228698D01*
X1079003D01*
X1072563Y1231365D01*
X1060338D01*
X1059255Y1230282D01*
X1057618D01*
X1056586Y1231314D01*
X1054164D01*
X1052236Y1229385D01*
X1050819Y1228799D01*
X1048250D01*
X1046138Y1229673D01*
X1043305D01*
X1042241Y1228609D01*
G01X1307065Y1106144D02*
X1304932D01*
X1243378Y1167698D01*
Y1175704D01*
X1240148Y1178934D01*
X1238471D01*
X1237312Y1180093D01*
X1235834D01*
X1234873Y1179132D01*
X1231439D01*
X1229215Y1181356D01*
X1225870D01*
X1224851Y1182375D01*
X1222502D01*
X1221445Y1183432D01*
X1219561D01*
X1218416Y1182287D01*
X1216869D01*
X1214510Y1184646D01*
X1211652Y1185830D01*
X1207119Y1190363D01*
X1206309Y1192317D01*
X1199642Y1198984D01*
X1189423Y1203221D01*
X1184764Y1207880D01*
X1181815Y1209102D01*
X1179388D01*
X1178287Y1210203D01*
X1176403D01*
X1175211Y1209011D01*
X1173716D01*
X1171306Y1211421D01*
X1168834Y1212445D01*
X1166452Y1214827D01*
Y1217361D01*
X1164671Y1219142D01*
X1163246D01*
X1162144Y1220244D01*
X1160262D01*
X1159116Y1219098D01*
X1158197D01*
X1156362Y1220933D01*
X1152636Y1222476D01*
X1150049Y1225061D01*
X1129899Y1233408D01*
X1125540Y1237767D01*
X1122028Y1239221D01*
X1119668D01*
X1118567Y1240322D01*
X1117003D01*
X1115833Y1239152D01*
X1114142D01*
X1111391Y1236401D01*
X1110434Y1236004D01*
X1103535D01*
X1102565Y1236974D01*
X1100861D01*
X1099702Y1235815D01*
X1097812D01*
X1093860Y1231863D01*
X1089164Y1229918D01*
X1079246D01*
X1072806Y1232585D01*
X1060263D01*
X1059219Y1233629D01*
X1057675D01*
X1056580Y1232534D01*
X1053658D01*
X1051544Y1230420D01*
X1050576Y1230019D01*
X1048493D01*
X1046382Y1230893D01*
X1043303D01*
X1042241Y1231955D01*
G01X1306900Y1116197D02*
X1252922Y1170175D01*
Y1178484D01*
X1243009Y1188397D01*
Y1191588D01*
X1237779Y1196818D01*
X1235014D01*
X1231667Y1200165D01*
X1215627D01*
X1213809Y1201983D01*
X1211345Y1203004D01*
X1208160Y1206189D01*
X1206348D01*
X1200717Y1211820D01*
X1190043Y1216242D01*
Y1216275D01*
X1182728Y1223590D01*
X1176404D01*
X1173465Y1226529D01*
Y1229013D01*
X1165501Y1236977D01*
X1152135D01*
X1146226Y1242886D01*
X1137629D01*
X1133847Y1246668D01*
Y1248851D01*
X1130003Y1252695D01*
X1101977D01*
X1099650Y1250368D01*
X1085000D01*
X1081647Y1247015D01*
X1043915D01*
X1042241Y1245341D01*
G01X1300865Y891166D02*
X1287645D01*
X1279145Y882666D01*
Y872124D01*
X1247082Y840061D01*
X1242722Y829538D01*
X1238264Y825080D01*
X1237572D01*
X1227240Y814748D01*
X1224290D01*
X1223080Y815958D01*
X1217632D01*
X1213393Y811719D01*
X1208761D01*
X1207961Y812519D01*
X1204273D01*
X1203553Y811799D01*
Y809990D01*
X1202833Y809270D01*
X1201553D01*
X1200833Y809990D01*
Y811799D01*
X1200113Y812519D01*
X1197261D01*
X1193590Y808848D01*
X1190191D01*
X1183963Y802620D01*
X1178570D01*
X1177899Y801949D01*
X1176491D01*
X1175570Y802870D01*
X1173637D01*
X1171236Y805271D01*
X1148407D01*
X1147280Y806398D01*
X1138640D01*
X1135496Y803254D01*
X1120245D01*
X1118929Y801938D01*
X1116820D01*
X1115110Y803648D01*
X1112139D01*
X1109249Y806538D01*
X1107090D01*
X1105831Y805279D01*
X1085770D01*
X1085140Y804649D01*
Y803827D01*
X1084510Y803197D01*
X1083040D01*
X1082410Y803827D01*
Y804649D01*
X1081780Y805279D01*
X1074740D01*
X1073961Y804500D01*
X1068318D01*
X1067598Y803780D01*
Y802299D01*
X1066878Y801579D01*
X1065598D01*
X1064878Y802299D01*
Y803780D01*
X1064158Y804500D01*
X1060838D01*
X1058383Y806955D01*
G01X1300865Y895086D02*
X1285824D01*
X1275066Y884328D01*
Y873971D01*
X1242897Y841802D01*
X1239434Y833442D01*
X1237136Y831144D01*
X1236310D01*
X1233428Y828262D01*
Y826936D01*
X1229311Y822819D01*
X1216441D01*
X1212141Y818519D01*
X1209761D01*
X1208661Y819619D01*
X1203641D01*
X1202921Y818899D01*
Y817682D01*
X1202201Y816962D01*
X1200921D01*
X1200201Y817682D01*
Y818899D01*
X1199481Y819619D01*
X1196761D01*
X1193061Y815919D01*
X1189861D01*
X1182571Y808629D01*
X1174798D01*
X1171449Y811978D01*
X1136740D01*
X1133387Y808625D01*
X1130429D01*
X1129100Y809954D01*
X1127709D01*
X1126380Y808625D01*
X1124989D01*
X1123660Y809954D01*
X1122269D01*
X1120940Y808625D01*
X1114139D01*
X1110792Y811972D01*
X1096898D01*
X1095697Y810771D01*
X1094178D01*
X1092977Y811972D01*
X1090645D01*
X1090008Y812609D01*
X1084993D01*
X1084273Y811889D01*
Y811422D01*
X1083553Y810702D01*
X1082273D01*
X1081553Y811422D01*
Y811889D01*
X1080833Y812609D01*
X1078516D01*
X1077155Y811248D01*
X1070133D01*
X1069503Y811878D01*
Y812838D01*
X1068873Y813468D01*
X1067403D01*
X1066773Y812838D01*
Y811878D01*
X1066143Y811248D01*
X1060783D01*
X1058383Y813648D01*
G01X1301465Y905366D02*
X1279806D01*
X1264195Y889755D01*
Y877898D01*
X1242035Y855738D01*
X1236681D01*
X1235549Y854606D01*
Y853033D01*
X1229631Y847115D01*
Y846191D01*
X1228492Y845052D01*
X1224565D01*
X1223555Y844042D01*
Y843152D01*
X1225270Y841438D01*
Y840548D01*
X1224491Y839769D01*
X1223601D01*
X1221886Y841483D01*
X1220996D01*
X1218490Y838977D01*
X1211018D01*
X1208317Y836276D01*
X1204786D01*
X1204066Y835556D01*
Y834398D01*
X1203346Y833678D01*
X1202066D01*
X1201346Y834398D01*
Y835556D01*
X1200626Y836276D01*
X1197118D01*
X1192893Y832051D01*
X1172999D01*
X1169653Y835397D01*
X1153778D01*
X1148457Y830076D01*
X1138954D01*
X1136977Y832053D01*
X1107395D01*
X1104048Y835400D01*
X1100080D01*
X1097677Y832997D01*
X1090926D01*
X1089906Y831977D01*
X1085107D01*
X1084387Y831257D01*
Y828313D01*
X1083667Y827593D01*
X1082387D01*
X1081667Y828313D01*
Y831257D01*
X1080947Y831977D01*
X1076694D01*
X1076018Y832653D01*
X1060655D01*
X1058383Y830381D01*
G01X1301465Y900226D02*
X1282956D01*
X1269926Y887196D01*
Y876235D01*
X1238245Y844554D01*
X1236636D01*
X1234040Y841959D01*
X1230611Y833684D01*
X1227823Y830895D01*
X1225862D01*
X1223091Y828124D01*
X1217887D01*
X1217397Y828614D01*
X1215237D01*
X1214747Y828124D01*
X1211639D01*
X1208854Y825339D01*
X1204418D01*
X1203928Y825829D01*
X1201768D01*
X1201278Y825339D01*
X1190766D01*
X1182994Y817567D01*
X1179138D01*
X1178037Y818668D01*
X1176368D01*
X1175276Y817576D01*
X1174056D01*
X1170722Y820910D01*
X1162999D01*
X1161895Y822014D01*
X1160261D01*
X1159121Y820874D01*
X1156677D01*
X1154458Y818655D01*
X1151153D01*
X1149500Y820308D01*
X1135798D01*
X1133050Y817560D01*
X1119745D01*
X1118637Y818668D01*
X1117003D01*
X1115863Y817528D01*
X1113022D01*
X1109690Y820860D01*
X1103649D01*
X1102495Y822014D01*
X1100861D01*
X1099721Y820874D01*
X1098022D01*
X1095210Y823686D01*
X1093050D01*
X1089699Y822300D01*
X1087684Y820285D01*
X1076795D01*
X1073744Y823336D01*
X1061987D01*
X1061260Y822609D01*
X1059462D01*
X1058383Y823688D01*
G01X1301465Y899006D02*
X1283462D01*
X1271146Y886690D01*
Y875729D01*
X1238751Y843334D01*
X1237142D01*
X1235075Y841267D01*
X1231646Y832992D01*
X1228329Y829675D01*
X1226368D01*
X1223597Y826904D01*
X1212145D01*
X1209360Y824119D01*
X1191272D01*
X1183500Y816347D01*
X1179147D01*
X1178122Y815322D01*
X1176305D01*
X1175271Y816356D01*
X1173550D01*
X1170216Y819690D01*
X1163002D01*
X1161980Y818668D01*
X1160163D01*
X1159177Y819654D01*
X1157183D01*
X1154964Y817435D01*
X1150647D01*
X1148994Y819088D01*
X1136304D01*
X1133556Y816340D01*
X1119740D01*
X1118722Y815322D01*
X1116905D01*
X1115919Y816308D01*
X1112516D01*
X1109184Y819640D01*
X1103552D01*
X1102580Y818668D01*
X1100763D01*
X1099777Y819654D01*
X1097516D01*
X1094704Y822466D01*
X1093293D01*
X1090390Y821265D01*
X1088190Y819065D01*
X1076289D01*
X1073238Y822116D01*
X1062493D01*
X1061766Y821389D01*
X1059431D01*
X1058383Y820341D01*
G01X1301465Y909286D02*
X1278013D01*
X1260234Y891507D01*
Y879927D01*
X1240092Y859785D01*
X1234013D01*
X1229885Y855657D01*
Y853093D01*
X1228276Y851484D01*
X1224251D01*
X1220951Y848184D01*
X1218720D01*
X1216325Y845789D01*
X1211269D01*
X1207764Y842284D01*
X1196026D01*
X1193259Y839517D01*
X1187861D01*
X1187141Y838797D01*
Y837014D01*
X1186421Y836294D01*
X1185141D01*
X1184421Y837014D01*
Y838797D01*
X1183701Y839517D01*
X1180862D01*
X1180089Y838744D01*
X1174642D01*
X1171290Y842096D01*
X1151657D01*
X1147042Y837481D01*
X1144254D01*
X1143534Y838201D01*
Y839382D01*
X1142797Y840119D01*
X1141534D01*
X1140814Y839399D01*
Y838201D01*
X1140094Y837481D01*
X1134072D01*
X1131934Y839619D01*
X1120767D01*
X1119894Y838746D01*
X1107632D01*
X1104286Y842092D01*
X1100080D01*
X1097676Y839688D01*
X1092008D01*
X1090929Y838609D01*
X1085203D01*
X1084483Y839329D01*
Y841403D01*
X1083729Y842157D01*
X1082483D01*
X1081763Y841437D01*
Y839329D01*
X1081043Y838609D01*
X1076022D01*
X1075207Y839424D01*
X1069061D01*
X1068341Y838704D01*
Y837476D01*
X1067621Y836756D01*
X1066341D01*
X1065621Y837476D01*
Y838704D01*
X1064901Y839424D01*
X1060733D01*
X1058383Y837074D01*
G01X1303667Y971082D02*
X1300374D01*
X1294128Y964836D01*
X1264128D01*
X1262306Y966658D01*
X1249779D01*
X1239821Y956700D01*
X1233286D01*
X1229114Y952528D01*
X1223461D01*
X1223052Y952119D01*
X1210811D01*
X1209809Y953121D01*
X1205133D01*
X1204535Y952523D01*
X1196389D01*
X1194160Y950294D01*
X1187103D01*
X1185737Y951660D01*
X1180812D01*
X1179949Y952523D01*
X1172405D01*
X1171789Y953139D01*
X1165029D01*
X1164413Y952523D01*
X1161552D01*
X1161551Y952524D01*
X1144286D01*
X1142141Y954669D01*
X1137880D01*
X1135246Y952035D01*
X1128461D01*
X1127741Y952755D01*
Y953511D01*
X1127021Y954231D01*
X1125741D01*
X1125021Y953511D01*
Y952755D01*
X1124301Y952035D01*
X1121520D01*
X1121031Y952524D01*
X1112683D01*
X1112098Y953109D01*
X1105744D01*
X1105159Y952524D01*
X1099953D01*
X1098643Y951214D01*
X1091524D01*
X1090215Y952523D01*
X1087203D01*
X1086070Y953656D01*
X1084712D01*
X1084082Y953026D01*
Y951778D01*
X1083452Y951148D01*
X1081982D01*
X1081352Y951778D01*
Y953026D01*
X1080722Y953656D01*
X1078432D01*
X1074882Y950106D01*
X1070391D01*
X1066400Y954097D01*
Y956222D01*
X1064176Y958446D01*
X1063158D01*
X1062009Y957297D01*
X1060991D01*
X1060085Y958203D01*
Y959221D01*
X1061234Y960370D01*
Y961388D01*
X1058383Y964239D01*
G01X1304265Y1091428D02*
X1303849D01*
X1292216Y1096247D01*
X1236689Y1151774D01*
X1234539D01*
X1230438Y1155875D01*
X1227304D01*
X1223299Y1159880D01*
X1217650D01*
X1214013Y1163517D01*
X1211031D01*
X1207247Y1167301D01*
X1205571D01*
X1198589Y1174283D01*
X1195415D01*
X1191134Y1178564D01*
X1190116D01*
X1189734Y1178182D01*
X1188716D01*
X1187810Y1179088D01*
Y1180106D01*
X1188192Y1180488D01*
Y1181506D01*
X1186266Y1183432D01*
X1172800D01*
X1163648Y1192584D01*
Y1195183D01*
X1162013Y1196818D01*
X1158914D01*
X1155130Y1200602D01*
X1151344D01*
X1147857Y1204089D01*
X1145807D01*
X1139431Y1210465D01*
X1137485D01*
X1134399Y1213551D01*
X1107962D01*
X1104621Y1210210D01*
X1095374D01*
X1094632Y1209468D01*
Y1207933D01*
X1093912Y1207213D01*
X1092632D01*
X1091912Y1207933D01*
Y1209482D01*
X1091192Y1210202D01*
X1085881D01*
X1085161Y1209482D01*
Y1204959D01*
X1084441Y1204239D01*
X1083332D01*
X1082441Y1205130D01*
Y1209482D01*
X1081721Y1210202D01*
X1077605D01*
X1076975Y1209572D01*
Y1207448D01*
X1076345Y1206818D01*
X1074875D01*
X1074245Y1207448D01*
Y1209298D01*
X1073615Y1209928D01*
X1072145D01*
X1071515Y1209298D01*
Y1207448D01*
X1070885Y1206818D01*
X1069415D01*
X1068785Y1207448D01*
Y1209572D01*
X1068155Y1210202D01*
X1066685D01*
X1066055Y1209572D01*
Y1207448D01*
X1065425Y1206818D01*
X1063955D01*
X1063325Y1207448D01*
Y1209572D01*
X1062695Y1210202D01*
X1060058D01*
X1058383Y1211877D01*
G01X1304265Y1096148D02*
X1303129D01*
X1295644Y1099245D01*
X1239173Y1155716D01*
Y1158602D01*
X1237364Y1160411D01*
X1235266D01*
X1233536Y1162141D01*
Y1162186D01*
X1228616Y1167106D01*
X1225330D01*
X1224548Y1166324D01*
X1217144D01*
X1213042Y1170426D01*
X1210846D01*
X1207135Y1174137D01*
X1205571D01*
X1198145Y1181563D01*
X1196517D01*
X1195407Y1182673D01*
Y1184301D01*
X1193364Y1186344D01*
X1189898D01*
X1182771Y1193471D01*
X1175651D01*
X1175021Y1192841D01*
Y1189705D01*
X1174391Y1189075D01*
X1172989D01*
X1172291Y1189773D01*
Y1192841D01*
X1171661Y1193471D01*
X1171099D01*
X1170428Y1194142D01*
Y1195860D01*
X1168690Y1197598D01*
X1167334D01*
X1163540Y1201392D01*
Y1202748D01*
X1162777Y1203511D01*
X1158121D01*
X1154317Y1207315D01*
X1151130D01*
X1147607Y1210838D01*
X1146238D01*
X1139629Y1217447D01*
X1136623D01*
X1133826Y1220244D01*
X1128794D01*
X1128086Y1219536D01*
X1126064D01*
X1125356Y1220244D01*
X1115261D01*
X1114126Y1219109D01*
X1112531D01*
X1111396Y1220244D01*
X1107330D01*
X1103981Y1216895D01*
X1099584D01*
X1098415Y1218064D01*
X1095740D01*
X1094469Y1216793D01*
X1090539D01*
X1089149Y1218183D01*
X1085418D01*
X1084788Y1217553D01*
Y1216344D01*
X1084158Y1215714D01*
X1082688D01*
X1082058Y1216344D01*
Y1217553D01*
X1081428Y1218183D01*
X1077142D01*
X1074756Y1215797D01*
X1069544D01*
X1068824Y1216517D01*
Y1220685D01*
X1068104Y1221405D01*
X1066824D01*
X1066104Y1220685D01*
Y1216517D01*
X1065384Y1215797D01*
X1061156D01*
X1058383Y1218570D01*
G01X1304869Y1101562D02*
X1302020D01*
X1299696Y1102524D01*
X1298169Y1104051D01*
X1297476D01*
X1295948Y1105579D01*
Y1106272D01*
X1294421Y1107799D01*
X1293728D01*
X1292200Y1109327D01*
Y1110020D01*
X1290673Y1111547D01*
X1289980D01*
X1288452Y1113075D01*
Y1113768D01*
X1286925Y1115295D01*
X1286232D01*
X1284704Y1116823D01*
Y1117516D01*
X1283177Y1119043D01*
X1282484D01*
X1280956Y1120571D01*
Y1121264D01*
X1279429Y1122791D01*
X1278736D01*
X1277208Y1124319D01*
Y1125012D01*
X1275681Y1126539D01*
X1274988D01*
X1273460Y1128067D01*
Y1128760D01*
X1271933Y1130287D01*
X1271240D01*
X1269712Y1131815D01*
Y1132508D01*
X1268185Y1134035D01*
X1267492D01*
X1265964Y1135563D01*
Y1136256D01*
X1264437Y1137783D01*
X1263744D01*
X1262216Y1139311D01*
Y1140004D01*
X1260689Y1141531D01*
X1259996D01*
X1258468Y1143059D01*
Y1143752D01*
X1256941Y1145279D01*
X1256248D01*
X1254720Y1146807D01*
Y1147500D01*
X1244086Y1158135D01*
Y1160505D01*
X1236443Y1168148D01*
X1235146D01*
X1229522Y1173772D01*
X1226161D01*
X1224569Y1172180D01*
X1218634D01*
X1213154Y1177660D01*
X1211064D01*
X1207791Y1180933D01*
X1206763D01*
X1203587Y1184109D01*
Y1186148D01*
X1199636Y1190099D01*
X1198117D01*
X1193063Y1195153D01*
X1188755D01*
X1182718Y1201190D01*
X1179303D01*
X1178277Y1200164D01*
X1176306D01*
X1175324Y1201146D01*
X1173257D01*
X1170310Y1204093D01*
X1168479D01*
X1164980Y1207592D01*
X1164983Y1209933D01*
X1163687Y1211229D01*
X1163161D01*
X1162136Y1210204D01*
X1160163D01*
X1159141Y1211226D01*
X1156881D01*
X1154413Y1213694D01*
X1152400D01*
X1147164Y1218930D01*
X1145420D01*
X1140487Y1223862D01*
X1122518Y1231308D01*
X1119659D01*
X1118633Y1230282D01*
X1116906D01*
X1115924Y1231264D01*
X1114833D01*
X1110527Y1226958D01*
X1104869Y1224615D01*
X1103477D01*
X1102452Y1223590D01*
X1100859D01*
X1099792Y1224657D01*
X1099772D01*
X1099731Y1224698D01*
X1097328D01*
X1094895Y1222265D01*
X1090728D01*
X1088296Y1224697D01*
X1078791D01*
X1072473Y1227314D01*
X1062421D01*
X1061392Y1226285D01*
X1059405D01*
X1058383Y1225263D01*
G01X1307283Y1113685D02*
X1306640D01*
X1250962Y1169363D01*
Y1177648D01*
X1240699Y1187911D01*
Y1190923D01*
X1238150Y1193472D01*
X1234085D01*
X1230739Y1196818D01*
X1215849D01*
X1212237Y1200430D01*
X1211088D01*
X1207645Y1203873D01*
X1205766D01*
X1199547Y1210092D01*
X1188959Y1214480D01*
X1183196Y1220243D01*
X1175881D01*
X1169777Y1226347D01*
Y1227237D01*
X1170387Y1227847D01*
Y1228737D01*
X1169346Y1229778D01*
X1168456D01*
X1167720Y1229042D01*
X1166830D01*
X1162242Y1233630D01*
X1158580D01*
X1157950Y1233000D01*
Y1231873D01*
X1157320Y1231243D01*
X1155850D01*
X1155220Y1231873D01*
Y1233000D01*
X1154590Y1233630D01*
X1151484D01*
X1148932Y1236182D01*
X1146006D01*
X1141499Y1240689D01*
X1135924D01*
X1126035Y1250578D01*
X1113420D01*
X1109856Y1247014D01*
X1093328D01*
X1089175Y1242861D01*
X1085408D01*
X1084688Y1242141D01*
Y1239732D01*
X1083968Y1239012D01*
X1082688D01*
X1081968Y1239732D01*
Y1242141D01*
X1081248Y1242861D01*
X1075685D01*
X1074200Y1244346D01*
X1069852D01*
X1069132Y1243626D01*
Y1243002D01*
X1068412Y1242282D01*
X1067132D01*
X1066412Y1243002D01*
Y1243626D01*
X1065692Y1244346D01*
X1060734D01*
X1058383Y1241995D01*
G01X1309065Y1108184D02*
X1306464D01*
X1246588Y1168060D01*
Y1175760D01*
X1238912Y1183436D01*
X1234595D01*
X1229311Y1188720D01*
X1226854D01*
X1224912Y1186778D01*
X1216466D01*
X1209556Y1193688D01*
Y1195202D01*
X1207239Y1197519D01*
X1205011D01*
X1198120Y1204410D01*
X1194829D01*
X1191613Y1207626D01*
X1189025D01*
X1183101Y1213550D01*
X1173046D01*
X1171582Y1215014D01*
Y1215904D01*
X1172498Y1216820D01*
Y1217710D01*
X1171457Y1218751D01*
X1170567D01*
X1169651Y1217835D01*
X1168761D01*
X1163006Y1223590D01*
X1157436D01*
X1152934Y1228092D01*
X1149759D01*
X1143626Y1230632D01*
X1140209Y1234049D01*
X1135796D01*
X1132133Y1237712D01*
X1129788D01*
X1123833Y1243667D01*
X1113830D01*
X1110484Y1240321D01*
X1100322D01*
X1097831Y1237830D01*
X1092614D01*
X1089419Y1234635D01*
X1085443D01*
X1084723Y1233915D01*
Y1232621D01*
X1084003Y1231901D01*
X1082723D01*
X1082003Y1232621D01*
Y1233915D01*
X1081283Y1234635D01*
X1076170D01*
X1073186Y1237619D01*
X1069681D01*
X1068961Y1236899D01*
Y1235561D01*
X1068241Y1234841D01*
X1066961D01*
X1066241Y1235561D01*
Y1236899D01*
X1065521Y1237619D01*
X1060700D01*
X1058383Y1235302D01*
G01X1304869Y1102782D02*
X1302263D01*
X1300388Y1103559D01*
X1245306Y1158641D01*
Y1161011D01*
X1236949Y1169368D01*
X1235652D01*
X1230028Y1174992D01*
X1225655D01*
X1224063Y1173400D01*
X1219140D01*
X1213660Y1178880D01*
X1211570D01*
X1208297Y1182153D01*
X1207269D01*
X1204807Y1184615D01*
Y1186654D01*
X1200142Y1191319D01*
X1198623D01*
X1193569Y1196373D01*
X1189261D01*
X1183224Y1202410D01*
X1179388D01*
X1178287Y1203511D01*
X1176403D01*
X1175258Y1202366D01*
X1173763D01*
X1170816Y1205313D01*
X1168985D01*
X1166201Y1208097D01*
X1166204Y1210438D01*
X1164193Y1212449D01*
X1163246D01*
X1162144Y1213551D01*
X1160262D01*
X1159157Y1212446D01*
X1157387D01*
X1154919Y1214914D01*
X1152906D01*
X1147670Y1220150D01*
X1145926D01*
X1141179Y1224897D01*
X1122761Y1232528D01*
X1119650D01*
X1118549Y1233629D01*
X1117003D01*
X1115858Y1232484D01*
X1114326D01*
X1109835Y1227993D01*
X1104626Y1225835D01*
X1103482D01*
X1102381Y1226936D01*
X1100861D01*
X1099843Y1225918D01*
X1096822D01*
X1094389Y1223485D01*
X1091234D01*
X1088802Y1225917D01*
X1079034D01*
X1072716Y1228534D01*
X1061915D01*
X1060886Y1227505D01*
X1059487D01*
X1058383Y1228609D01*
G01X1308563Y1001526D02*
X1294540D01*
X1285981Y1005071D01*
X1237856D01*
X1237855Y1005072D01*
X1180228D01*
X1173215Y998059D01*
X1166866Y995554D01*
X1164071Y992759D01*
Y990179D01*
X1163231Y989339D01*
X1161566D01*
X1161561Y989334D01*
X1157956D01*
X1154605Y985983D01*
X1145380D01*
X1144660Y986703D01*
Y988255D01*
X1143940Y988975D01*
X1142660D01*
X1141940Y988255D01*
Y986703D01*
X1141220Y985983D01*
X1135224D01*
X1133939Y987268D01*
X1128484D01*
X1120511Y979295D01*
X1107142D01*
X1103795Y975948D01*
X1094040D01*
X1089711Y971619D01*
X1079875D01*
X1076211Y967955D01*
Y965162D01*
X1071941Y960892D01*
G01X1308563Y999556D02*
X1295654D01*
X1285868Y1003609D01*
X1275026D01*
X1273509Y1002980D01*
X1272629Y1002616D01*
X1256179D01*
X1256178Y1002615D01*
X1247150D01*
X1233279Y996870D01*
X1176918D01*
X1167534Y989994D01*
X1162940Y983375D01*
X1161734Y982642D01*
X1159381D01*
X1153241Y982345D01*
X1152051D01*
X1145771Y983641D01*
X1139921D01*
X1125131Y977514D01*
X1123565Y975948D01*
X1107776D01*
X1106804Y974976D01*
X1103694Y970132D01*
X1102535Y969255D01*
X1083650D01*
X1071941Y957546D01*
G01X1300865Y873217D02*
X1298536D01*
X1297231Y871912D01*
Y863876D01*
X1262927Y829572D01*
X1251678Y802412D01*
X1237693Y788427D01*
X1233610D01*
X1229602Y784419D01*
X1224411D01*
X1221411Y781419D01*
X1219061D01*
X1212386Y774744D01*
X1210857D01*
X1207711Y771598D01*
X1195290D01*
X1191255Y767563D01*
X1186223D01*
X1185307Y768479D01*
X1159001D01*
X1155662Y771818D01*
X1144472D01*
X1143752Y772538D01*
Y774473D01*
X1143032Y775193D01*
X1141742D01*
X1141022Y774473D01*
Y772538D01*
X1140302Y771818D01*
X1134426D01*
X1131825Y774419D01*
X1122701D01*
X1118613Y778507D01*
X1110349D01*
X1109903Y778061D01*
X1103764D01*
X1101641Y780184D01*
G01X1304600Y865009D02*
X1303284Y863693D01*
Y861612D01*
X1268323Y826651D01*
X1256894Y799062D01*
X1240180Y782348D01*
X1236288D01*
X1229859Y775919D01*
X1226411D01*
X1222911Y772419D01*
X1219911D01*
X1217911Y770419D01*
Y767418D01*
X1214077Y763584D01*
X1212218Y762935D01*
X1205915Y761788D01*
X1187420Y760365D01*
X1133511D01*
X1131401Y760639D01*
X1125035Y761825D01*
X1118860Y763672D01*
X1115712Y765070D01*
X1101641Y773491D01*
G01X1300865Y878386D02*
X1293987D01*
X1292084Y876483D01*
Y866052D01*
X1258041Y832009D01*
X1249821Y811993D01*
X1248294Y810466D01*
Y809773D01*
X1246766Y808245D01*
X1246073D01*
X1244546Y806718D01*
Y806025D01*
X1243018Y804497D01*
X1242325D01*
X1237389Y799561D01*
X1235753D01*
X1234082Y797890D01*
Y797197D01*
X1232554Y795668D01*
X1231861D01*
X1230334Y794141D01*
X1227702Y793051D01*
X1227436Y792409D01*
X1225440Y791583D01*
X1224800Y791848D01*
X1222805Y791022D01*
X1222540Y790381D01*
X1220543Y789554D01*
X1219903Y789819D01*
X1217908Y788993D01*
X1217643Y788352D01*
X1215646Y787525D01*
X1215006Y787790D01*
X1208997Y785301D01*
X1206837D01*
X1206347Y784811D01*
X1204187D01*
X1203697Y785301D01*
X1201537D01*
X1201047Y784811D01*
X1198887D01*
X1198397Y785301D01*
X1196237D01*
X1195747Y784811D01*
X1193587D01*
X1193097Y785301D01*
X1189166D01*
X1187482Y783618D01*
X1187481Y782925D01*
X1185953Y781397D01*
X1185260D01*
X1183370Y779509D01*
X1178962D01*
X1177961Y778508D01*
X1176381D01*
X1175299Y779590D01*
X1174335D01*
X1166340Y782902D01*
X1162842D01*
X1161794Y781854D01*
X1160269D01*
X1159217Y782906D01*
X1156706D01*
X1155778Y781978D01*
X1154850Y781049D01*
X1153592Y780529D01*
X1151880D01*
X1143377Y784052D01*
X1137166D01*
X1134454Y782929D01*
X1133171D01*
X1132047Y781805D01*
X1130622D01*
X1129537Y782890D01*
X1128275D01*
X1124691Y784375D01*
X1119947Y789119D01*
X1119533D01*
X1118961Y788547D01*
X1117045D01*
X1115983Y789609D01*
X1113479D01*
X1111824Y787954D01*
X1109528Y787004D01*
X1106633D01*
X1104487Y787893D01*
X1102657D01*
X1101641Y786877D01*
G01X1300865Y885486D02*
X1289998D01*
X1284825Y880313D01*
Y869328D01*
X1251746Y836249D01*
X1244332Y818348D01*
X1238926Y812942D01*
X1236326D01*
X1229603Y806219D01*
X1226161D01*
X1222937Y802995D01*
X1211937D01*
X1208561Y799619D01*
X1196561D01*
X1192185Y795243D01*
X1188885D01*
X1187499Y796629D01*
X1186155D01*
X1184769Y795243D01*
X1183425D01*
X1182039Y796629D01*
X1180695D01*
X1179309Y795243D01*
X1175092D01*
X1173877Y794028D01*
X1172362D01*
X1171147Y795243D01*
X1165203D01*
X1161856Y798590D01*
X1159958D01*
X1157261Y795893D01*
X1151785D01*
X1150711Y794819D01*
X1137645D01*
X1136873Y795591D01*
X1126988D01*
X1125660Y796919D01*
X1120681D01*
X1119014Y798586D01*
X1110132D01*
X1109412Y799306D01*
Y800996D01*
X1108692Y801716D01*
X1107402D01*
X1106682Y800996D01*
Y799306D01*
X1105962Y798586D01*
X1104418D01*
X1103692Y799312D01*
Y801558D01*
X1101641Y803609D01*
G01X1300865Y883526D02*
X1290810D01*
X1286785Y879501D01*
Y868286D01*
X1253342Y834843D01*
X1245794Y816622D01*
X1237638Y808466D01*
X1235258D01*
X1228411Y801619D01*
X1225061D01*
X1221861Y798419D01*
X1218241D01*
X1217521Y799139D01*
Y800315D01*
X1216801Y801035D01*
X1215521D01*
X1214801Y800315D01*
Y799139D01*
X1214081Y798419D01*
X1211361D01*
X1207761Y794819D01*
X1204512D01*
X1203792Y795539D01*
Y796825D01*
X1203072Y797545D01*
X1201792D01*
X1201072Y796825D01*
Y795539D01*
X1200352Y794819D01*
X1196161D01*
X1193239Y791897D01*
X1190459D01*
X1189180Y790618D01*
X1187729D01*
X1186450Y791897D01*
X1184999D01*
X1183720Y790618D01*
X1182269D01*
X1180990Y791897D01*
X1165731D01*
X1162385Y795243D01*
X1160353D01*
X1157005Y791895D01*
X1145149D01*
X1143932Y790678D01*
X1142419D01*
X1141202Y791895D01*
X1133904D01*
X1132727Y790718D01*
X1131174D01*
X1129997Y791895D01*
X1126885D01*
X1123540Y795240D01*
X1110691D01*
X1110061Y794610D01*
X1109254D01*
X1108534Y793890D01*
Y792815D01*
X1107814Y792095D01*
X1106524D01*
X1105804Y792815D01*
Y793890D01*
X1105084Y794610D01*
X1103947D01*
X1101641Y796916D01*
G01X1300865Y879606D02*
X1293481D01*
X1290864Y876989D01*
Y866558D01*
X1257005Y832699D01*
X1248785Y812683D01*
X1236883Y800781D01*
X1235247D01*
X1229642Y795176D01*
X1208754Y786521D01*
X1188660D01*
X1182864Y780729D01*
X1179019D01*
X1177894Y781854D01*
X1176355D01*
X1175311Y780810D01*
X1174578D01*
X1166583Y784122D01*
X1162822D01*
X1161744Y785200D01*
X1160317D01*
X1159243Y784126D01*
X1156200D01*
X1154158Y782084D01*
X1153349Y781749D01*
X1152123D01*
X1143620Y785272D01*
X1136923D01*
X1134211Y784149D01*
X1133157D01*
X1132056Y785250D01*
X1130629D01*
X1129489Y784110D01*
X1128518D01*
X1125383Y785410D01*
X1118894Y791899D01*
X1117009D01*
X1115939Y790829D01*
X1112973D01*
X1111133Y788989D01*
X1109285Y788224D01*
X1106876D01*
X1104730Y789113D01*
X1102751D01*
X1101641Y790223D01*
G01X1301466Y916926D02*
X1274847D01*
X1252186Y894265D01*
Y883609D01*
X1236597Y868020D01*
X1230827D01*
X1228722Y865915D01*
X1226301D01*
X1222467Y862081D01*
X1219455D01*
X1212571Y855197D01*
X1209271D01*
X1207104Y857364D01*
X1195498D01*
X1193610Y855476D01*
X1173355D01*
X1170012Y852133D01*
X1160353D01*
X1157020Y855466D01*
X1144407D01*
X1140888Y851947D01*
X1136602D01*
X1133440Y848785D01*
X1103313D01*
X1101641Y847113D01*
G01X1301466Y920846D02*
X1272656D01*
X1248224Y896414D01*
Y885991D01*
X1237125Y874892D01*
X1229434D01*
X1223457Y868915D01*
X1219598D01*
X1212647Y861964D01*
X1203561D01*
X1202841Y862684D01*
Y864439D01*
X1202121Y865159D01*
X1200841D01*
X1200121Y864439D01*
Y862684D01*
X1199401Y861964D01*
X1196681D01*
X1193129Y865516D01*
X1174261D01*
X1167571Y858826D01*
X1160029D01*
X1157201Y861654D01*
X1144846D01*
X1141463Y858271D01*
X1136156D01*
X1133363Y855478D01*
X1133320D01*
X1133318Y855476D01*
X1103311D01*
X1101641Y853806D01*
G01X1302266Y926008D02*
X1269693D01*
X1241796Y898111D01*
Y891732D01*
X1240011Y889947D01*
X1238322D01*
X1237326Y888951D01*
X1235755D01*
X1234718Y889988D01*
X1232692D01*
X1230156Y887451D01*
X1227421Y886318D01*
X1226491Y885388D01*
X1225473Y883483D01*
X1225675Y882820D01*
X1224656Y880914D01*
X1223993Y880713D01*
X1222418Y877766D01*
X1219683Y876635D01*
X1213161D01*
X1207445Y874267D01*
X1204123D01*
X1203633Y873777D01*
X1201473D01*
X1200983Y874267D01*
X1198823D01*
X1198333Y873777D01*
X1196173D01*
X1195683Y874267D01*
X1193523D01*
X1191257Y876533D01*
X1188235D01*
X1187745Y876043D01*
X1185585D01*
X1185095Y876533D01*
X1179184D01*
X1178198Y875547D01*
X1176165D01*
X1175193Y876519D01*
X1174002D01*
X1170803Y873318D01*
X1168987D01*
X1168497Y872828D01*
X1166337D01*
X1165847Y873318D01*
X1163093D01*
X1161981Y872206D01*
X1160098D01*
X1159051Y873253D01*
X1157692D01*
X1156495Y872055D01*
X1153811Y870944D01*
X1151550D01*
X1148353Y872268D01*
X1146503D01*
X1144546Y871456D01*
X1143019Y869929D01*
X1143020Y869236D01*
X1141491Y867707D01*
X1140798D01*
X1139557Y866465D01*
X1136799Y865322D01*
X1136534Y864681D01*
X1134538Y863854D01*
X1133898Y864119D01*
X1131880Y863283D01*
X1129720D01*
X1129230Y862793D01*
X1127070D01*
X1126580Y863283D01*
X1119799D01*
X1118694Y862178D01*
X1116789D01*
X1115753Y863214D01*
X1114494D01*
X1112024Y860744D01*
X1110292D01*
X1109802Y860254D01*
X1107642D01*
X1107152Y860744D01*
X1105705D01*
X1103782Y861540D01*
X1102682D01*
X1101641Y860499D01*
G01X1302266Y927228D02*
X1269187D01*
X1240576Y898617D01*
Y892238D01*
X1239505Y891167D01*
X1238454D01*
X1237336Y892285D01*
X1235735D01*
X1234658Y891208D01*
X1232186D01*
X1229464Y888486D01*
X1226729Y887353D01*
X1225501Y886125D01*
X1221547Y878727D01*
X1219440Y877855D01*
X1212918D01*
X1207202Y875487D01*
X1194029D01*
X1191763Y877753D01*
X1179287D01*
X1178125Y878915D01*
X1176345D01*
X1175169Y877739D01*
X1173496D01*
X1170297Y874538D01*
X1163094D01*
X1162067Y875565D01*
X1160119D01*
X1159027Y874473D01*
X1157186D01*
X1155803Y873090D01*
X1153568Y872164D01*
X1151793D01*
X1148596Y873488D01*
X1146259D01*
X1143854Y872491D01*
X1138865Y867500D01*
X1131637Y864503D01*
X1119792D01*
X1118774Y865521D01*
X1116816D01*
X1115729Y864434D01*
X1113988D01*
X1111518Y861964D01*
X1105948D01*
X1104025Y862760D01*
X1102726D01*
X1101641Y863845D01*
G01X1303266Y940162D02*
X1261437D01*
X1239735Y918460D01*
X1234953D01*
X1228357Y911864D01*
X1226330D01*
X1223488Y909022D01*
X1213974D01*
X1210171Y905219D01*
X1196412D01*
X1193521Y902328D01*
X1173920D01*
X1167227Y895635D01*
X1146187D01*
X1145092Y894540D01*
X1137766D01*
X1132991Y889765D01*
X1130474D01*
X1128173Y887464D01*
X1125636D01*
X1123768Y885596D01*
X1103313D01*
X1101641Y883924D01*
G01X1302266Y935068D02*
X1264511D01*
X1238479Y909036D01*
X1234612D01*
X1227905Y902329D01*
X1218842D01*
X1218212Y901699D01*
Y900389D01*
X1215987Y898164D01*
X1208888D01*
X1205888Y895164D01*
X1201708D01*
X1200827Y896045D01*
X1198988D01*
X1198107Y895164D01*
X1195387D01*
X1192512Y892289D01*
X1187879D01*
X1187159Y893009D01*
Y894128D01*
X1186439Y894848D01*
X1185159D01*
X1184439Y894128D01*
Y893009D01*
X1183719Y892289D01*
X1173383D01*
X1170037Y888943D01*
X1150486D01*
X1147333Y885790D01*
X1145346D01*
X1144626Y885070D01*
Y883841D01*
X1143906Y883121D01*
X1142626D01*
X1141906Y883841D01*
Y885070D01*
X1141186Y885790D01*
X1138146D01*
X1134674Y882318D01*
X1128779D01*
X1127976Y881515D01*
Y880625D01*
X1129026Y879576D01*
Y878686D01*
X1128247Y877907D01*
X1127357D01*
X1126307Y878956D01*
X1125417D01*
X1124488Y878027D01*
X1121419D01*
X1120541Y878905D01*
X1110195D01*
X1109475Y879625D01*
Y881204D01*
X1108755Y881924D01*
X1107475D01*
X1106755Y881204D01*
Y879625D01*
X1106035Y878905D01*
X1103315D01*
X1101641Y877231D01*
G01X1302266Y931148D02*
X1266135D01*
X1237327Y902340D01*
X1234295D01*
X1232565Y900610D01*
Y898817D01*
X1229758Y896010D01*
X1226832D01*
X1223439Y892617D01*
Y890194D01*
X1222188Y888943D01*
X1208567D01*
X1205482Y885858D01*
X1197149D01*
X1195955Y884664D01*
X1180693D01*
X1179761Y885596D01*
X1173137D01*
X1169791Y882250D01*
X1157188D01*
X1153841Y878903D01*
X1143417D01*
X1139240Y874726D01*
X1137738D01*
X1134276Y871264D01*
X1121466D01*
X1120519Y872211D01*
X1114903D01*
X1114183Y871491D01*
Y867224D01*
X1113463Y866504D01*
X1112183D01*
X1111463Y867224D01*
Y871491D01*
X1110743Y872211D01*
X1107474D01*
X1106754Y872931D01*
Y875186D01*
X1106034Y875906D01*
X1104754D01*
X1104034Y875186D01*
Y872931D01*
X1101641Y870538D01*
G01X1303266Y944125D02*
X1259710D01*
Y944114D01*
X1240814Y925218D01*
X1235187D01*
X1228761Y918792D01*
X1226292D01*
X1223215Y915715D01*
X1211303D01*
X1207607Y912019D01*
X1195771D01*
X1192773Y909021D01*
X1167544D01*
X1164199Y905676D01*
X1156556D01*
X1153212Y902332D01*
X1143482D01*
X1140045Y898895D01*
X1135967D01*
X1134063Y896991D01*
X1131207D01*
X1126503Y892287D01*
X1115631D01*
X1114911Y893007D01*
Y893957D01*
X1114191Y894677D01*
X1112911D01*
X1112191Y893957D01*
Y893007D01*
X1111471Y892287D01*
X1110191D01*
X1109471Y893007D01*
Y893957D01*
X1108751Y894677D01*
X1107471D01*
X1106751Y893957D01*
Y893007D01*
X1106031Y892287D01*
X1103311D01*
X1101641Y890617D01*
G01X1303266Y949318D02*
X1257304D01*
X1240447Y932461D01*
X1234024D01*
X1230896Y929333D01*
X1226827D01*
X1221037Y926929D01*
X1218877D01*
X1218387Y926439D01*
X1216227D01*
X1215737Y926929D01*
X1211952D01*
X1208020Y922997D01*
X1205860D01*
X1205370Y922507D01*
X1203210D01*
X1202720Y922997D01*
X1200560D01*
X1200070Y922507D01*
X1197910D01*
X1197420Y922997D01*
X1195215D01*
X1192344Y920126D01*
X1190184D01*
X1189694Y919636D01*
X1187534D01*
X1187044Y920126D01*
X1184884D01*
X1184394Y919636D01*
X1182234D01*
X1181744Y920126D01*
X1179343D01*
X1178279Y919062D01*
X1176304D01*
X1175303Y920063D01*
X1174062D01*
X1170773Y916774D01*
X1169057D01*
X1168567Y916284D01*
X1166407D01*
X1165917Y916774D01*
X1163085D01*
X1162027Y915716D01*
X1160052D01*
X1159051Y916717D01*
X1155892D01*
X1154365Y915190D01*
Y914497D01*
X1152837Y912969D01*
X1152144D01*
X1151133Y911957D01*
X1149138Y911130D01*
X1148873Y910489D01*
X1146877Y909662D01*
X1146236Y909927D01*
X1144112Y909047D01*
X1137336D01*
X1133986Y905697D01*
X1129196D01*
X1127669Y904170D01*
Y903477D01*
X1126141Y901949D01*
X1125448D01*
X1123507Y900008D01*
X1119903D01*
X1118878Y898983D01*
X1116905D01*
X1115903Y899985D01*
X1114012D01*
X1112379Y898352D01*
X1109890Y897321D01*
X1106967D01*
X1104535Y898328D01*
X1102659D01*
X1101641Y897310D01*
G01X1303266Y950538D02*
X1256798D01*
X1239941Y933681D01*
X1233518D01*
X1230390Y930553D01*
X1226583D01*
X1220793Y928149D01*
X1211446D01*
X1207514Y924217D01*
X1194709D01*
X1191838Y921346D01*
X1179348D01*
X1178286Y922408D01*
X1176404D01*
X1175279Y921283D01*
X1173556D01*
X1170267Y917994D01*
X1163102D01*
X1162034Y919062D01*
X1160152D01*
X1159027Y917937D01*
X1155386D01*
X1150441Y912992D01*
X1143869Y910267D01*
X1136830D01*
X1133480Y906917D01*
X1128690D01*
X1123001Y901228D01*
X1119988D01*
X1118887Y902329D01*
X1117003D01*
X1115879Y901205D01*
X1113506D01*
X1111687Y899386D01*
X1109647Y898541D01*
X1107210D01*
X1104779Y899548D01*
X1102749D01*
X1101641Y900656D01*
G01X1303266Y962459D02*
X1300777D01*
X1296752Y958434D01*
X1253126D01*
X1241010Y946318D01*
X1234772D01*
X1230542Y942088D01*
X1225327D01*
X1222377Y939138D01*
X1206800D01*
X1203080Y935418D01*
X1184014D01*
X1180291Y939141D01*
X1172869D01*
X1166176Y932448D01*
X1138334D01*
X1133691Y927805D01*
Y922374D01*
X1126155Y914838D01*
X1121420D01*
X1120542Y915716D01*
X1103757D01*
X1102083Y914042D01*
X1101641D01*
G01X1303266Y958417D02*
X1302280D01*
X1298321Y954458D01*
X1254961D01*
X1239876Y939373D01*
X1233500D01*
X1228646Y934519D01*
X1209987D01*
X1206785Y931317D01*
X1195270D01*
X1191926Y927973D01*
X1180884D01*
X1179756Y929101D01*
X1172393D01*
X1169047Y925755D01*
X1149424D01*
X1142094Y918425D01*
X1138777D01*
X1133261Y912909D01*
X1130231D01*
X1128205Y910883D01*
X1125961D01*
X1124101Y909023D01*
X1115635D01*
X1114915Y909743D01*
Y911360D01*
X1114195Y912080D01*
X1112915D01*
X1112195Y911360D01*
Y909743D01*
X1111475Y909023D01*
X1110195D01*
X1109475Y909743D01*
Y911360D01*
X1108755Y912080D01*
X1107475D01*
X1106755Y911360D01*
Y909743D01*
X1106035Y909023D01*
X1103315D01*
X1101641Y907349D01*
G01X1308563Y997571D02*
X1296880D01*
X1285523Y1002275D01*
X1277333D01*
X1276497Y1001928D01*
X1276496D01*
X1272936Y1000453D01*
X1247198D01*
X1229911Y993294D01*
X1228607Y991987D01*
X1227715D01*
X1224815Y994887D01*
X1202149D01*
X1199691Y992429D01*
X1195411D01*
X1194121Y993719D01*
X1181291D01*
X1180011Y992439D01*
Y990875D01*
X1178471Y989335D01*
X1171937D01*
X1170711Y988109D01*
Y986819D01*
X1163187Y979295D01*
X1160741D01*
X1160738Y979298D01*
X1158119D01*
X1157917Y979500D01*
X1150708D01*
X1150130Y978922D01*
X1144611D01*
X1143891Y979642D01*
Y980961D01*
X1143171Y981681D01*
X1141891D01*
X1141171Y980961D01*
Y979642D01*
X1140451Y978922D01*
X1135303D01*
X1131701Y975320D01*
X1127854D01*
X1125448Y972914D01*
Y968521D01*
X1122835Y965908D01*
X1115215D01*
X1114495Y966628D01*
Y970063D01*
X1113775Y970783D01*
X1112495D01*
X1111775Y970063D01*
Y966628D01*
X1111055Y965908D01*
X1106657D01*
X1101641Y960892D01*
G01X1308563Y995605D02*
X1297763D01*
X1284959Y1000908D01*
X1279189D01*
X1277926Y1000385D01*
X1277903Y1000376D01*
X1273206Y998430D01*
X1247456D01*
X1232408Y992197D01*
X1230062Y989851D01*
X1226393D01*
X1223442Y992802D01*
X1203464D01*
X1200311Y989649D01*
X1197031D01*
X1196523Y989571D01*
X1192391Y988939D01*
X1179031Y985989D01*
X1176676D01*
X1175126Y985059D01*
X1170110Y979603D01*
X1161934Y975949D01*
X1158731D01*
X1151678Y975651D01*
X1147781Y976824D01*
X1144695D01*
X1143975Y976104D01*
Y973796D01*
X1143255Y973076D01*
X1141975D01*
X1141255Y973796D01*
Y976104D01*
X1140535Y976824D01*
X1137522D01*
X1133918Y973220D01*
X1129012D01*
X1127812Y972020D01*
Y963995D01*
X1126379Y962562D01*
X1115095D01*
X1114465Y961932D01*
Y959744D01*
X1113745Y959024D01*
X1112170D01*
X1111540Y959654D01*
Y962450D01*
X1110910Y963080D01*
X1107175D01*
X1101641Y957546D01*
G01X1375404Y999684D02*
X1372629Y1001286D01*
X1372628D01*
X1372609Y1001297D01*
G02X1371703Y1002888I944J1591D01*
G01Y1002941D01*
G03X1370778Y1004491I-1850J-53D01*
G02X1369854Y1006055I926J1602D01*
G01Y1006093D01*
G03X1368970Y1007670I-1849J0D01*
G01X1368928Y1007695D01*
X1368909Y1007706D01*
G02X1368003Y1009297I944J1591D01*
G03X1367097Y1010888I-1850J0D01*
G01X1367078Y1010899D01*
G02X1366154Y1012444I925J1602D01*
G01Y1012501D01*
G03X1365248Y1014092I-1850J0D01*
G01X1365191Y1014125D01*
G03X1363378Y1014103I-887J-1624D01*
G02X1361528I-925J1602D01*
G03X1359678I-925J-1602D01*
G01X1359640Y1014081D01*
G02X1357829Y1014103I-886J1624D01*
G01X1357791Y1014125D01*
G03X1355978Y1014103I-887J-1624D01*
G02X1354128I-925J1602D01*
G01X1354075Y1014134D01*
G03X1352278Y1014103I-871J-1633D01*
G02X1350428I-925J1602D01*
G01X1350375Y1014134D01*
G03X1348578Y1014103I-871J-1633D01*
G02X1346728I-925J1602D01*
G01X1346675Y1014134D01*
G03X1344878Y1014103I-871J-1633D01*
G02X1343028I-925J1602D01*
G03X1341178I-925J-1602D01*
G01X1341140Y1014081D01*
G02X1339329Y1014103I-886J1624D01*
G01X1339291Y1014125D01*
G03X1337478Y1014103I-887J-1624D01*
G02X1335628I-925J1602D01*
G03X1333778I-925J-1602D01*
G01X1333725Y1014072D01*
G02X1331928Y1014103I-871J1633D01*
G03X1330078I-925J-1602D01*
G02X1328228I-925J1602D01*
G03X1326378I-925J-1602D01*
G02X1324528I-925J1602D01*
G03X1322678I-925J-1602D01*
G02X1320926Y1014050I-925J1602D01*
G01X1320834Y1014103D01*
X1320694Y1014184D01*
G03X1318984Y1014103I-777J-1683D01*
G02X1317270Y1014025I-932J1602D01*
G01X1317135Y1014103D01*
X1316995Y1014184D01*
G03X1315285Y1014103I-777J-1683D01*
G02X1313581Y1014020I-932J1602D01*
G01X1313436Y1014103D01*
X1313337Y1014160D01*
G03X1311593Y1014103I-819J-1659D01*
G02X1309782Y1014081I-925J1602D01*
G01X1309744Y1014103D01*
G03X1307894I-925J-1602D01*
G01X1306586D01*
X1305793Y1014896D01*
X1294302D01*
X1281918Y1020025D01*
X1237856D01*
X1237855Y1020026D01*
X1214653D01*
X1213086Y1021593D01*
X1181540D01*
X1179912Y1023221D01*
Y1025120D01*
X1178887Y1026145D01*
X1154107D01*
X1149955Y1030297D01*
X1139391D01*
X1134419Y1035269D01*
X1128719D01*
X1120147Y1043841D01*
Y1051907D01*
X1119137Y1052917D01*
X1113786D01*
X1105417Y1061286D01*
X1101641D01*
G01X1303263Y1022676D02*
X1295490D01*
X1283250Y1027746D01*
X1242185D01*
X1239708Y1030223D01*
X1233607D01*
X1232977Y1030853D01*
Y1032058D01*
X1232347Y1032688D01*
X1230877D01*
X1230247Y1032058D01*
Y1030853D01*
X1229617Y1030223D01*
X1228394D01*
X1224755Y1033862D01*
X1219011D01*
X1213211Y1039662D01*
X1210911D01*
X1208661Y1037412D01*
X1194713D01*
X1192594Y1039531D01*
X1188159D01*
X1187117Y1038489D01*
X1185529D01*
X1184487Y1039531D01*
X1166449D01*
X1163103Y1042877D01*
X1158003D01*
X1154259Y1046621D01*
X1151063D01*
X1150261Y1045819D01*
X1146756D01*
X1142461Y1050114D01*
Y1053819D01*
X1139261Y1057019D01*
X1136861D01*
X1133561Y1060319D01*
X1129961D01*
X1123971Y1066309D01*
X1113788D01*
X1105425Y1074672D01*
X1101641D01*
G01X1303263Y1018637D02*
X1294993D01*
X1282587Y1023775D01*
X1225225D01*
X1222101Y1026899D01*
X1212131D01*
X1209542Y1029488D01*
X1204853D01*
X1204223Y1028858D01*
Y1027968D01*
X1203593Y1027338D01*
X1202123D01*
X1201493Y1027968D01*
Y1028858D01*
X1200863Y1029488D01*
X1180592D01*
X1179611Y1030469D01*
Y1031758D01*
X1178531Y1032838D01*
X1165741D01*
X1162395Y1036184D01*
X1149800D01*
X1142724Y1043260D01*
X1135612D01*
X1125699Y1053173D01*
Y1057428D01*
X1123511Y1059616D01*
X1113711D01*
X1105348Y1067979D01*
X1101641D01*
G01X1301568Y1033061D02*
X1297295D01*
X1284882Y1038202D01*
X1262278D01*
X1240706Y1047137D01*
X1237140Y1050703D01*
X1234477D01*
X1228689Y1056491D01*
X1226001D01*
X1223451Y1053941D01*
X1219011D01*
X1216693Y1056259D01*
X1196259D01*
X1192910Y1059608D01*
X1174103D01*
X1164061Y1069650D01*
X1154429D01*
X1153598Y1068819D01*
X1151161D01*
X1149661Y1070319D01*
X1145861D01*
X1139181Y1076999D01*
X1134981D01*
X1131761Y1080219D01*
X1127861D01*
X1125044Y1083036D01*
X1115893D01*
X1114717Y1084212D01*
Y1086259D01*
X1114217Y1086759D01*
X1111298D01*
X1107978Y1088134D01*
X1107038Y1087744D01*
X1106434Y1086288D01*
X1105494Y1085898D01*
X1104310Y1086389D01*
X1103920Y1087329D01*
X1104524Y1088785D01*
X1104134Y1089725D01*
X1102743Y1090302D01*
X1101641Y1091404D01*
G01X1301567Y1026662D02*
X1296116D01*
X1283821Y1031754D01*
X1251424D01*
X1233243Y1039269D01*
X1230213Y1042300D01*
X1228761Y1042899D01*
X1225589D01*
X1222207Y1041499D01*
X1219694D01*
X1216554Y1042799D01*
X1212955Y1046399D01*
X1211563D01*
X1207727Y1044809D01*
X1197561D01*
X1191616Y1047271D01*
X1179334D01*
X1178294Y1046231D01*
X1177781Y1046230D01*
X1176831D01*
X1176830Y1046231D01*
X1176282D01*
X1175280Y1047233D01*
X1172148D01*
X1168809Y1050572D01*
X1163146D01*
X1162152Y1049578D01*
X1161572D01*
X1161571Y1049577D01*
X1160731D01*
X1160730Y1049578D01*
X1160140D01*
X1159182Y1050536D01*
X1157257D01*
X1146972Y1057409D01*
X1141149Y1063231D01*
X1129883Y1067898D01*
X1124864Y1072916D01*
X1121937Y1074129D01*
X1119871D01*
X1118744Y1073002D01*
X1116877D01*
X1115890Y1073989D01*
X1113876D01*
X1105446Y1082419D01*
X1102695D01*
X1101641Y1081365D01*
G01X1301567Y1027882D02*
X1296359D01*
X1284064Y1032974D01*
X1256967D01*
X1256477Y1033464D01*
X1254317D01*
X1253827Y1032974D01*
X1251667D01*
X1249671Y1033799D01*
X1249406Y1034440D01*
X1247408Y1035265D01*
X1246768Y1034999D01*
X1244772Y1035824D01*
X1244507Y1036465D01*
X1242509Y1037290D01*
X1241869Y1037024D01*
X1239873Y1037849D01*
X1239608Y1038490D01*
X1237610Y1039315D01*
X1236970Y1039049D01*
X1233934Y1040304D01*
X1230904Y1043335D01*
X1229003Y1044119D01*
X1225344D01*
X1221964Y1042719D01*
X1219937D01*
X1217246Y1043834D01*
X1213461Y1047619D01*
X1211320D01*
X1207484Y1046029D01*
X1204486D01*
X1203996Y1046519D01*
X1201836D01*
X1201346Y1046029D01*
X1197804D01*
X1191859Y1048491D01*
X1189699D01*
X1189209Y1048981D01*
X1187049D01*
X1186559Y1048491D01*
X1179320D01*
X1178236Y1049575D01*
X1176440D01*
X1175318Y1048453D01*
X1172654D01*
X1169315Y1051792D01*
X1163224D01*
X1162094Y1052922D01*
X1160298D01*
X1159176Y1051800D01*
X1159144D01*
X1159100Y1051756D01*
X1157628D01*
X1155833Y1052956D01*
X1155697Y1053635D01*
X1153901Y1054836D01*
X1153221Y1054701D01*
X1147750Y1058357D01*
X1145589Y1060518D01*
Y1061211D01*
X1144061Y1062739D01*
X1143368D01*
X1141841Y1064266D01*
X1135472Y1066904D01*
X1135207Y1067545D01*
X1133210Y1068372D01*
X1132570Y1068107D01*
X1130575Y1068933D01*
X1125556Y1073951D01*
X1122180Y1075349D01*
X1119832D01*
X1118833Y1076348D01*
X1116889D01*
X1115750Y1075209D01*
X1114382D01*
X1105952Y1083639D01*
X1102713D01*
X1101641Y1084711D01*
G01X1301568Y1037034D02*
X1297949D01*
X1285465Y1042205D01*
X1264323D01*
X1242353Y1051303D01*
X1237385Y1056271D01*
X1235698D01*
X1228785Y1063184D01*
X1226377D01*
X1222816Y1059623D01*
X1219327D01*
X1212516Y1066434D01*
X1210911D01*
X1208661Y1064184D01*
X1194713D01*
X1192594Y1066303D01*
X1175861D01*
X1171917Y1070247D01*
Y1074155D01*
X1169728Y1076344D01*
X1146256D01*
X1140612Y1081988D01*
X1136830D01*
X1133104Y1085714D01*
X1129315D01*
X1125311Y1089718D01*
X1113649D01*
X1105270Y1098097D01*
X1101641D01*
G01X1303068Y1048574D02*
X1298964D01*
X1287181Y1053454D01*
X1269572D01*
X1255469Y1059296D01*
X1237542Y1077223D01*
X1234191D01*
X1228544Y1082870D01*
X1195806D01*
X1192673Y1086003D01*
X1190244D01*
X1183169Y1093078D01*
X1173422D01*
X1170076Y1096424D01*
X1158604D01*
X1156505Y1098523D01*
X1152407D01*
X1148211Y1102719D01*
X1146329D01*
X1141707Y1107341D01*
X1135781D01*
X1129966Y1113156D01*
X1118887D01*
X1118886Y1113157D01*
X1117004D01*
X1117003Y1113156D01*
X1110215D01*
X1109495Y1113876D01*
Y1115310D01*
X1108775Y1116030D01*
X1107495D01*
X1106775Y1115310D01*
Y1113876D01*
X1106055Y1113156D01*
X1103314D01*
X1101641Y1111483D01*
G01X1303068Y1044222D02*
X1299011D01*
X1286428Y1049434D01*
X1266245D01*
X1253050Y1054900D01*
X1237200Y1070750D01*
X1234023D01*
X1232354Y1072419D01*
X1226541D01*
X1223113Y1075847D01*
X1210048D01*
X1207434Y1078461D01*
X1194109D01*
X1191523Y1081047D01*
X1185528D01*
X1180190Y1086385D01*
X1173422D01*
X1170076Y1089731D01*
X1152907D01*
X1142377Y1100261D01*
X1136569D01*
X1133511Y1103319D01*
X1122869D01*
X1119725Y1106463D01*
X1115634D01*
X1114914Y1107183D01*
Y1108198D01*
X1114194Y1108918D01*
X1112914D01*
X1112194Y1108198D01*
Y1107183D01*
X1111474Y1106463D01*
X1110194D01*
X1109474Y1107183D01*
Y1108198D01*
X1108754Y1108918D01*
X1107474D01*
X1106754Y1108198D01*
Y1107183D01*
X1106034Y1106463D01*
X1103314D01*
X1101641Y1104790D01*
G01X1303068Y1059356D02*
X1300002D01*
X1260883Y1075550D01*
X1240257Y1096176D01*
X1234937D01*
X1230612Y1100501D01*
X1224325D01*
X1221708Y1103118D01*
X1204120D01*
X1200239Y1106999D01*
X1197431D01*
X1191273Y1113157D01*
X1175212D01*
X1171866Y1116503D01*
X1158970D01*
X1155705Y1119768D01*
X1146801D01*
X1140820Y1125749D01*
X1136581D01*
X1132441Y1129889D01*
X1115774D01*
X1115054Y1130609D01*
Y1131581D01*
X1114334Y1132301D01*
X1113054D01*
X1112334Y1131581D01*
Y1130609D01*
X1111614Y1129889D01*
X1110334D01*
X1109614Y1130609D01*
Y1131581D01*
X1108894Y1132301D01*
X1107614D01*
X1106894Y1131581D01*
Y1130609D01*
X1106174Y1129889D01*
X1103315D01*
X1101641Y1128215D01*
G01X1303068Y1053744D02*
X1300050D01*
X1282972Y1060818D01*
X1282332Y1060553D01*
X1280335Y1061380D01*
X1280070Y1062021D01*
X1278075Y1062847D01*
X1277435Y1062582D01*
X1275438Y1063409D01*
X1275173Y1064050D01*
X1273178Y1064876D01*
X1272538Y1064611D01*
X1270541Y1065438D01*
X1270276Y1066079D01*
X1268281Y1066905D01*
X1267641Y1066640D01*
X1265644Y1067467D01*
X1265379Y1068108D01*
X1263384Y1068934D01*
X1262744Y1068669D01*
X1260747Y1069496D01*
X1260482Y1070137D01*
X1256294Y1071872D01*
X1254767Y1073399D01*
X1254074D01*
X1252546Y1074927D01*
Y1075620D01*
X1251019Y1077147D01*
X1250326D01*
X1248798Y1078675D01*
Y1079368D01*
X1247271Y1080895D01*
X1246578D01*
X1245050Y1082423D01*
Y1083116D01*
X1242886Y1085280D01*
X1240891Y1086107D01*
X1240251Y1085842D01*
X1238255Y1086669D01*
X1237990Y1087311D01*
X1232799Y1089463D01*
X1229163Y1093099D01*
X1227205D01*
X1222573Y1091182D01*
X1212023D01*
X1205338Y1093952D01*
X1197461D01*
X1195019Y1096394D01*
X1192381Y1102766D01*
X1191006Y1104142D01*
X1179303D01*
X1178278Y1103117D01*
X1176305D01*
X1175275Y1104147D01*
X1173820D01*
X1170638Y1105465D01*
X1169457Y1106646D01*
X1167422Y1107489D01*
X1163161D01*
X1162136Y1106464D01*
X1160163D01*
X1159182Y1107445D01*
X1157789D01*
X1155917Y1108221D01*
X1153158Y1110980D01*
X1142199Y1115518D01*
X1139924Y1117793D01*
X1132439Y1120895D01*
X1119923D01*
X1118877Y1119849D01*
X1116906D01*
X1115928Y1120827D01*
X1113367D01*
X1111959Y1119421D01*
X1109492Y1118399D01*
X1106365D01*
X1104443Y1119195D01*
X1102660D01*
X1101641Y1118176D01*
G01X1303068Y1054964D02*
X1300293D01*
X1256986Y1072907D01*
X1243578Y1086315D01*
X1233491Y1090498D01*
X1229669Y1094319D01*
X1226959D01*
X1222330Y1092402D01*
X1212266D01*
X1205581Y1095172D01*
X1197967D01*
X1196054Y1097085D01*
X1193416Y1103458D01*
X1191512Y1105362D01*
X1179388D01*
X1178286Y1106464D01*
X1176404D01*
X1175307Y1105367D01*
X1174063D01*
X1171330Y1106500D01*
X1170149Y1107681D01*
X1167665Y1108709D01*
X1163246D01*
X1162144Y1109811D01*
X1160262D01*
X1159116Y1108665D01*
X1158033D01*
X1156609Y1109256D01*
X1153850Y1112015D01*
X1142891Y1116553D01*
X1140616Y1118828D01*
X1132682Y1122115D01*
X1119968D01*
X1118887Y1123196D01*
X1117003D01*
X1115854Y1122047D01*
X1112861D01*
X1111268Y1120456D01*
X1109249Y1119619D01*
X1106608D01*
X1104686Y1120415D01*
X1102748D01*
X1101641Y1121522D01*
G01X1304264Y1063480D02*
X1300295D01*
X1264594Y1078259D01*
X1240382Y1102471D01*
X1235948D01*
X1231856Y1106563D01*
X1224848D01*
X1221593Y1109818D01*
X1203550D01*
X1192408Y1120960D01*
X1189072D01*
X1186836Y1123196D01*
X1175112D01*
X1171766Y1126542D01*
X1153485D01*
X1147930Y1132097D01*
X1138287D01*
X1133803Y1136581D01*
X1103314D01*
X1101641Y1134908D01*
G01X1304264Y1068642D02*
X1301110D01*
X1269148Y1081877D01*
X1241750Y1109275D01*
X1236882D01*
X1234427Y1111730D01*
X1231796D01*
X1229707Y1113819D01*
X1226701D01*
X1221801Y1118719D01*
X1206593D01*
X1199261Y1126051D01*
X1195148D01*
X1191837Y1129362D01*
X1190027D01*
X1182808Y1136581D01*
X1172346D01*
X1168999Y1139928D01*
X1151818D01*
X1146029Y1145717D01*
X1138191D01*
X1134852Y1149056D01*
Y1150960D01*
X1131707Y1154105D01*
X1129839D01*
X1124427Y1159517D01*
Y1176018D01*
X1123707Y1176738D01*
X1118887D01*
X1118886Y1176739D01*
X1117004D01*
X1117003Y1176738D01*
X1110195D01*
X1109475Y1176018D01*
Y1174361D01*
X1108755Y1173641D01*
X1107475D01*
X1106755Y1174361D01*
Y1176018D01*
X1106035Y1176738D01*
X1103315D01*
X1101641Y1178412D01*
G01X1304264Y1072840D02*
X1301222D01*
X1271970Y1084957D01*
X1241263Y1115664D01*
X1235123D01*
X1232886Y1117901D01*
X1228192D01*
X1223127Y1122966D01*
X1219633D01*
X1216784Y1125815D01*
X1212578D01*
X1212167Y1126226D01*
X1211365Y1126558D01*
X1209627D01*
X1208888Y1125819D01*
X1206699D01*
X1200031Y1132487D01*
X1196466D01*
X1192853Y1136100D01*
X1190030D01*
X1182856Y1143274D01*
X1172584D01*
X1169236Y1146622D01*
X1154758D01*
X1148939Y1152441D01*
X1142237D01*
X1133246Y1161432D01*
Y1177046D01*
X1126860Y1183432D01*
X1115634D01*
X1114914Y1182712D01*
Y1180823D01*
X1114194Y1180103D01*
X1112914D01*
X1112194Y1180823D01*
Y1182712D01*
X1111474Y1183432D01*
X1110194D01*
X1109474Y1182712D01*
Y1180823D01*
X1108754Y1180103D01*
X1107474D01*
X1106754Y1180823D01*
Y1182712D01*
X1106034Y1183432D01*
X1103314D01*
X1101641Y1185105D01*
G01X1304264Y1078044D02*
X1302137D01*
X1280236Y1087115D01*
X1278710Y1088642D01*
X1278016D01*
X1276488Y1090170D01*
Y1090863D01*
X1274961Y1092390D01*
X1274268D01*
X1272740Y1093918D01*
Y1094611D01*
X1271213Y1096138D01*
X1270520D01*
X1268992Y1097666D01*
Y1098359D01*
X1267465Y1099886D01*
X1266772D01*
X1265244Y1101414D01*
Y1102107D01*
X1263717Y1103634D01*
X1263024D01*
X1261496Y1105162D01*
Y1105855D01*
X1259969Y1107382D01*
X1259276D01*
X1257748Y1108910D01*
Y1109603D01*
X1256221Y1111130D01*
X1255528D01*
X1254000Y1112658D01*
Y1113351D01*
X1252473Y1114878D01*
X1251780D01*
X1250252Y1116406D01*
Y1117099D01*
X1248725Y1118626D01*
X1248032D01*
X1246504Y1120154D01*
Y1120847D01*
X1243076Y1124276D01*
X1235118D01*
X1228639Y1130755D01*
X1219015Y1134741D01*
X1210625D01*
X1208542Y1136823D01*
X1204706Y1138412D01*
X1199452Y1143666D01*
X1190225Y1147489D01*
X1180032Y1157683D01*
X1179203D01*
X1178179Y1156659D01*
X1176204D01*
X1175175Y1157688D01*
X1171640D01*
X1169251Y1160077D01*
X1165893D01*
X1164848Y1161122D01*
X1162955D01*
X1161841Y1160008D01*
X1160162D01*
X1159182Y1160988D01*
X1156621D01*
X1154334Y1158701D01*
X1151616D01*
X1149605Y1159536D01*
X1147595Y1160370D01*
X1143511Y1164453D01*
X1142119Y1167816D01*
Y1184740D01*
X1139569Y1187290D01*
X1122147Y1194508D01*
X1119914D01*
X1118877Y1193471D01*
X1116906D01*
X1115903Y1194474D01*
X1113658D01*
X1112344Y1193160D01*
X1109810Y1192114D01*
X1107439D01*
X1105623Y1192866D01*
X1102709D01*
X1101641Y1191798D01*
G01X1304264Y1087642D02*
X1303105D01*
X1289342Y1093343D01*
X1239244Y1143441D01*
X1235195D01*
X1228473Y1150163D01*
X1225096D01*
X1221825Y1153434D01*
X1217441D01*
X1216721Y1152714D01*
Y1152104D01*
X1216001Y1151384D01*
X1214711D01*
X1213991Y1152104D01*
Y1152714D01*
X1213271Y1153434D01*
X1209293D01*
X1200753Y1161974D01*
X1196880D01*
X1193839Y1165015D01*
Y1168780D01*
X1189227Y1173392D01*
X1176515D01*
X1169822Y1180085D01*
X1159360D01*
X1157020Y1182425D01*
Y1189352D01*
X1146510Y1199862D01*
X1138105D01*
X1135021Y1202946D01*
X1130764D01*
X1124472Y1209238D01*
X1119486D01*
X1118534Y1210190D01*
X1116774D01*
X1112773Y1206189D01*
X1103982D01*
X1101641Y1208530D01*
G01X1304264Y1083534D02*
X1302489D01*
X1285593Y1090533D01*
X1239367Y1136759D01*
X1235217D01*
X1228694Y1143282D01*
X1219582D01*
X1216245Y1146619D01*
X1205941D01*
X1198540Y1154020D01*
X1195220D01*
X1182541Y1166699D01*
X1171228D01*
X1167881Y1170046D01*
X1159288D01*
X1158658Y1170676D01*
Y1173668D01*
X1158028Y1174298D01*
X1156558D01*
X1155928Y1173668D01*
Y1170676D01*
X1155298Y1170046D01*
X1153636D01*
X1150055Y1173627D01*
Y1185743D01*
X1145159Y1190639D01*
X1130049Y1196897D01*
X1123435Y1203511D01*
X1103315D01*
X1101641Y1201837D01*
G01X1304264Y1079264D02*
X1302380D01*
X1280928Y1088150D01*
X1243582Y1125496D01*
X1235624D01*
X1229330Y1131790D01*
X1219258Y1135961D01*
X1211131D01*
X1209234Y1137858D01*
X1205398Y1139447D01*
X1200144Y1144701D01*
X1190917Y1148524D01*
X1180538Y1158903D01*
X1179288D01*
X1178185Y1160006D01*
X1176305D01*
X1175207Y1158908D01*
X1172146D01*
X1169757Y1161297D01*
X1166399D01*
X1165354Y1162342D01*
X1162976D01*
X1161964Y1163354D01*
X1160262D01*
X1159116Y1162208D01*
X1156115D01*
X1153828Y1159921D01*
X1151860D01*
X1148287Y1161404D01*
X1144546Y1165145D01*
X1143339Y1168059D01*
Y1185246D01*
X1140261Y1188324D01*
X1122390Y1195728D01*
X1119977D01*
X1118887Y1196818D01*
X1117003D01*
X1115879Y1195694D01*
X1113150D01*
X1111653Y1194195D01*
X1109568Y1193334D01*
X1107682D01*
X1105866Y1194086D01*
X1102699D01*
X1101641Y1195144D01*
G01X1303182Y866427D02*
X1301224Y864469D01*
Y862325D01*
X1266584Y827685D01*
X1255210Y800228D01*
X1239420Y784438D01*
X1235422D01*
X1229403Y778419D01*
X1226012D01*
X1222512Y774919D01*
X1219411D01*
X1214911Y770419D01*
Y767318D01*
X1213262Y765669D01*
X1212168Y765008D01*
X1211048Y764716D01*
X1207927Y764196D01*
X1199097Y763410D01*
X1198316Y764064D01*
X1198289Y764365D01*
X1198268Y764599D01*
X1197489Y765252D01*
X1196201Y765137D01*
X1195555Y764365D01*
X1195549Y764358D01*
X1195597Y763822D01*
X1194943Y763042D01*
X1191083Y762698D01*
X1150002D01*
X1149282Y763418D01*
Y764246D01*
X1148562Y764966D01*
X1147282D01*
X1146562Y764246D01*
Y763418D01*
X1145842Y762698D01*
X1139177D01*
X1138457Y763418D01*
Y764469D01*
X1137737Y765189D01*
X1136447D01*
X1135727Y764469D01*
Y763418D01*
X1135007Y762698D01*
X1131932D01*
X1130831Y762825D01*
X1124464Y764109D01*
X1121646Y765084D01*
X1120761Y765969D01*
Y769187D01*
X1119804Y770144D01*
X1117783D01*
G01X1300865Y870267D02*
X1300145D01*
X1299191Y869313D01*
Y863064D01*
X1264759Y828632D01*
X1253505Y801463D01*
X1238475Y786433D01*
X1234617D01*
X1230603Y782419D01*
X1225911D01*
X1222411Y778919D01*
X1219910D01*
X1213535Y772544D01*
X1211436D01*
X1208311Y769419D01*
X1204239D01*
X1203519Y768699D01*
Y766892D01*
X1202799Y766172D01*
X1201519D01*
X1200799Y766892D01*
Y768699D01*
X1200079Y769419D01*
X1196811D01*
X1192919Y765527D01*
X1190968Y764719D01*
X1157161D01*
X1153412Y768468D01*
X1150012D01*
X1149375Y769105D01*
X1144701D01*
X1143981Y768385D01*
Y765584D01*
X1143261Y764864D01*
X1141981D01*
X1141261Y765584D01*
Y768385D01*
X1140541Y769105D01*
X1137821D01*
X1136935Y768219D01*
X1134042D01*
X1133322Y767499D01*
Y765736D01*
X1132602Y765016D01*
X1130306D01*
X1127013Y768309D01*
Y769327D01*
X1128121Y770435D01*
Y771453D01*
X1127208Y772366D01*
X1126190D01*
X1125082Y771258D01*
X1124064D01*
X1123003Y772319D01*
X1122009D01*
X1117783Y776545D01*
Y776837D01*
G01X1300865Y876397D02*
X1296277D01*
X1294044Y874164D01*
Y865220D01*
X1260026Y831202D01*
X1249449Y805443D01*
X1247922Y803916D01*
X1247229D01*
X1245701Y802388D01*
Y801695D01*
X1244174Y800168D01*
X1243481D01*
X1241953Y798640D01*
Y797947D01*
X1238122Y794116D01*
X1234304D01*
X1228107Y787919D01*
X1223014D01*
X1217968Y785829D01*
X1216465Y784326D01*
X1215772D01*
X1214244Y782798D01*
Y782105D01*
X1212717Y780578D01*
X1211093D01*
X1208598Y778083D01*
X1204501D01*
X1204011Y778573D01*
X1201851D01*
X1201361Y778083D01*
X1195099D01*
X1191133Y774117D01*
X1188361D01*
X1187871Y774607D01*
X1185711D01*
X1185221Y774117D01*
X1178976D01*
X1177939Y775154D01*
X1176400D01*
X1175413Y774167D01*
X1174708D01*
X1166779Y777451D01*
X1162860D01*
X1161804Y778507D01*
X1160243D01*
X1159197Y777461D01*
X1156253D01*
X1153841Y775049D01*
X1151330D01*
X1149733Y776646D01*
X1146149Y778131D01*
X1143537Y780743D01*
X1140697D01*
X1139521Y781919D01*
X1138000D01*
X1136909Y780828D01*
X1134374D01*
X1133359Y779813D01*
X1123067D01*
X1120998Y781882D01*
Y782544D01*
X1119733Y783809D01*
Y784927D01*
X1117783Y786877D01*
G01X1300865Y875177D02*
X1296783D01*
X1295264Y873658D01*
Y864714D01*
X1261062Y830512D01*
X1250485Y804753D01*
X1238628Y792896D01*
X1234810D01*
X1228613Y786699D01*
X1223257D01*
X1218660Y784794D01*
X1213223Y779358D01*
X1211599D01*
X1209104Y776863D01*
X1195605D01*
X1191639Y772897D01*
X1179009D01*
X1177932Y771820D01*
X1176428D01*
X1175301Y772947D01*
X1174465D01*
X1166536Y776231D01*
X1162903D01*
X1161833Y775161D01*
X1160283D01*
X1159203Y776241D01*
X1156759D01*
X1154347Y773829D01*
X1150824D01*
X1149041Y775611D01*
X1145457Y777096D01*
X1143031Y779523D01*
X1140669D01*
X1139565Y778419D01*
X1138022D01*
X1136833Y779608D01*
X1134880D01*
X1133865Y778593D01*
X1122561D01*
X1119778Y781376D01*
Y782038D01*
X1119058Y782758D01*
X1118555D01*
X1117783Y783530D01*
G01X1300865Y887446D02*
X1289186D01*
X1282865Y881125D01*
Y870160D01*
X1249938Y837233D01*
X1244499Y824102D01*
X1236539Y818784D01*
X1234482Y816727D01*
Y813990D01*
X1229058Y808566D01*
X1226518D01*
X1224187Y810897D01*
X1223169D01*
X1222256Y809984D01*
Y808966D01*
X1223551Y807671D01*
Y806653D01*
X1222117Y805219D01*
X1218141D01*
X1217421Y805939D01*
Y807740D01*
X1216701Y808460D01*
X1215505D01*
X1214701Y807656D01*
Y805939D01*
X1213981Y805219D01*
X1211261D01*
X1207861Y801819D01*
X1204087D01*
X1203367Y802539D01*
Y804687D01*
X1202647Y805407D01*
X1201367D01*
X1200647Y804687D01*
Y802539D01*
X1199927Y801819D01*
X1195861D01*
X1192632Y798590D01*
X1170826D01*
X1170196Y799220D01*
Y800888D01*
X1169566Y801518D01*
X1168096D01*
X1167466Y800888D01*
Y799220D01*
X1166836Y798590D01*
X1165089D01*
X1161752Y801927D01*
X1160280D01*
X1159723Y801370D01*
X1156795D01*
X1153859Y798434D01*
X1151022D01*
X1149058Y800398D01*
X1145281D01*
X1144561Y799678D01*
Y797601D01*
X1143841Y796881D01*
X1142551D01*
X1141831Y797601D01*
Y799678D01*
X1141111Y800398D01*
X1138391D01*
X1135547Y797554D01*
X1128126D01*
X1127077Y798603D01*
X1121767D01*
X1120107Y800263D01*
X1117783D01*
G01X1300865Y881566D02*
X1291623D01*
X1288745Y878688D01*
Y867296D01*
X1254930Y833481D01*
X1247180Y814772D01*
X1238204Y805796D01*
X1236138D01*
X1229911Y799569D01*
X1226211D01*
X1222961Y796319D01*
X1219123D01*
X1213985Y791181D01*
X1209599D01*
X1208711Y792069D01*
X1204683D01*
X1203963Y791349D01*
Y789480D01*
X1203243Y788760D01*
X1201963D01*
X1201243Y789480D01*
Y791349D01*
X1200523Y792069D01*
X1196411D01*
X1192892Y788550D01*
X1184193D01*
X1183473Y787830D01*
Y786757D01*
X1182753Y786037D01*
X1181463D01*
X1180743Y786757D01*
Y787830D01*
X1180023Y788550D01*
X1174533D01*
X1173813Y787830D01*
Y785585D01*
X1173093Y784865D01*
X1171803D01*
X1171083Y785585D01*
Y787830D01*
X1170363Y788550D01*
X1165737D01*
X1162390Y791897D01*
X1160285D01*
X1158312Y789924D01*
Y788949D01*
X1157682Y788319D01*
X1156907D01*
X1156277Y787689D01*
Y786808D01*
X1155647Y786178D01*
X1154177D01*
X1153547Y786808D01*
Y787689D01*
X1152917Y788319D01*
X1151447D01*
X1150817Y787689D01*
Y786808D01*
X1150187Y786178D01*
X1148717D01*
X1148087Y786808D01*
Y787689D01*
X1147457Y788319D01*
X1125363D01*
X1120112Y793570D01*
X1117783D01*
G01X1301466Y918886D02*
X1273752D01*
X1250226Y895360D01*
Y885221D01*
X1237674Y872669D01*
X1232549D01*
X1227790Y867910D01*
X1225292D01*
X1221612Y864230D01*
X1218368D01*
X1213727Y859589D01*
X1195912D01*
X1193328Y862173D01*
X1189626D01*
X1188906Y861453D01*
Y859838D01*
X1188186Y859118D01*
X1186906D01*
X1186186Y859838D01*
Y861453D01*
X1185466Y862173D01*
X1184186D01*
X1183466Y861453D01*
Y859838D01*
X1182746Y859118D01*
X1181466D01*
X1180746Y859838D01*
Y861453D01*
X1180026Y862173D01*
X1174591D01*
X1167897Y855479D01*
X1159806D01*
X1155691Y859594D01*
X1145745D01*
X1142030Y855879D01*
X1137618D01*
X1135087Y853348D01*
X1128427D01*
X1127707Y852628D01*
Y851514D01*
X1126987Y850794D01*
X1125707D01*
X1124987Y851514D01*
Y852628D01*
X1124267Y853348D01*
X1120672D01*
X1117783Y850459D01*
G01X1301466Y914966D02*
X1275659D01*
X1254146Y893453D01*
Y882585D01*
X1237382Y865821D01*
X1231519D01*
X1225631Y859933D01*
X1221431D01*
X1214585Y853087D01*
X1209665D01*
X1208208Y851630D01*
X1203259D01*
X1202539Y850910D01*
Y849218D01*
X1201819Y848498D01*
X1200539D01*
X1199819Y849218D01*
Y850910D01*
X1199099Y851630D01*
X1194487D01*
X1193120Y852997D01*
X1187981D01*
X1187261Y852277D01*
Y851119D01*
X1186541Y850399D01*
X1185261D01*
X1184541Y851119D01*
Y852277D01*
X1183821Y852997D01*
X1180956D01*
X1180092Y852133D01*
X1174159D01*
X1170818Y848792D01*
X1160331D01*
X1156590Y852533D01*
X1150054D01*
X1147485Y849964D01*
X1144720D01*
X1144000Y849244D01*
Y847368D01*
X1143280Y846648D01*
X1142000D01*
X1141280Y847368D01*
Y849244D01*
X1140560Y849964D01*
X1137840D01*
X1134312Y846436D01*
X1120453D01*
X1117783Y843766D01*
G01X1302266Y929188D02*
X1267697D01*
X1237497Y898988D01*
X1235800D01*
X1234747Y897935D01*
Y896047D01*
X1232370Y893670D01*
X1227401D01*
X1225512Y891781D01*
Y889425D01*
X1221683Y885596D01*
X1212939D01*
X1209593Y882250D01*
X1208468D01*
X1207748Y881530D01*
Y879887D01*
X1207028Y879167D01*
X1205748D01*
X1205028Y879887D01*
Y881530D01*
X1204308Y882250D01*
X1203028D01*
X1202308Y881530D01*
Y879887D01*
X1201588Y879167D01*
X1200308D01*
X1199588Y879887D01*
Y881530D01*
X1198868Y882250D01*
X1197588D01*
X1196868Y881530D01*
Y879887D01*
X1196148Y879167D01*
X1194868D01*
X1194148Y879887D01*
Y881530D01*
X1193428Y882250D01*
X1188596D01*
X1187876Y881530D01*
Y880626D01*
X1187156Y879906D01*
X1185876D01*
X1185156Y880626D01*
Y881530D01*
X1184436Y882250D01*
X1173351D01*
X1170005Y878904D01*
X1157406D01*
X1154060Y875558D01*
X1143024D01*
X1140044Y872578D01*
X1138370D01*
X1134911Y869119D01*
X1128523D01*
X1127803Y868399D01*
Y867292D01*
X1127083Y866572D01*
X1125803D01*
X1125083Y867292D01*
Y868399D01*
X1124363Y869119D01*
X1119710D01*
X1117783Y867192D01*
G01X1302266Y924026D02*
X1270567D01*
X1244687Y898146D01*
Y889604D01*
X1239746Y884669D01*
X1238373D01*
X1237443Y885599D01*
X1235825D01*
X1234816Y884590D01*
X1231142D01*
X1225396Y878845D01*
X1223038Y873157D01*
X1220573Y872135D01*
X1217203D01*
X1216713Y872625D01*
X1214553D01*
X1214063Y872135D01*
X1210885D01*
X1207089Y868339D01*
X1204554D01*
X1204064Y868829D01*
X1201904D01*
X1201414Y868339D01*
X1195766D01*
X1193025Y871080D01*
X1179278D01*
X1178144Y872214D01*
X1176326D01*
X1175169Y871057D01*
X1172852D01*
X1169558Y867763D01*
X1163096D01*
X1161994Y868865D01*
X1160112D01*
X1158987Y867740D01*
X1156360D01*
X1153637Y865017D01*
X1151553D01*
X1149150Y867420D01*
X1145367D01*
X1139977Y862030D01*
X1136296D01*
X1132344Y860391D01*
X1120928D01*
X1120022Y859485D01*
X1118797D01*
X1117783Y860499D01*
G01X1302266Y922806D02*
X1271073D01*
X1245907Y897640D01*
Y889098D01*
X1240251Y883449D01*
X1238459D01*
X1237258Y882248D01*
X1235879D01*
X1234757Y883370D01*
X1231648D01*
X1226431Y878153D01*
X1223972Y872223D01*
X1220816Y870915D01*
X1211391D01*
X1207595Y867119D01*
X1195260D01*
X1192519Y869860D01*
X1179193D01*
X1178196Y868863D01*
X1176167D01*
X1175193Y869837D01*
X1173358D01*
X1170064Y866543D01*
X1163011D01*
X1161987Y865519D01*
X1160012D01*
X1159011Y866520D01*
X1156866D01*
X1154143Y863797D01*
X1151047D01*
X1148644Y866200D01*
X1145873D01*
X1140483Y860810D01*
X1136539D01*
X1132587Y859171D01*
X1121434D01*
X1120528Y858265D01*
X1118896D01*
X1117783Y857152D01*
G01X1302266Y933108D02*
X1265323D01*
X1237899Y905684D01*
X1234176D01*
X1230605Y902113D01*
Y899948D01*
X1229252Y898595D01*
X1226120D01*
X1223161Y895636D01*
X1217561D01*
X1216841Y894916D01*
Y891623D01*
X1216121Y890903D01*
X1214841D01*
X1214121Y891623D01*
Y894916D01*
X1213401Y895636D01*
X1209782D01*
X1207210Y893064D01*
X1204003D01*
X1203283Y892344D01*
Y888961D01*
X1202563Y888241D01*
X1201367D01*
X1200563Y889045D01*
Y892344D01*
X1199843Y893064D01*
X1196888D01*
X1192767Y888943D01*
X1187861D01*
X1187141Y888223D01*
Y887430D01*
X1186421Y886710D01*
X1185141D01*
X1184421Y887430D01*
Y888223D01*
X1183701Y888943D01*
X1173564D01*
X1170217Y885596D01*
X1166508D01*
X1165264Y884352D01*
X1163824D01*
X1162580Y885596D01*
X1154674D01*
X1150054Y880976D01*
X1138100D01*
X1135988Y878864D01*
Y877140D01*
X1134727Y875879D01*
X1128461D01*
X1127741Y875159D01*
Y873993D01*
X1127021Y873273D01*
X1125741D01*
X1125021Y873993D01*
Y875159D01*
X1124301Y875879D01*
X1119777D01*
X1117783Y873885D01*
G01X1302266Y938188D02*
X1262255D01*
X1240112Y916045D01*
X1235427D01*
X1229046Y909664D01*
X1227077D01*
X1223088Y905675D01*
X1216353D01*
X1213012Y902334D01*
X1204188D01*
X1203468Y901614D01*
Y900012D01*
X1202748Y899292D01*
X1201468D01*
X1200748Y900012D01*
Y901614D01*
X1200028Y902334D01*
X1196510D01*
X1194396Y900220D01*
X1191667D01*
X1191037Y899590D01*
Y897538D01*
X1190407Y896908D01*
X1189074D01*
X1188307Y897675D01*
Y899590D01*
X1187677Y900220D01*
X1186207D01*
X1185577Y899590D01*
Y898598D01*
X1184947Y897968D01*
X1183477D01*
X1182847Y898598D01*
Y899590D01*
X1182217Y900220D01*
X1180951D01*
X1179712Y898981D01*
X1173773D01*
X1167080Y892288D01*
X1146438D01*
X1143083Y888933D01*
X1136632D01*
X1133163Y885464D01*
X1127446D01*
X1124876Y882894D01*
X1120100D01*
X1117783Y880577D01*
G01X1303266Y942151D02*
X1260528D01*
X1241568Y923191D01*
X1235952D01*
X1229129Y916368D01*
X1227471D01*
X1223471Y912368D01*
X1217115D01*
X1215976Y911229D01*
X1214485D01*
X1213346Y912368D01*
X1210832D01*
X1208383Y909919D01*
X1204495D01*
X1203775Y909199D01*
Y907899D01*
X1203055Y907179D01*
X1201775D01*
X1201055Y907899D01*
Y909199D01*
X1200335Y909919D01*
X1197450D01*
X1194106Y906575D01*
X1188699D01*
X1187979Y905855D01*
Y905008D01*
X1187259Y904288D01*
X1185979D01*
X1185259Y905008D01*
Y905855D01*
X1184539Y906575D01*
X1180194D01*
X1179293Y905674D01*
X1172328D01*
X1171698Y905044D01*
Y903868D01*
X1171068Y903238D01*
X1169598D01*
X1168968Y903868D01*
Y905044D01*
X1168338Y905674D01*
X1166996D01*
X1163651Y902329D01*
X1159312D01*
X1154703Y897720D01*
X1152766D01*
X1152136Y898350D01*
Y899437D01*
X1151506Y900067D01*
X1150250D01*
X1149029Y898846D01*
X1145369D01*
X1143148Y896625D01*
X1136995D01*
X1132186Y891816D01*
X1129547D01*
X1127412Y889681D01*
X1120194D01*
X1117783Y887270D01*
G01X1303266Y947316D02*
X1258275D01*
X1241398Y930439D01*
X1234841D01*
X1229961Y925559D01*
X1227597D01*
X1223094Y921056D01*
X1217271D01*
X1216781Y921546D01*
X1214621D01*
X1214131Y921056D01*
X1210430D01*
X1207494Y918120D01*
X1203665D01*
X1203175Y918610D01*
X1201015D01*
X1200525Y918120D01*
X1196105D01*
X1192687Y914702D01*
X1179300D01*
X1178286Y915716D01*
X1176404D01*
X1175279Y914591D01*
X1172737D01*
X1170431Y912285D01*
X1166247D01*
X1165230Y911268D01*
X1163246D01*
X1162145Y912369D01*
X1160261D01*
X1159137Y911245D01*
X1156557D01*
X1153541Y908229D01*
X1151321D01*
X1148641Y905549D01*
X1137825D01*
X1133766Y901490D01*
X1129620D01*
X1125049Y896919D01*
X1120846D01*
X1120218Y896291D01*
X1118802D01*
X1117783Y897310D01*
G01X1303266Y946096D02*
X1258781D01*
X1241904Y929219D01*
X1235347D01*
X1230467Y924339D01*
X1228103D01*
X1223600Y919836D01*
X1210936D01*
X1208000Y916900D01*
X1196611D01*
X1193193Y913482D01*
X1179391D01*
X1178278Y912369D01*
X1176305D01*
X1175303Y913371D01*
X1173243D01*
X1170937Y911065D01*
X1166753D01*
X1165736Y910048D01*
X1163161D01*
X1162136Y909023D01*
X1160163D01*
X1159161Y910025D01*
X1157063D01*
X1154047Y907009D01*
X1151827D01*
X1149147Y904329D01*
X1138331D01*
X1134272Y900270D01*
X1130126D01*
X1125555Y895699D01*
X1121352D01*
X1120724Y895071D01*
X1118891D01*
X1117783Y893963D01*
G01X1303266Y960499D02*
X1301589D01*
X1297508Y956418D01*
X1254148D01*
X1239444Y941714D01*
X1232948D01*
X1230653Y939419D01*
X1226174D01*
X1223514Y936759D01*
X1209435D01*
X1205995Y933319D01*
X1188064D01*
X1187344Y932599D01*
Y930818D01*
X1186624Y930098D01*
X1185344D01*
X1184624Y930818D01*
Y932599D01*
X1183904Y933319D01*
X1181184D01*
X1178709Y935794D01*
X1176153D01*
X1174049Y933690D01*
X1173031D01*
X1172221Y934499D01*
X1171203D01*
X1170297Y933593D01*
Y932575D01*
X1171107Y931765D01*
Y930748D01*
X1169460Y929101D01*
X1155156D01*
X1153948Y927893D01*
X1152436D01*
X1151228Y929101D01*
X1144269D01*
X1142190Y927022D01*
Y926004D01*
X1144036Y924158D01*
Y923140D01*
X1143130Y922234D01*
X1142112D01*
X1140266Y924080D01*
X1139248D01*
X1135650Y920482D01*
Y918671D01*
X1131986Y915007D01*
X1129352D01*
X1127211Y912866D01*
X1119953D01*
X1117783Y910696D01*
G01X1303266Y955805D02*
X1302575D01*
X1299268Y952498D01*
X1255986D01*
X1239176Y935688D01*
X1232680D01*
X1229511Y932519D01*
X1218148D01*
X1217428Y931799D01*
Y931187D01*
X1216708Y930467D01*
X1215428D01*
X1214708Y931187D01*
Y931799D01*
X1213988Y932519D01*
X1210903D01*
X1207650Y929266D01*
X1203203D01*
X1202483Y928546D01*
Y927057D01*
X1201763Y926337D01*
X1200483D01*
X1199763Y927057D01*
Y928546D01*
X1199043Y929266D01*
X1196281D01*
X1192770Y925755D01*
X1187011D01*
X1186291Y925035D01*
Y924026D01*
X1185571Y923306D01*
X1184291D01*
X1183571Y924026D01*
Y925035D01*
X1182851Y925755D01*
X1173047D01*
X1169700Y922408D01*
X1158480D01*
X1157760Y921688D01*
Y920937D01*
X1157040Y920217D01*
X1155760D01*
X1155040Y920937D01*
Y921688D01*
X1154320Y922408D01*
X1151600D01*
X1149437Y920245D01*
Y919227D01*
X1150123Y918541D01*
Y917523D01*
X1149217Y916617D01*
X1148199D01*
X1147513Y917303D01*
X1146495D01*
X1141466Y912274D01*
X1135895D01*
X1132521Y908900D01*
X1126891D01*
X1123811Y905820D01*
X1119600D01*
X1117783Y904003D01*
G01X1303263Y1020607D02*
X1295360D01*
X1282919Y1025760D01*
X1227168D01*
X1223920Y1029008D01*
X1218500D01*
X1214659Y1032849D01*
X1213205D01*
X1212575Y1033479D01*
Y1034838D01*
X1211945Y1035468D01*
X1210475D01*
X1209845Y1034838D01*
Y1033479D01*
X1209215Y1032849D01*
X1196463D01*
X1193127Y1036185D01*
X1190321D01*
X1189601Y1035465D01*
Y1034140D01*
X1188881Y1033420D01*
X1187601D01*
X1186881Y1034140D01*
Y1035465D01*
X1186161Y1036185D01*
X1184881D01*
X1184161Y1035465D01*
Y1034140D01*
X1183441Y1033420D01*
X1182161D01*
X1181441Y1034140D01*
Y1035465D01*
X1180721Y1036185D01*
X1166895D01*
X1163549Y1039531D01*
X1153849D01*
X1149761Y1043619D01*
X1145863D01*
X1138907Y1050575D01*
X1137890D01*
X1135004Y1047689D01*
X1133986D01*
X1133080Y1048595D01*
Y1049613D01*
X1135965Y1052498D01*
Y1053517D01*
X1133228Y1056254D01*
X1129958D01*
X1124093Y1062119D01*
X1120297D01*
X1117783Y1064633D01*
G01X1301567Y1024677D02*
X1295785D01*
X1283582Y1029731D01*
X1243241D01*
X1240749Y1032223D01*
X1235826D01*
X1231861Y1036188D01*
X1225989D01*
X1225359Y1036818D01*
Y1039088D01*
X1224729Y1039718D01*
X1223259D01*
X1222629Y1039088D01*
Y1036818D01*
X1221999Y1036188D01*
X1219685D01*
X1213961Y1041912D01*
X1210161D01*
X1207661Y1039412D01*
X1204003D01*
X1203283Y1040132D01*
Y1041832D01*
X1202563Y1042552D01*
X1201283D01*
X1200563Y1041832D01*
Y1040132D01*
X1199843Y1039412D01*
X1195561D01*
X1192095Y1042878D01*
X1187913D01*
X1187193Y1043598D01*
Y1044465D01*
X1186473Y1045185D01*
X1185193D01*
X1184473Y1044465D01*
Y1043598D01*
X1183753Y1042878D01*
X1166002D01*
X1162656Y1046224D01*
X1158028D01*
X1155487Y1048765D01*
X1151246D01*
X1149452Y1050559D01*
Y1052151D01*
X1148691Y1052912D01*
X1145303D01*
X1144661Y1053554D01*
Y1055819D01*
X1141061Y1059419D01*
X1137861D01*
X1134761Y1062519D01*
X1130761D01*
X1124561Y1068719D01*
X1120390D01*
X1117783Y1071326D01*
G01X1301567Y1029873D02*
X1296674D01*
X1284309Y1034996D01*
X1258780D01*
X1250863Y1038275D01*
X1250223Y1038009D01*
X1248226Y1038836D01*
X1247961Y1039477D01*
X1245966Y1040303D01*
X1245326Y1040038D01*
X1243329Y1040865D01*
X1243064Y1041506D01*
X1241069Y1042332D01*
X1240429Y1042067D01*
X1238432Y1042894D01*
X1238167Y1043535D01*
X1232684Y1045806D01*
X1228691Y1049799D01*
X1225904D01*
X1221889Y1048136D01*
X1219651D01*
X1217389Y1049072D01*
X1213463Y1052999D01*
X1211313D01*
X1206588Y1051042D01*
X1198032D01*
X1191009Y1053949D01*
X1179319D01*
X1178294Y1052924D01*
X1177711Y1052923D01*
X1176871D01*
X1176870Y1052924D01*
X1176282D01*
X1175280Y1053926D01*
X1172192D01*
X1169783Y1056335D01*
X1167814Y1057150D01*
X1165232Y1059732D01*
Y1063080D01*
X1164354Y1063958D01*
X1163146D01*
X1162152Y1062964D01*
X1161551Y1062963D01*
X1160731D01*
X1160730Y1062964D01*
X1160140D01*
X1159138Y1063966D01*
X1157094D01*
X1154778Y1061650D01*
X1150075D01*
X1148425Y1063300D01*
X1147303Y1064421D01*
X1144907Y1065414D01*
X1140278Y1070042D01*
X1127992Y1075131D01*
X1123293Y1079831D01*
X1121899D01*
X1121120Y1079052D01*
X1118817D01*
X1117783Y1078018D01*
G01X1301568Y1039052D02*
X1298203D01*
X1285717Y1044223D01*
X1264945D01*
X1244895Y1052525D01*
X1237798Y1059622D01*
X1235523D01*
X1229886Y1065259D01*
X1224740D01*
X1222444Y1062963D01*
X1219682D01*
X1213961Y1068684D01*
X1210161D01*
X1207661Y1066184D01*
X1195561D01*
X1192096Y1069649D01*
X1187861D01*
X1187141Y1070369D01*
Y1072433D01*
X1186421Y1073153D01*
X1185141D01*
X1184421Y1072433D01*
Y1070369D01*
X1183701Y1069649D01*
X1176082D01*
X1174238Y1071493D01*
Y1075432D01*
X1169980Y1079690D01*
X1153722D01*
X1153002Y1080410D01*
Y1082109D01*
X1152282Y1082829D01*
X1151002D01*
X1150282Y1082109D01*
Y1080410D01*
X1149562Y1079690D01*
X1146690D01*
X1142151Y1084229D01*
Y1085247D01*
X1143699Y1086795D01*
Y1087813D01*
X1142793Y1088719D01*
X1141775D01*
X1140227Y1087171D01*
X1139209D01*
X1137282Y1089098D01*
X1133182D01*
X1129702Y1092578D01*
X1119956D01*
X1117783Y1094751D01*
G01X1301568Y1035028D02*
X1297669D01*
X1285134Y1040220D01*
X1262834D01*
X1241824Y1048922D01*
X1237892Y1052854D01*
X1235326D01*
X1229689Y1058491D01*
X1225161D01*
X1222861Y1056191D01*
X1219617D01*
X1217299Y1058509D01*
X1215148D01*
X1214428Y1059229D01*
Y1061331D01*
X1213768Y1061991D01*
X1211333D01*
X1208033Y1058691D01*
X1204217D01*
X1203497Y1059411D01*
Y1061458D01*
X1202777Y1062178D01*
X1201497D01*
X1200777Y1061458D01*
Y1059411D01*
X1200057Y1058691D01*
X1197337D01*
X1194342Y1061686D01*
X1188191D01*
X1187471Y1062406D01*
Y1063612D01*
X1186751Y1064332D01*
X1185471D01*
X1184751Y1063612D01*
Y1062406D01*
X1184031Y1061686D01*
X1181311D01*
X1180041Y1062956D01*
X1176162D01*
X1166121Y1072997D01*
X1146183D01*
X1139591Y1079589D01*
X1135721D01*
X1132991Y1082319D01*
X1128661D01*
X1125461Y1085519D01*
X1120322D01*
X1117783Y1088058D01*
G01X1301567Y1031093D02*
X1296917D01*
X1284552Y1036216D01*
X1259029D01*
X1233372Y1046845D01*
X1229197Y1051019D01*
X1225661D01*
X1221645Y1049356D01*
X1219894D01*
X1218081Y1050107D01*
X1213969Y1054219D01*
X1211070D01*
X1206345Y1052262D01*
X1198275D01*
X1191252Y1055169D01*
X1179335D01*
X1178195Y1056309D01*
X1176481D01*
X1175318Y1055146D01*
X1172698D01*
X1170475Y1057370D01*
X1168506Y1058185D01*
X1166452Y1060239D01*
Y1063586D01*
X1164860Y1065178D01*
X1163224D01*
X1162094Y1066308D01*
X1160298D01*
X1159176Y1065186D01*
X1156588D01*
X1154272Y1062870D01*
X1150581D01*
X1147995Y1065456D01*
X1145599Y1066449D01*
X1140970Y1071077D01*
X1128684Y1076166D01*
X1123799Y1081051D01*
X1121393D01*
X1120614Y1080272D01*
X1118876D01*
X1117783Y1081365D01*
G01X1303068Y1046505D02*
X1298787D01*
X1286922Y1051419D01*
X1267118D01*
X1253790Y1056940D01*
X1237881Y1072849D01*
X1235472D01*
X1231868Y1076453D01*
X1230850D01*
X1229942Y1075545D01*
X1228924D01*
X1228018Y1076451D01*
Y1077469D01*
X1228926Y1078377D01*
Y1079395D01*
X1227835Y1080486D01*
X1216957D01*
X1216237Y1079766D01*
Y1078527D01*
X1215517Y1077807D01*
X1214237D01*
X1213517Y1078527D01*
Y1079766D01*
X1212797Y1080486D01*
X1194958D01*
X1191581Y1083863D01*
X1189419D01*
X1188421Y1084861D01*
X1187403D01*
X1186644Y1084102D01*
X1185626D01*
X1184720Y1085008D01*
Y1086026D01*
X1185479Y1086785D01*
Y1087803D01*
X1183552Y1089730D01*
X1173037D01*
X1169690Y1093077D01*
X1166832D01*
X1165445Y1094464D01*
X1164112D01*
X1162725Y1093077D01*
X1158265D01*
X1154819Y1096523D01*
X1151579D01*
X1147583Y1100519D01*
X1145738D01*
X1143360Y1102897D01*
X1137271D01*
X1134449Y1105719D01*
X1131082D01*
X1129605Y1107196D01*
X1128616Y1107606D01*
X1128226Y1108545D01*
X1128503Y1109212D01*
X1128113Y1110152D01*
X1126930Y1110643D01*
X1125990Y1110253D01*
X1125713Y1109587D01*
X1124773Y1109197D01*
X1122005Y1110344D01*
X1119990D01*
X1117783Y1108137D01*
G01X1303068Y1042200D02*
X1298759D01*
X1286235Y1047387D01*
X1265605D01*
X1248519Y1054466D01*
X1236721Y1066264D01*
X1234976D01*
X1231021Y1070219D01*
X1225783D01*
X1222994Y1073008D01*
X1217818D01*
X1216629Y1071819D01*
X1215098D01*
X1213909Y1073008D01*
X1203504D01*
X1202784Y1073728D01*
Y1075781D01*
X1202064Y1076501D01*
X1200784D01*
X1200064Y1075781D01*
Y1073728D01*
X1199344Y1073008D01*
X1195968D01*
X1192643Y1076333D01*
X1187043D01*
X1180339Y1083037D01*
X1178287D01*
X1178286Y1083038D01*
X1176404D01*
X1176403Y1083037D01*
X1173422D01*
X1170075Y1086384D01*
X1167545D01*
X1166186Y1087743D01*
X1164825D01*
X1163466Y1086384D01*
X1149544D01*
X1144820Y1091108D01*
Y1094639D01*
X1143250Y1096209D01*
X1137481D01*
X1134112Y1099578D01*
X1131969D01*
X1131249Y1098858D01*
Y1097191D01*
X1130529Y1096471D01*
X1129249D01*
X1128529Y1097191D01*
Y1098858D01*
X1127809Y1099578D01*
X1126529D01*
X1125809Y1098858D01*
Y1097191D01*
X1125089Y1096471D01*
X1123809D01*
X1123089Y1097191D01*
Y1098858D01*
X1122369Y1099578D01*
X1119649D01*
X1117783Y1101444D01*
G01X1303068Y1057006D02*
X1300536D01*
X1259535Y1073986D01*
X1240159Y1093362D01*
X1233777D01*
X1230820Y1096319D01*
X1225683D01*
X1222233Y1099769D01*
X1217409D01*
X1216689Y1099049D01*
Y1096165D01*
X1215969Y1095445D01*
X1214689D01*
X1213969Y1096165D01*
Y1099049D01*
X1213249Y1099769D01*
X1200425D01*
X1194022Y1106172D01*
Y1107288D01*
X1191500Y1109810D01*
X1188420D01*
X1187700Y1109090D01*
Y1108096D01*
X1186980Y1107376D01*
X1185700D01*
X1184980Y1108096D01*
Y1109090D01*
X1184260Y1109810D01*
X1175112D01*
X1171766Y1113156D01*
X1158970D01*
X1154800Y1117326D01*
X1146311D01*
X1140280Y1123357D01*
X1136173D01*
X1132633Y1126897D01*
X1128461D01*
X1127741Y1126177D01*
Y1124852D01*
X1127021Y1124132D01*
X1125741D01*
X1125021Y1124852D01*
Y1126177D01*
X1124301Y1126897D01*
X1119811D01*
X1117783Y1124869D01*
G01X1303068Y1051755D02*
X1299595D01*
X1287662Y1056697D01*
X1285374D01*
X1255478Y1069083D01*
X1242817Y1081744D01*
X1235065D01*
X1229090Y1087719D01*
X1225317D01*
X1223675Y1086077D01*
X1218023D01*
X1217533Y1086567D01*
X1215373D01*
X1214883Y1086077D01*
X1209831D01*
X1207352Y1088556D01*
X1203460D01*
X1202970Y1089046D01*
X1200810D01*
X1200320Y1088556D01*
X1196590D01*
X1192428Y1092718D01*
X1189359D01*
X1183318Y1098759D01*
X1179298D01*
X1178286Y1099771D01*
X1176404D01*
X1175307Y1098674D01*
X1172761D01*
X1169419Y1102016D01*
X1163246D01*
X1162144Y1103118D01*
X1160262D01*
X1159116Y1101972D01*
X1156061D01*
X1149735Y1108298D01*
X1146560D01*
X1139480Y1115378D01*
X1135130D01*
X1132721Y1117787D01*
X1121010D01*
X1120300Y1117077D01*
X1118882D01*
X1117783Y1118176D01*
G01X1303068Y1050535D02*
X1299352D01*
X1287419Y1055477D01*
X1285131D01*
X1254786Y1068048D01*
X1242311Y1080524D01*
X1234559D01*
X1228584Y1086499D01*
X1225823D01*
X1224181Y1084857D01*
X1209325D01*
X1206846Y1087336D01*
X1196084D01*
X1191922Y1091498D01*
X1188853D01*
X1182812Y1097539D01*
X1179393D01*
X1178278Y1096424D01*
X1176305D01*
X1175275Y1097454D01*
X1172255D01*
X1168913Y1100796D01*
X1163161D01*
X1162136Y1099771D01*
X1160163D01*
X1159182Y1100752D01*
X1155555D01*
X1149229Y1107078D01*
X1146054D01*
X1138974Y1114158D01*
X1134624D01*
X1132215Y1116567D01*
X1121516D01*
X1120806Y1115857D01*
X1118811D01*
X1117783Y1114829D01*
G01X1303068Y1061326D02*
X1300371D01*
X1262686Y1076926D01*
X1239316Y1100296D01*
X1234223D01*
X1231573Y1102946D01*
X1225384D01*
X1222796Y1105534D01*
X1210879D01*
X1209594Y1106819D01*
X1203508D01*
X1201033Y1109294D01*
X1198008D01*
X1193594Y1113708D01*
Y1115554D01*
X1191227Y1117921D01*
X1186320D01*
X1185690Y1118551D01*
Y1120548D01*
X1185060Y1121178D01*
X1183590D01*
X1182960Y1120548D01*
Y1118551D01*
X1182330Y1117921D01*
X1180428D01*
X1178500Y1119849D01*
X1169998D01*
X1169220Y1119071D01*
X1167272D01*
X1163147Y1123196D01*
X1150153D01*
X1148270Y1125079D01*
X1147252D01*
X1146267Y1124094D01*
X1145249D01*
X1144343Y1125000D01*
Y1126018D01*
X1145328Y1127003D01*
Y1128021D01*
X1143401Y1129948D01*
X1136782D01*
X1133411Y1133319D01*
X1119540D01*
X1117783Y1131562D01*
G01X1304264Y1066678D02*
X1300727D01*
X1266746Y1080750D01*
X1240737Y1106759D01*
X1236286D01*
X1233308Y1109737D01*
X1226151D01*
X1224017Y1111871D01*
Y1113681D01*
X1221079Y1116619D01*
X1205694D01*
X1198420Y1123893D01*
X1194366D01*
X1191156Y1127103D01*
X1189253D01*
X1183122Y1133234D01*
X1172584D01*
X1169236Y1136582D01*
X1156907D01*
X1156277Y1135952D01*
Y1133832D01*
X1155604Y1133159D01*
X1154177D01*
X1153547Y1133789D01*
Y1135952D01*
X1152917Y1136582D01*
X1148848D01*
X1146421Y1139009D01*
X1145531D01*
X1144010Y1137488D01*
X1143120D01*
X1142079Y1138529D01*
Y1139419D01*
X1143600Y1140940D01*
Y1141830D01*
X1141810Y1143620D01*
X1136848D01*
X1129829Y1150639D01*
X1128811D01*
X1124874Y1146702D01*
X1123856D01*
X1122950Y1147608D01*
Y1148626D01*
X1126887Y1152563D01*
Y1153581D01*
X1120299Y1160169D01*
Y1172550D01*
X1117783Y1175066D01*
G01X1304264Y1070727D02*
X1301199D01*
X1270648Y1083382D01*
X1240327Y1113703D01*
X1234289D01*
X1232170Y1115822D01*
X1227498D01*
X1222471Y1120849D01*
X1211341D01*
X1208471Y1123719D01*
X1205381D01*
X1198664Y1130436D01*
X1195392D01*
X1191876Y1133952D01*
X1189378D01*
X1183403Y1139927D01*
X1172850D01*
X1169503Y1143274D01*
X1167932D01*
X1166728Y1144478D01*
X1165202D01*
X1163998Y1143274D01*
X1158885D01*
X1157681Y1144478D01*
X1156155D01*
X1154951Y1143274D01*
X1153716D01*
X1153124Y1142682D01*
X1152142D01*
X1149809Y1145015D01*
Y1145905D01*
X1150747Y1146843D01*
Y1147835D01*
X1148213Y1150369D01*
X1144456D01*
X1143826Y1149739D01*
Y1148480D01*
X1143196Y1147850D01*
X1141826D01*
X1141069Y1148607D01*
Y1150815D01*
X1138907Y1152977D01*
X1137889Y1152978D01*
X1137333Y1152422D01*
X1136315D01*
X1135409Y1153328D01*
Y1154346D01*
X1135965Y1154902D01*
Y1155919D01*
X1134038Y1157846D01*
X1129688D01*
X1126683Y1160851D01*
Y1165178D01*
X1127403Y1165898D01*
X1128971D01*
X1129691Y1166618D01*
Y1167898D01*
X1128971Y1168618D01*
X1127403D01*
X1126683Y1169338D01*
Y1170618D01*
X1127403Y1171338D01*
X1128971D01*
X1129691Y1172058D01*
Y1173338D01*
X1128971Y1174058D01*
X1127403D01*
X1126683Y1174778D01*
Y1177554D01*
X1124802Y1179435D01*
X1120107D01*
X1117783Y1181759D01*
G01X1304264Y1076032D02*
X1301830D01*
X1276438Y1086550D01*
X1243394Y1119605D01*
X1236317D01*
X1230048Y1125874D01*
X1225314D01*
X1221416Y1129772D01*
X1210619D01*
X1209159Y1130377D01*
X1207941Y1131191D01*
X1201046Y1138087D01*
X1190772Y1142345D01*
X1184251Y1148866D01*
X1179252D01*
X1178150Y1149968D01*
X1176230D01*
X1175174Y1148912D01*
X1172960D01*
X1171096Y1150776D01*
X1167629Y1152213D01*
X1162954D01*
X1161852Y1153315D01*
X1160262D01*
X1159116Y1152169D01*
X1156947D01*
X1152880Y1156236D01*
X1146553D01*
X1140336Y1162453D01*
X1138170D01*
X1136665Y1163958D01*
Y1182126D01*
X1133396Y1185395D01*
X1127484Y1187844D01*
X1123832Y1191496D01*
X1121056D01*
X1120288Y1190728D01*
X1118853D01*
X1117783Y1191798D01*
G01X1304264Y1074812D02*
X1301587D01*
X1275746Y1085515D01*
X1274220Y1087042D01*
X1273526D01*
X1271998Y1088571D01*
X1271999Y1089264D01*
X1270472Y1090791D01*
X1269779D01*
X1268251Y1092320D01*
Y1093013D01*
X1266724Y1094540D01*
X1266031D01*
X1264503Y1096069D01*
Y1096762D01*
X1262976Y1098289D01*
X1262283D01*
X1260755Y1099818D01*
X1260756Y1100511D01*
X1259229Y1102038D01*
X1258536D01*
X1257008Y1103567D01*
Y1104260D01*
X1255481Y1105787D01*
X1254788D01*
X1253260Y1107316D01*
Y1108009D01*
X1251733Y1109536D01*
X1251040D01*
X1249512Y1111065D01*
X1249513Y1111758D01*
X1247986Y1113285D01*
X1247293D01*
X1245765Y1114814D01*
Y1115507D01*
X1242888Y1118385D01*
X1235811D01*
X1233290Y1120906D01*
X1232597D01*
X1231069Y1122434D01*
Y1123127D01*
X1229542Y1124654D01*
X1224808D01*
X1220910Y1128552D01*
X1210376D01*
X1208581Y1129295D01*
X1207163Y1130243D01*
X1204736Y1132670D01*
X1204043D01*
X1202514Y1134199D01*
Y1134892D01*
X1200354Y1137052D01*
X1196118Y1138807D01*
X1195477Y1138542D01*
X1193481Y1139369D01*
X1193216Y1140011D01*
X1190080Y1141310D01*
X1188327Y1143063D01*
X1187634Y1143064D01*
X1186106Y1144592D01*
Y1145285D01*
X1183745Y1147646D01*
X1179119D01*
X1178094Y1146621D01*
X1176305D01*
X1175234Y1147692D01*
X1172454D01*
X1170404Y1149741D01*
X1167386Y1150993D01*
X1163055D01*
X1162030Y1149968D01*
X1160163D01*
X1159182Y1150949D01*
X1156441D01*
X1152374Y1155016D01*
X1146047D01*
X1139830Y1161233D01*
X1137664D01*
X1135445Y1163452D01*
Y1181620D01*
X1132704Y1184360D01*
X1126792Y1186809D01*
X1123326Y1190276D01*
X1121562D01*
X1120794Y1189508D01*
X1118839D01*
X1117783Y1188452D01*
G01X1304264Y1085558D02*
X1302950D01*
X1287747Y1091855D01*
X1240734Y1138870D01*
X1236310D01*
X1229363Y1145817D01*
X1223620D01*
X1219372Y1150065D01*
X1217552D01*
X1216301Y1148814D01*
X1213736D01*
X1212582Y1149968D01*
X1206572D01*
X1204959Y1151581D01*
Y1152471D01*
X1205758Y1153270D01*
Y1154160D01*
X1204717Y1155201D01*
X1203827D01*
X1203028Y1154402D01*
X1202138D01*
X1200274Y1156266D01*
X1196686D01*
X1193756Y1159196D01*
Y1162224D01*
X1190353Y1165627D01*
X1189335D01*
X1188494Y1164786D01*
X1187476D01*
X1186570Y1165692D01*
Y1166710D01*
X1187411Y1167551D01*
Y1168569D01*
X1185933Y1170047D01*
X1175994D01*
X1169302Y1176739D01*
X1166861D01*
X1166141Y1176019D01*
Y1173317D01*
X1165421Y1172597D01*
X1164141D01*
X1163421Y1173317D01*
Y1176019D01*
X1162701Y1176739D01*
X1157588D01*
X1154205Y1180122D01*
Y1189273D01*
X1150650Y1192828D01*
X1147030D01*
X1142283Y1197575D01*
X1136211D01*
X1133380Y1200406D01*
X1130010D01*
X1123457Y1206959D01*
X1119558D01*
X1117783Y1205184D01*
G01X1304264Y1081571D02*
X1302090D01*
X1283286Y1089360D01*
X1241077Y1131569D01*
X1234831D01*
X1225270Y1141130D01*
X1218042D01*
X1217322Y1140410D01*
Y1138746D01*
X1216602Y1138026D01*
X1215322D01*
X1214602Y1138746D01*
Y1140410D01*
X1213882Y1141130D01*
X1210942D01*
X1208258Y1143814D01*
X1205280D01*
X1197516Y1151578D01*
X1194432D01*
X1191373Y1154637D01*
X1190355D01*
X1189525Y1153808D01*
X1188507D01*
X1187601Y1154714D01*
Y1155732D01*
X1188431Y1156562D01*
Y1157579D01*
X1187525Y1158485D01*
X1186507D01*
X1185677Y1157656D01*
X1184659D01*
X1183753Y1158562D01*
Y1159580D01*
X1184583Y1160410D01*
Y1161427D01*
X1182656Y1163354D01*
X1167425D01*
X1164079Y1166700D01*
X1157309D01*
X1155974Y1165365D01*
X1150881D01*
X1145636Y1170610D01*
Y1186049D01*
X1141861Y1189824D01*
X1128122Y1195515D01*
X1123304Y1200333D01*
X1119625D01*
X1117783Y1198491D01*
G01X1360112Y995202D02*
Y994632D01*
X1359560Y994080D01*
X1322693D01*
X1320476Y991863D01*
X1297482D01*
X1287222Y981603D01*
X1276907D01*
X1264644Y993866D01*
X1246375D01*
X1234819Y989080D01*
X1232299Y986560D01*
X1230093Y985646D01*
X1224930D01*
X1221738Y988838D01*
X1210560D01*
X1206691Y984969D01*
X1194105D01*
X1191400Y982264D01*
X1182815Y980099D01*
X1180861Y979499D01*
X1179481Y978119D01*
Y977249D01*
X1178181Y975949D01*
X1175861D01*
X1166079Y971057D01*
X1162647Y969256D01*
X1145473D01*
X1143524Y967307D01*
X1133679Y963230D01*
X1131341Y960892D01*
G01X1362094Y995202D02*
Y993318D01*
X1360837Y992061D01*
X1322728D01*
X1321209Y990542D01*
X1298031D01*
X1287771Y980282D01*
X1275456D01*
X1263914Y991824D01*
X1246875D01*
X1241093Y989430D01*
X1237811Y986148D01*
X1230530Y983133D01*
X1224195D01*
X1220644Y986684D01*
X1211380D01*
X1207567Y982871D01*
X1198451D01*
X1196916Y982657D01*
X1191391Y979875D01*
X1187143Y978641D01*
X1179558Y972602D01*
X1175961D01*
X1170565Y970205D01*
X1167071Y969261D01*
X1162501Y965909D01*
X1160003D01*
X1159230Y965136D01*
X1153017Y962563D01*
X1143558D01*
X1142788Y963333D01*
X1139593D01*
X1135385Y961590D01*
X1131341Y957546D01*
G01X1364303Y995202D02*
Y992467D01*
X1361822Y989986D01*
X1322603D01*
X1321838Y989221D01*
X1298580D01*
X1288320Y978961D01*
X1274005D01*
X1263377Y989589D01*
X1247225D01*
X1242171Y987496D01*
X1238682Y984007D01*
X1229702Y980287D01*
X1228370Y978955D01*
X1225243D01*
X1222042Y982156D01*
X1217746D01*
X1217026Y982876D01*
Y984004D01*
X1216306Y984724D01*
X1215026D01*
X1214306Y984004D01*
Y982876D01*
X1213586Y982156D01*
X1210866D01*
X1209458Y980748D01*
Y977429D01*
X1208076Y976047D01*
X1203987D01*
X1203267Y976767D01*
Y980015D01*
X1202547Y980735D01*
X1201267D01*
X1200547Y980015D01*
Y976767D01*
X1199827Y976047D01*
X1195578D01*
X1194620Y975089D01*
X1192806D01*
X1192086Y974369D01*
Y973420D01*
X1191366Y972700D01*
X1190086D01*
X1189366Y973420D01*
Y974369D01*
X1188646Y975089D01*
X1185926D01*
X1184177Y973340D01*
Y970248D01*
X1182908Y968979D01*
X1178566D01*
X1178289Y969256D01*
X1173474D01*
X1169997Y965779D01*
X1165928D01*
X1161041Y960892D01*
G01X1370312Y995202D02*
Y993420D01*
X1364569Y987677D01*
X1298906D01*
X1288869Y977640D01*
X1272553D01*
X1263003Y987190D01*
X1247844D01*
X1244123Y985649D01*
X1237649Y979175D01*
X1231012Y976426D01*
X1224276D01*
X1220964Y979738D01*
X1218843D01*
X1217552Y978447D01*
Y977131D01*
X1215721Y975300D01*
X1213179D01*
X1209889Y972010D01*
X1204748D01*
X1204118Y971380D01*
Y970094D01*
X1203488Y969464D01*
X1202018D01*
X1201388Y970094D01*
Y971380D01*
X1200758Y972010D01*
X1196488D01*
X1192743Y968265D01*
X1190641D01*
X1188955Y969951D01*
X1188065D01*
X1183948Y965834D01*
Y964944D01*
X1185043Y963849D01*
Y959827D01*
X1184446Y959230D01*
X1171986D01*
X1171479Y959737D01*
Y962119D01*
X1170793Y962805D01*
X1166300D01*
X1161041Y957546D01*
G01X1304963Y981486D02*
X1299848D01*
X1290960Y972598D01*
X1269560D01*
X1261831Y980327D01*
X1248651D01*
X1238175Y969851D01*
X1234878D01*
X1233050Y968023D01*
X1230303D01*
X1227693Y970633D01*
X1223889D01*
X1221409Y968153D01*
X1215194D01*
X1213580Y966539D01*
Y963378D01*
X1212314Y962112D01*
X1210128D01*
X1209403Y962837D01*
X1204448D01*
X1203404Y961793D01*
X1201818D01*
X1200774Y962837D01*
X1197823D01*
X1192167Y960572D01*
X1191061D01*
X1190741Y960892D01*
G01X1304963Y983956D02*
X1300448D01*
X1290411Y973919D01*
X1271012D01*
X1261891Y983040D01*
X1247885D01*
X1237446Y972601D01*
X1219178D01*
X1216841Y971633D01*
X1212251Y968618D01*
X1209054Y966519D01*
X1207620Y965925D01*
X1197465Y964862D01*
X1194337Y963791D01*
X1192052Y962695D01*
X1191775Y962562D01*
X1191772Y962565D01*
X1189802D01*
X1188771Y961534D01*
Y959516D01*
X1190741Y957546D01*
G01X1304963Y977592D02*
X1297856D01*
X1291531Y971267D01*
X1268119D01*
X1261702Y977684D01*
X1249589D01*
X1236746Y964841D01*
X1224390D01*
X1220441Y960892D01*
G01X1304963Y976160D02*
X1298320D01*
X1292038Y969878D01*
X1266736D01*
X1261265Y975349D01*
X1250212D01*
X1237578Y962715D01*
X1225610D01*
X1220441Y957546D01*
G01X1715841Y1061286D02*
X1718155Y1058972D01*
Y1016213D01*
X1717219Y1015277D01*
X1574475D01*
X1569918Y1019834D01*
X1548994D01*
X1540460Y1018136D01*
X1528512Y1013188D01*
X1522918D01*
X1520629Y1010899D01*
G02X1518779I-925J1602D01*
G03X1516929I-925J-1602D01*
G02X1515079I-925J1602D01*
G01X1515041Y1010921D01*
G03X1513228Y1010899I-887J-1624D01*
G02X1511378I-925J1602D01*
G03X1509528I-925J-1602D01*
G02X1507678I-925J1602D01*
G03X1505828I-925J-1602D01*
G02X1503978I-925J1602D01*
G03X1502128I-925J-1602D01*
G01X1502075Y1010868D01*
G02X1500278Y1010899I-871J1633D01*
G03X1498428I-925J-1602D01*
G02X1496578I-925J1602D01*
G03X1494728I-925J-1602D01*
G01X1494675Y1010868D01*
G02X1492878Y1010899I-871J1633D01*
G03X1491028I-925J-1602D01*
G01X1490975Y1010868D01*
G02X1489178Y1010899I-871J1633D01*
G03X1487328I-925J-1602D01*
G01X1487290Y1010877D01*
G02X1485479Y1010899I-886J1624D01*
G03X1483629I-925J-1602D01*
G01X1483591Y1010877D01*
G02X1481778Y1010899I-887J1624D01*
G03X1479928I-925J-1602D01*
G02X1478078I-925J1602D01*
G03X1476228I-925J-1602D01*
G01X1476175Y1010868D01*
G02X1474378Y1010899I-871J1633D01*
G03X1472528I-925J-1602D01*
G02X1470678I-925J1602D01*
G03X1468828I-925J-1602D01*
G02X1466978I-925J1602D01*
G03X1465128I-925J-1602D01*
G01X1465075Y1010868D01*
G02X1463278Y1010899I-871J1633D01*
G03X1461428I-925J-1602D01*
G01X1461390Y1010877D01*
G02X1459579Y1010899I-886J1624D01*
G03X1457688I-946J-1638D01*
G01X1454961Y1009325D01*
X1454953Y1009297D01*
G01X1775241Y810302D02*
X1772305Y807366D01*
X1767321D01*
X1766691Y807996D01*
Y809038D01*
X1766061Y809668D01*
X1764591D01*
X1763961Y809038D01*
Y807996D01*
X1763331Y807366D01*
X1758018D01*
X1756350Y809034D01*
X1752876D01*
X1751718Y807876D01*
Y806986D01*
X1752829Y805875D01*
Y804985D01*
X1751788Y803944D01*
X1750898D01*
X1750323Y804519D01*
X1744661D01*
X1742538Y806642D01*
X1739818D01*
X1738461Y805285D01*
X1723695D01*
X1720350Y808630D01*
X1709550D01*
X1705400Y812780D01*
X1698461D01*
Y812719D01*
X1696643Y810901D01*
X1692012D01*
X1691382Y811531D01*
Y813349D01*
X1690752Y813979D01*
X1689282D01*
X1688652Y813349D01*
Y811531D01*
X1688022Y810901D01*
X1683786D01*
X1682714Y811973D01*
X1678111D01*
X1674769Y815315D01*
X1667637D01*
X1667033Y815919D01*
X1664863D01*
X1660922Y811978D01*
X1640795D01*
X1639584Y810767D01*
X1635165D01*
X1634088Y811844D01*
X1632435D01*
X1631358Y810767D01*
X1629705D01*
X1628486Y811986D01*
X1619929D01*
X1618564Y810621D01*
X1617098D01*
X1614999Y812720D01*
X1611663D01*
X1610279Y811336D01*
X1596049D01*
X1579392Y827993D01*
Y829402D01*
X1525009Y883785D01*
G01X1775241Y840420D02*
X1771755Y843906D01*
X1768256D01*
X1767626Y844536D01*
Y846138D01*
X1766996Y846768D01*
X1765526D01*
X1764896Y846138D01*
Y844536D01*
X1764266Y843906D01*
X1758848D01*
X1756876Y841934D01*
X1751671D01*
X1750951Y842654D01*
Y846616D01*
X1750231Y847336D01*
X1748941D01*
X1748221Y846616D01*
Y842654D01*
X1747501Y841934D01*
X1744426D01*
X1742839Y843521D01*
X1739863D01*
X1738437Y842095D01*
X1723755D01*
X1720413Y845437D01*
X1709683D01*
X1708853Y844607D01*
X1699649D01*
X1696961Y841919D01*
X1694161D01*
X1687281Y848799D01*
X1660560D01*
X1657240Y852119D01*
X1655747D01*
X1654792Y851164D01*
X1650376D01*
X1644506Y845294D01*
X1640136D01*
X1636561Y841719D01*
X1633444D01*
X1632724Y842439D01*
Y843881D01*
X1632004Y844601D01*
X1630714D01*
X1629994Y843881D01*
Y842439D01*
X1629274Y841719D01*
X1624886D01*
X1623724Y842881D01*
X1620224D01*
X1618261Y844844D01*
X1611086D01*
X1608888Y847042D01*
X1603908D01*
X1603188Y846322D01*
Y844358D01*
X1602468Y843638D01*
X1601178D01*
X1600458Y844358D01*
Y846322D01*
X1599738Y847042D01*
X1591188D01*
X1533499Y904731D01*
X1527565D01*
G01X1775241Y833727D02*
X1773616Y835402D01*
X1768426D01*
X1767796Y836032D01*
Y836538D01*
X1767166Y837168D01*
X1765696D01*
X1765066Y836538D01*
Y836032D01*
X1764436Y835402D01*
X1738961D01*
X1738241Y834682D01*
Y833222D01*
X1737521Y832502D01*
X1736231D01*
X1735511Y833222D01*
Y834682D01*
X1734791Y835402D01*
X1721977D01*
X1718631Y838748D01*
X1700190D01*
X1696761Y835319D01*
X1691061D01*
X1684285Y842095D01*
X1679895D01*
X1679265Y841465D01*
Y838798D01*
X1678635Y838168D01*
X1677165D01*
X1676535Y838798D01*
Y841465D01*
X1675905Y842095D01*
X1671016D01*
X1669843Y843268D01*
X1668286D01*
X1667113Y842095D01*
X1661583D01*
X1658237Y845441D01*
X1650883D01*
X1643886Y838444D01*
X1640486D01*
X1636379Y834337D01*
X1633357D01*
X1632637Y835057D01*
Y836725D01*
X1631917Y837445D01*
X1630627D01*
X1629907Y836725D01*
Y835057D01*
X1629187Y834337D01*
X1624843D01*
X1623111Y836069D01*
X1619611D01*
X1617361Y838319D01*
X1610861D01*
X1609844Y839336D01*
X1603995D01*
X1603275Y838616D01*
Y836651D01*
X1602555Y835931D01*
X1601265D01*
X1600545Y836651D01*
Y838616D01*
X1599825Y839336D01*
X1592625D01*
X1531197Y900764D01*
X1524465D01*
G01X1775241Y816995D02*
X1773265Y815019D01*
X1768298D01*
X1767668Y815649D01*
Y817080D01*
X1767038Y817710D01*
X1765568D01*
X1764938Y817080D01*
Y815649D01*
X1764308Y815019D01*
X1757387D01*
X1756146Y816260D01*
X1752776D01*
X1747935Y811419D01*
X1744735D01*
X1742661Y813493D01*
X1736461D01*
X1734946Y811978D01*
X1723602D01*
X1720256Y815324D01*
X1709056D01*
X1704278Y820102D01*
X1699144D01*
X1697361Y818319D01*
X1693976D01*
X1691999Y820296D01*
X1688838D01*
X1687209Y818667D01*
X1678663Y818668D01*
X1678033Y819298D01*
Y821238D01*
X1677256Y822015D01*
X1667682Y822014D01*
X1667177Y822519D01*
X1665463D01*
X1663359Y820415D01*
X1661609D01*
X1660889Y821135D01*
Y822835D01*
X1660169Y823555D01*
X1659039D01*
X1658169Y822685D01*
Y819445D01*
X1657395Y818671D01*
X1650030D01*
X1649400Y819301D01*
Y822038D01*
X1648770Y822668D01*
X1647300D01*
X1646670Y822038D01*
Y819301D01*
X1646040Y818671D01*
X1624209D01*
X1622694Y820186D01*
X1611229D01*
X1609462Y818419D01*
X1596365D01*
X1526989Y887795D01*
G01X1775241Y823688D02*
X1774230Y824699D01*
X1772668D01*
X1771347Y823378D01*
X1760869D01*
X1754179Y826149D01*
X1746985D01*
X1740418Y823429D01*
X1738032D01*
X1735002Y826459D01*
X1733765D01*
X1732670Y825364D01*
X1731302D01*
X1730207Y826459D01*
X1722624D01*
X1719277Y829806D01*
X1717637D01*
X1716542Y828711D01*
X1715136D01*
X1714075Y829772D01*
X1702882D01*
X1696435Y827102D01*
X1683851D01*
X1682124Y828829D01*
X1679386D01*
X1675124Y833091D01*
X1674299D01*
X1673266Y832058D01*
X1671890D01*
X1670833Y833115D01*
X1663266D01*
X1659881Y836500D01*
X1658221D01*
X1657126Y835405D01*
X1655756D01*
X1654668Y836493D01*
X1651915D01*
X1644741Y829319D01*
X1639379D01*
X1636368Y826308D01*
X1625145D01*
X1622640Y828813D01*
X1618464D01*
X1617974Y828323D01*
X1615824D01*
X1615334Y828813D01*
X1609296D01*
X1607212Y826729D01*
X1603647D01*
X1603157Y826239D01*
X1601007D01*
X1600517Y826729D01*
X1596593D01*
X1590194Y833128D01*
Y834238D01*
X1528869Y895563D01*
X1524373D01*
G01X1775241Y827034D02*
X1774126Y825919D01*
X1772162D01*
X1770841Y824598D01*
X1761112D01*
X1754422Y827369D01*
X1746742D01*
X1740175Y824649D01*
X1738538D01*
X1735508Y827679D01*
X1733695D01*
X1732670Y828704D01*
X1731304D01*
X1730279Y827679D01*
X1723130D01*
X1719783Y831026D01*
X1717553D01*
X1716528Y832051D01*
X1715124D01*
X1714065Y830992D01*
X1702639D01*
X1696192Y828322D01*
X1684357D01*
X1682630Y830049D01*
X1679892D01*
X1675630Y834311D01*
X1674407D01*
X1673320Y835398D01*
X1671858D01*
X1670795Y834335D01*
X1663772D01*
X1660387Y837720D01*
X1658169D01*
X1657144Y838745D01*
X1655718D01*
X1654686Y837713D01*
X1651409D01*
X1644235Y830539D01*
X1638873D01*
X1635862Y827528D01*
X1625651D01*
X1623146Y830033D01*
X1608790D01*
X1606706Y827949D01*
X1597099D01*
X1591414Y833634D01*
Y834744D01*
X1529375Y896783D01*
X1524373D01*
G01X1731983Y873885D02*
X1727695Y878173D01*
X1722129D01*
X1719516Y875560D01*
X1701020D01*
X1698061Y878519D01*
X1690725D01*
X1686125Y883119D01*
X1684861D01*
X1681661Y886319D01*
X1676860D01*
X1674234Y888945D01*
X1662507D01*
X1659160Y892292D01*
X1650585D01*
X1649501Y891208D01*
X1646336D01*
X1645706Y891838D01*
Y891889D01*
X1645076Y892519D01*
X1640961D01*
X1638587Y890145D01*
X1626823D01*
X1622446Y885768D01*
X1618347D01*
X1614830Y882251D01*
X1609461D01*
X1608162Y883550D01*
X1600260D01*
X1598961Y882251D01*
X1588900D01*
X1544225Y926926D01*
X1528199D01*
G01X1715841Y853806D02*
X1714145Y855502D01*
X1708776D01*
X1707642Y854368D01*
X1706046D01*
X1704923Y855491D01*
X1693689D01*
X1689093Y860087D01*
X1677548D01*
X1675461Y862174D01*
X1671824D01*
X1670730Y863268D01*
X1669094D01*
X1668000Y862174D01*
X1666364D01*
X1665270Y863268D01*
X1663634D01*
X1662540Y862174D01*
X1661664D01*
X1658317Y865521D01*
X1650587D01*
X1649904Y864838D01*
Y862898D01*
X1649274Y862268D01*
X1647804D01*
X1647174Y862898D01*
Y864838D01*
X1646544Y865468D01*
X1643911D01*
X1643211Y866168D01*
X1641410D01*
X1639105Y863863D01*
Y862973D01*
X1640766Y861312D01*
Y860422D01*
X1639725Y859381D01*
X1638835D01*
X1637174Y861042D01*
X1636284D01*
X1630723Y855481D01*
X1617610D01*
X1614193Y858898D01*
X1590429D01*
X1536809Y912518D01*
X1528009D01*
G01X1715841Y847113D02*
X1713331Y849623D01*
X1700745D01*
X1699491Y848369D01*
X1694211D01*
X1689461Y853119D01*
X1684561D01*
X1681861Y855819D01*
X1679513D01*
X1678883Y855189D01*
Y853585D01*
X1678163Y852865D01*
X1676138D01*
X1673511Y855492D01*
X1667065D01*
X1665778Y854205D01*
X1662651D01*
X1658021Y858835D01*
X1652703D01*
X1648565Y854697D01*
X1647547D01*
X1645693Y856551D01*
X1644675D01*
X1643762Y855638D01*
Y854620D01*
X1645616Y852766D01*
Y851748D01*
X1644383Y850515D01*
X1639157D01*
X1636961Y848319D01*
X1634411D01*
X1632911Y849819D01*
X1631311D01*
X1629811Y848319D01*
X1624440D01*
X1623540Y849219D01*
X1614764D01*
X1611195Y852788D01*
X1603956D01*
X1603236Y852068D01*
Y851575D01*
X1602516Y850855D01*
X1601226D01*
X1600506Y851575D01*
Y852068D01*
X1599786Y852788D01*
X1590728D01*
X1535055Y908461D01*
X1527565D01*
G01X1715841Y870538D02*
X1713580D01*
X1711761Y868719D01*
X1701461D01*
X1697955Y872225D01*
X1690847D01*
X1687253Y875819D01*
X1685561D01*
X1681661Y879719D01*
X1677061D01*
X1674527Y882253D01*
X1662828D01*
X1659481Y885600D01*
X1654742D01*
X1653375Y886967D01*
X1649620D01*
X1648900Y886247D01*
Y884081D01*
X1648180Y883361D01*
X1646890D01*
X1646170Y884081D01*
Y886247D01*
X1645450Y886967D01*
X1642809D01*
X1638661Y882819D01*
X1635161D01*
X1633296Y880954D01*
X1632406D01*
X1630397Y882963D01*
X1629507D01*
X1628466Y881922D01*
Y881032D01*
X1630475Y879023D01*
Y878133D01*
X1627916Y875574D01*
X1627254D01*
X1626624Y876204D01*
Y878238D01*
X1625994Y878868D01*
X1624524D01*
X1623894Y878238D01*
Y876277D01*
X1623174Y875557D01*
X1604698D01*
X1603259Y874118D01*
X1600417D01*
X1598820Y875715D01*
X1589473D01*
X1542197Y922991D01*
X1527566D01*
G01X1715841Y860499D02*
X1714811Y861529D01*
X1712808D01*
X1711765Y860486D01*
X1699867D01*
X1696154Y864199D01*
X1684188D01*
X1681358Y867029D01*
X1679624D01*
X1676755Y869898D01*
X1674292D01*
X1673262Y868868D01*
X1671898D01*
X1670783Y869983D01*
X1664370D01*
X1661007Y873346D01*
X1658311D01*
X1657180Y872215D01*
X1655708D01*
X1654640Y873283D01*
X1645032D01*
X1634041Y868730D01*
X1626229Y860919D01*
X1620785D01*
X1615633Y866071D01*
X1611413D01*
X1609202Y863860D01*
X1591560D01*
X1538802Y916618D01*
X1530642D01*
X1529612Y916619D01*
X1527473D01*
G01X1715841Y863845D02*
X1714745Y862749D01*
X1712302D01*
X1711259Y861706D01*
X1700373D01*
X1696660Y865419D01*
X1684694D01*
X1681864Y868249D01*
X1680130D01*
X1677261Y871118D01*
X1674375D01*
X1673285Y872208D01*
X1671818D01*
X1670813Y871203D01*
X1664876D01*
X1661513Y874566D01*
X1658284D01*
X1657295Y875555D01*
X1655706D01*
X1654654Y874503D01*
X1644789D01*
X1633349Y869765D01*
X1630548Y866964D01*
X1629855D01*
X1628333Y865442D01*
Y864749D01*
X1625723Y862139D01*
X1621291D01*
X1616139Y867291D01*
X1610907D01*
X1608696Y865080D01*
X1602910D01*
X1602420Y865570D01*
X1600270D01*
X1599780Y865080D01*
X1592066D01*
X1590546Y866600D01*
Y867293D01*
X1589025Y868814D01*
X1588332D01*
X1539308Y917838D01*
X1530643D01*
X1529613Y917839D01*
X1527473D01*
G01X1715841Y907349D02*
X1713971Y909219D01*
X1710553D01*
X1707733Y912039D01*
X1706715D01*
X1705789Y911113D01*
X1704771D01*
X1703858Y912026D01*
Y913044D01*
X1704784Y913970D01*
Y914988D01*
X1703078Y916694D01*
X1701110D01*
X1700389Y917415D01*
Y920705D01*
X1699729Y921365D01*
X1698709D01*
X1698058Y920714D01*
X1697040D01*
X1696159Y921595D01*
Y922925D01*
X1697197Y923963D01*
Y924983D01*
X1695811Y926369D01*
X1690811D01*
X1688761Y928419D01*
X1684721D01*
X1682118Y931022D01*
X1678777D01*
X1676857Y929102D01*
X1670569D01*
X1669182Y927715D01*
X1664137D01*
X1659403Y932449D01*
X1650692D01*
X1649615Y931372D01*
X1647214D01*
X1645767Y932819D01*
X1643787D01*
X1642340Y931372D01*
X1640324D01*
X1638877Y932819D01*
X1630321D01*
X1626291Y928789D01*
X1623757D01*
X1621227Y931319D01*
X1610661D01*
X1607310Y927968D01*
X1594508D01*
X1593878Y928598D01*
Y930038D01*
X1593248Y930668D01*
X1591778D01*
X1591148Y930038D01*
Y928598D01*
X1590518Y927968D01*
X1589048D01*
X1588418Y928598D01*
Y930038D01*
X1587788Y930668D01*
X1586318D01*
X1585688Y930038D01*
Y928598D01*
X1585058Y927968D01*
X1580507D01*
X1559420Y949055D01*
X1529066D01*
G01X1715841Y890617D02*
X1713663D01*
X1711870Y892410D01*
X1707662D01*
X1705685Y894387D01*
X1700593D01*
X1696883Y898097D01*
X1693635D01*
X1688161Y903571D01*
Y905819D01*
X1687297Y906683D01*
X1684325D01*
X1683261Y905619D01*
X1680361D01*
X1676955Y909025D01*
X1662555D01*
X1659209Y912371D01*
X1653913D01*
X1653124Y911582D01*
X1649936D01*
X1648450Y913068D01*
X1645676D01*
X1644966Y912358D01*
X1633590D01*
X1630251Y909019D01*
X1621174D01*
X1619955Y907800D01*
X1615584D01*
X1614359Y909025D01*
X1611791D01*
X1611161Y909655D01*
Y912398D01*
X1610531Y913028D01*
X1609061D01*
X1608431Y912398D01*
Y909655D01*
X1607801Y909025D01*
X1601803D01*
X1598458Y912370D01*
X1593575D01*
X1592855Y913090D01*
Y914235D01*
X1592135Y914955D01*
X1590845D01*
X1590125Y914235D01*
Y913090D01*
X1589405Y912370D01*
X1588115D01*
X1587395Y913090D01*
Y914235D01*
X1586675Y914955D01*
X1585385D01*
X1584665Y914235D01*
Y913090D01*
X1583945Y912370D01*
X1582655D01*
X1581935Y913090D01*
Y914235D01*
X1581215Y914955D01*
X1579925D01*
X1579205Y914235D01*
Y913090D01*
X1578485Y912370D01*
X1575453D01*
X1549252Y938571D01*
X1529066D01*
G01X1715841Y883924D02*
X1715741D01*
X1713562Y886103D01*
X1708677D01*
X1706261Y888519D01*
X1699661D01*
X1696687Y891493D01*
X1691411D01*
X1685736Y897168D01*
X1682032D01*
X1676869Y902331D01*
X1670889D01*
X1669752Y903468D01*
X1668159D01*
X1667022Y902331D01*
X1662749D01*
X1659403Y905677D01*
X1653219D01*
X1652561Y905019D01*
X1649612D01*
X1648892Y905739D01*
Y906339D01*
X1648172Y907059D01*
X1646882D01*
X1646162Y906339D01*
Y905739D01*
X1645442Y905019D01*
X1640607D01*
X1639328Y906298D01*
X1634421D01*
X1632975Y904852D01*
Y903962D01*
X1634945Y901992D01*
Y901102D01*
X1633904Y900061D01*
X1633014D01*
X1631044Y902031D01*
X1630154D01*
X1628255Y900132D01*
X1626328D01*
X1623290Y903170D01*
X1620330D01*
X1619700Y902540D01*
Y901598D01*
X1619070Y900968D01*
X1617600D01*
X1616970Y901598D01*
Y902540D01*
X1616340Y903170D01*
X1614776D01*
X1613937Y902331D01*
X1602249D01*
X1598904Y905676D01*
X1591544D01*
X1590824Y904956D01*
Y904350D01*
X1590104Y903630D01*
X1588814D01*
X1588094Y904350D01*
Y904956D01*
X1587374Y905676D01*
X1586084D01*
X1585364Y904956D01*
Y904350D01*
X1584644Y903630D01*
X1583354D01*
X1582634Y904350D01*
Y904956D01*
X1581914Y905676D01*
X1576301D01*
X1547431Y934546D01*
X1529066D01*
G01X1715841Y897310D02*
X1714754Y898397D01*
X1713466D01*
X1712826Y897757D01*
X1709698D01*
X1703926Y903529D01*
X1701551D01*
X1696761Y908319D01*
Y911231D01*
X1688273Y919719D01*
X1685321D01*
X1683121Y917519D01*
X1679561D01*
X1676960Y920120D01*
X1674399D01*
X1673344Y919065D01*
X1671814D01*
X1670719Y920160D01*
X1662487D01*
X1659193Y923454D01*
X1658173D01*
X1657130Y922411D01*
X1655758D01*
X1654724Y923445D01*
X1642135D01*
X1638539Y919849D01*
X1625091D01*
X1622671Y917429D01*
X1618989D01*
X1613999Y922419D01*
X1612237D01*
X1605590Y921097D01*
X1577518D01*
X1554730Y943885D01*
X1528974D01*
G01X1715841Y900656D02*
X1714802Y899617D01*
X1712960D01*
X1712320Y898977D01*
X1710204D01*
X1708166Y901015D01*
Y901708D01*
X1706645Y903229D01*
X1705952D01*
X1704432Y904749D01*
X1702057D01*
X1697981Y908825D01*
Y911737D01*
X1696461Y913257D01*
Y913950D01*
X1694940Y915471D01*
X1694247D01*
X1692513Y917205D01*
Y917898D01*
X1690992Y919419D01*
X1690299D01*
X1688779Y920939D01*
X1684815D01*
X1682615Y918739D01*
X1680067D01*
X1677466Y921340D01*
X1674326D01*
X1673261Y922405D01*
X1671840D01*
X1670815Y921380D01*
X1668427D01*
X1667937Y921870D01*
X1665787D01*
X1665297Y921380D01*
X1662993D01*
X1659699Y924674D01*
X1658218D01*
X1657141Y925751D01*
X1655726D01*
X1654640Y924665D01*
X1652570D01*
X1652080Y925155D01*
X1649930D01*
X1649440Y924665D01*
X1647290D01*
X1646800Y925155D01*
X1644650D01*
X1644160Y924665D01*
X1641629D01*
X1638033Y921069D01*
X1635883D01*
X1635393Y921559D01*
X1633243D01*
X1632753Y921069D01*
X1630194D01*
X1629704Y921559D01*
X1627554D01*
X1627064Y921069D01*
X1624585D01*
X1622165Y918649D01*
X1619495D01*
X1614505Y923639D01*
X1612116D01*
X1605469Y922317D01*
X1602241D01*
X1601751Y922807D01*
X1599601D01*
X1599111Y922317D01*
X1595218D01*
X1594728Y922807D01*
X1592578D01*
X1592088Y922317D01*
X1589327D01*
X1588837Y922807D01*
X1586687D01*
X1586197Y922317D01*
X1583452D01*
X1582962Y922807D01*
X1580812D01*
X1580322Y922317D01*
X1578024D01*
X1555236Y945105D01*
X1528974D01*
G01X1715841Y914042D02*
X1712285Y917598D01*
X1710782D01*
X1708507Y919873D01*
Y922497D01*
X1710509Y924499D01*
Y925497D01*
X1708560Y927446D01*
X1707670D01*
X1706647Y926423D01*
X1705757D01*
X1704570Y927610D01*
Y928628D01*
X1710116Y934174D01*
Y935272D01*
X1709243Y936145D01*
X1708225D01*
X1702639Y930559D01*
X1701621D01*
X1700426Y931754D01*
Y932772D01*
X1701555Y933901D01*
Y934919D01*
X1700642Y935832D01*
X1699624D01*
X1698495Y934703D01*
X1697477D01*
X1696385Y935795D01*
X1665609D01*
X1662269Y939135D01*
X1654042D01*
X1653131Y940046D01*
X1641288D01*
X1638481Y937239D01*
X1627175D01*
X1625294Y935358D01*
X1591185D01*
X1587208Y939335D01*
X1575454D01*
X1561812Y952977D01*
X1529060D01*
G01X1804941Y967585D02*
X1809610Y962916D01*
Y954339D01*
X1807810Y952539D01*
X1785531D01*
X1782175Y949183D01*
X1773924D01*
X1772570Y947829D01*
X1768327D01*
X1767607Y948549D01*
Y950757D01*
X1766887Y951477D01*
X1765597D01*
X1764877Y950757D01*
Y948549D01*
X1764157Y947829D01*
X1757821D01*
X1755451Y945459D01*
X1751996D01*
X1751276Y946179D01*
Y946934D01*
X1750556Y947654D01*
X1749266D01*
X1748546Y946934D01*
Y946179D01*
X1747826Y945459D01*
X1743341D01*
X1741981Y946819D01*
X1737481D01*
X1735117Y949183D01*
X1729397D01*
X1726050Y945836D01*
X1698259D01*
X1697040Y944617D01*
X1692773D01*
X1692053Y945337D01*
Y947503D01*
X1691333Y948223D01*
X1690043D01*
X1689323Y947503D01*
Y945337D01*
X1688603Y944617D01*
X1684459D01*
X1682181Y942339D01*
X1680031D01*
X1676534Y945836D01*
X1669231D01*
X1665885Y949182D01*
X1640534D01*
X1636671Y945319D01*
X1626361D01*
X1623511Y948169D01*
X1620071D01*
X1614396Y942494D01*
X1597422D01*
X1597421Y942493D01*
X1594388D01*
X1591030Y945851D01*
X1580410D01*
X1567417Y958844D01*
X1523181D01*
X1521921Y960104D01*
X1518713D01*
G01X1775241Y967585D02*
Y967485D01*
X1779111Y963615D01*
Y957920D01*
X1777067Y955876D01*
X1752928D01*
X1749569Y952517D01*
X1738205D01*
X1734846Y955876D01*
X1729778D01*
X1726431Y952529D01*
X1685591D01*
X1681921Y948859D01*
X1679981D01*
X1676311Y952529D01*
X1670883D01*
X1667537Y955875D01*
X1640197D01*
X1636451Y952129D01*
X1626141D01*
X1623402Y954868D01*
X1619946D01*
X1614078Y949000D01*
X1610730D01*
X1608988Y950742D01*
X1581323D01*
X1569301Y962764D01*
X1533362D01*
X1529406Y966720D01*
X1526347D01*
X1524612Y967438D01*
X1520452D01*
X1518441Y965427D01*
X1516187D01*
G01X1626641Y960892D02*
X1624971Y962562D01*
X1615602D01*
X1601595Y968364D01*
X1597806D01*
X1597176Y968606D01*
X1592521Y970534D01*
X1577597D01*
X1573178Y972364D01*
X1538732D01*
X1530058Y981038D01*
X1525239D01*
X1523866Y979665D01*
X1518178D01*
G01X1596941Y960892D02*
X1592538D01*
X1590931Y962499D01*
Y965343D01*
X1590211Y966063D01*
X1574174D01*
X1571793Y968444D01*
X1535978D01*
X1529658Y974764D01*
X1523765D01*
X1523156Y975373D01*
X1513663D01*
G01X1626641Y957546D02*
X1624966Y959221D01*
X1612439D01*
X1612101Y959361D01*
X1604556Y962486D01*
X1603660Y963382D01*
X1602931Y964063D01*
X1593354Y968029D01*
X1575045D01*
X1572670Y970404D01*
X1537183D01*
X1530822Y976765D01*
X1526796D01*
X1526195Y977366D01*
X1518235D01*
G01X1596941Y957546D02*
X1592355D01*
X1590721Y959180D01*
X1578219D01*
X1570915Y966484D01*
X1535160D01*
X1530904Y970740D01*
X1526716D01*
X1525615Y971196D01*
X1523538D01*
X1522908Y971826D01*
Y972535D01*
X1522278Y973165D01*
X1518212D01*
X1516455Y971408D01*
X1514742D01*
G01X1656441Y957546D02*
X1656341D01*
X1655072Y958815D01*
X1647895D01*
X1643949Y962761D01*
X1642114D01*
X1641513Y962160D01*
X1636011D01*
X1635291Y961440D01*
Y956379D01*
X1634571Y955659D01*
X1633281D01*
X1632561Y956379D01*
Y961440D01*
X1631841Y962160D01*
X1631179D01*
X1626988Y966351D01*
X1625689D01*
X1621989Y970051D01*
X1619476D01*
X1618756Y969331D01*
Y967774D01*
X1618036Y967054D01*
X1616746D01*
X1616026Y967774D01*
Y969331D01*
X1615306Y970051D01*
X1609489D01*
X1606913Y972627D01*
X1597396D01*
X1592608Y974610D01*
X1578046D01*
X1574487Y976084D01*
X1540867D01*
X1530637Y986314D01*
X1522039D01*
G01X1715841Y1091404D02*
X1713756Y1089319D01*
X1708054D01*
X1705654Y1086919D01*
X1700617D01*
X1696245Y1082547D01*
X1686975D01*
X1683997Y1079569D01*
Y1076838D01*
X1684717Y1076118D01*
X1687170D01*
X1687890Y1075398D01*
Y1074108D01*
X1687170Y1073388D01*
X1684717D01*
X1683997Y1072668D01*
Y1070206D01*
X1684717Y1069486D01*
X1687112D01*
X1687832Y1068766D01*
Y1067476D01*
X1687112Y1066756D01*
X1684717D01*
X1683997Y1066036D01*
Y1060377D01*
X1682004Y1058384D01*
X1679547D01*
X1678356Y1059575D01*
X1667280D01*
X1666711Y1060144D01*
X1662886D01*
X1660146Y1057404D01*
Y1055766D01*
X1660799Y1055113D01*
Y1053837D01*
X1659881Y1052919D01*
X1649828D01*
X1648609Y1054138D01*
X1645933D01*
X1644193Y1052398D01*
X1639186D01*
X1635941Y1049153D01*
X1631555D01*
X1627395Y1053313D01*
X1624116D01*
X1622462Y1051659D01*
X1619694D01*
X1618974Y1052379D01*
Y1053334D01*
X1618254Y1054054D01*
X1616964D01*
X1616244Y1053334D01*
Y1052379D01*
X1615524Y1051659D01*
X1610536D01*
X1608431Y1053764D01*
X1605173D01*
X1600287Y1048878D01*
X1595764D01*
X1586886Y1040000D01*
X1547077D01*
X1537418Y1038079D01*
X1529668D01*
G01X1715841Y1074672D02*
X1713388Y1072219D01*
X1709160D01*
X1704567Y1067626D01*
Y1040584D01*
X1703475Y1039492D01*
X1700707D01*
X1696741Y1035526D01*
X1692515D01*
X1691795Y1036246D01*
Y1038261D01*
X1691075Y1038981D01*
X1689785D01*
X1689065Y1038261D01*
Y1036246D01*
X1688345Y1035526D01*
X1684882D01*
X1683310Y1037098D01*
X1679212D01*
X1674958Y1032844D01*
X1670714D01*
X1668111Y1035447D01*
X1662812D01*
X1660209Y1032844D01*
X1653441D01*
X1652075Y1031478D01*
X1638683D01*
X1637244Y1032917D01*
X1633076D01*
X1632356Y1032197D01*
Y1031594D01*
X1631636Y1030874D01*
X1630346D01*
X1629626Y1031594D01*
Y1032197D01*
X1628906Y1032917D01*
X1624566D01*
X1623717Y1032068D01*
X1619700D01*
X1619070Y1032698D01*
Y1034235D01*
X1618440Y1034865D01*
X1616661D01*
X1616031Y1034235D01*
Y1032595D01*
X1615401Y1031965D01*
X1610563D01*
X1609556Y1032972D01*
X1596112D01*
X1592596Y1029456D01*
X1548140D01*
X1539090Y1027656D01*
X1529168D01*
G01X1715841Y1081365D02*
X1714847Y1082355D01*
X1713224D01*
X1712226Y1081357D01*
X1708526D01*
X1704422Y1077253D01*
X1701301D01*
X1697364Y1073316D01*
X1693855D01*
X1693127Y1072588D01*
Y1070272D01*
X1693617Y1069782D01*
Y1067632D01*
X1693127Y1067142D01*
Y1063524D01*
X1693617Y1063034D01*
Y1060884D01*
X1693127Y1060394D01*
Y1053934D01*
X1690975Y1051782D01*
Y1051089D01*
X1689453Y1049567D01*
X1688760D01*
X1686850Y1047657D01*
X1684324D01*
X1682324Y1049657D01*
X1679634D01*
X1677183Y1047206D01*
X1674621D01*
X1673644Y1046229D01*
X1671562D01*
X1670467Y1047324D01*
X1664717D01*
X1661253Y1043860D01*
X1658479D01*
X1657502Y1042883D01*
X1655420D01*
X1654408Y1043895D01*
X1643043D01*
X1635377Y1040720D01*
X1625554D01*
X1622845Y1043429D01*
X1609648D01*
X1606753Y1040534D01*
X1595725D01*
X1589940Y1034749D01*
X1548076D01*
X1538502Y1032844D01*
X1529668D01*
G01X1715841Y1084711D02*
X1714700Y1083575D01*
X1712718D01*
X1711720Y1082577D01*
X1708020D01*
X1703916Y1078473D01*
X1700795D01*
X1696858Y1074536D01*
X1693349D01*
X1691907Y1073094D01*
Y1054440D01*
X1686344Y1048877D01*
X1684830D01*
X1682830Y1050877D01*
X1679128D01*
X1676677Y1048426D01*
X1674586D01*
X1673442Y1049570D01*
X1671584D01*
X1670558Y1048544D01*
X1664211D01*
X1660747Y1045080D01*
X1658470D01*
X1657326Y1046224D01*
X1655539D01*
X1654430Y1045115D01*
X1642800D01*
X1635134Y1041940D01*
X1626060D01*
X1623351Y1044649D01*
X1609142D01*
X1606247Y1041754D01*
X1595219D01*
X1589434Y1035969D01*
X1547955D01*
X1538381Y1034064D01*
X1529668D01*
G01X1715841Y1128215D02*
X1713806Y1126180D01*
X1709679D01*
X1708300Y1127559D01*
X1706287D01*
X1704367Y1125639D01*
X1701466D01*
X1699975Y1127130D01*
X1699133D01*
X1698503Y1127760D01*
Y1129338D01*
X1697873Y1129968D01*
X1696403D01*
X1695773Y1129338D01*
Y1127760D01*
X1695143Y1127130D01*
X1693673D01*
X1693043Y1127760D01*
Y1129338D01*
X1692413Y1129968D01*
X1690943D01*
X1690313Y1129338D01*
Y1127760D01*
X1689683Y1127130D01*
X1689351D01*
X1687127Y1129354D01*
X1684171D01*
X1682954Y1130571D01*
X1675066D01*
X1674385Y1129890D01*
X1665726D01*
X1662413Y1126577D01*
Y1125687D01*
X1663277Y1124823D01*
Y1123933D01*
X1662236Y1122892D01*
X1661346D01*
X1660482Y1123756D01*
X1659592D01*
X1659035Y1123199D01*
X1655528D01*
X1654658Y1122329D01*
Y1117929D01*
X1653644Y1116915D01*
Y1116025D01*
X1654560Y1115108D01*
Y1114218D01*
X1653519Y1113177D01*
X1652629D01*
X1651713Y1114094D01*
X1650823D01*
X1648843Y1112114D01*
Y1110398D01*
X1647770Y1109325D01*
X1646054D01*
X1644911Y1108182D01*
X1642730D01*
X1638447Y1103899D01*
Y1101818D01*
X1635139Y1098510D01*
X1632893D01*
X1632173Y1099230D01*
Y1100205D01*
X1631453Y1100925D01*
X1630163D01*
X1629443Y1100205D01*
Y1099230D01*
X1628723Y1098510D01*
X1625328D01*
X1623004Y1096186D01*
X1619772D01*
X1618749Y1095163D01*
X1617135D01*
X1616112Y1096186D01*
X1611701D01*
X1607440Y1091925D01*
X1595649D01*
X1567218Y1063494D01*
X1545800D01*
X1535701Y1061485D01*
X1529668D01*
G01X1715841Y1111483D02*
X1714889Y1110531D01*
X1713283D01*
X1711935Y1109183D01*
X1699625D01*
X1696864Y1106422D01*
X1683603D01*
X1682852Y1107173D01*
X1680791D01*
X1679026Y1105408D01*
X1678008D01*
X1676501Y1106915D01*
X1675483D01*
X1674570Y1106002D01*
Y1104984D01*
X1676077Y1103477D01*
Y1102459D01*
X1673388Y1099770D01*
X1671360D01*
X1670506Y1098916D01*
Y1096502D01*
X1666782Y1092778D01*
X1662981D01*
X1661175Y1090972D01*
Y1088127D01*
X1660455Y1087407D01*
X1658958D01*
X1658238Y1086687D01*
Y1085397D01*
X1658958Y1084677D01*
X1660455D01*
X1661175Y1083957D01*
Y1081361D01*
X1659509Y1079695D01*
X1653492D01*
X1652772Y1080415D01*
Y1082184D01*
X1652052Y1082904D01*
X1650762D01*
X1650042Y1082184D01*
Y1080415D01*
X1649322Y1079695D01*
X1644584D01*
X1641001Y1076112D01*
X1634805D01*
X1633285Y1077632D01*
X1629151D01*
X1627631Y1076112D01*
X1624967D01*
X1624015Y1077064D01*
X1619731D01*
X1619011Y1076344D01*
Y1075217D01*
X1618291Y1074497D01*
X1617001D01*
X1616281Y1075217D01*
Y1076344D01*
X1615561Y1077064D01*
X1610786D01*
X1609385Y1075663D01*
X1603610D01*
X1602890Y1076383D01*
Y1077297D01*
X1602170Y1078017D01*
X1600880D01*
X1600160Y1077297D01*
Y1076383D01*
X1599440Y1075663D01*
X1594708D01*
X1572065Y1053168D01*
X1546939D01*
X1536390Y1051070D01*
X1529668D01*
G01X1715841Y1121522D02*
X1714822Y1120503D01*
X1713184D01*
X1712368Y1119687D01*
X1679950D01*
X1677588Y1122049D01*
X1674580D01*
X1673437Y1123192D01*
X1671428D01*
X1670382Y1122146D01*
X1667871D01*
X1661735Y1116010D01*
Y1103758D01*
X1659948Y1101971D01*
X1658438D01*
X1657295Y1103114D01*
X1655286D01*
X1654150Y1101978D01*
X1650668D01*
X1644006Y1095316D01*
X1639436Y1093422D01*
X1637141Y1091129D01*
X1624243D01*
X1621402Y1088288D01*
X1613063D01*
X1608234Y1086288D01*
X1596183D01*
X1569423Y1059528D01*
X1546296D01*
X1535919Y1057463D01*
X1529668D01*
G01X1715841Y1185105D02*
X1713775D01*
X1711611Y1182941D01*
X1709546D01*
X1703024Y1176419D01*
X1700158D01*
X1696611Y1172872D01*
X1693264D01*
X1686411Y1166019D01*
X1684911D01*
X1681031Y1162139D01*
X1676582D01*
X1674452Y1160009D01*
X1663001D01*
X1660505Y1157513D01*
Y1156280D01*
X1657541Y1153316D01*
X1654917D01*
X1652814Y1155419D01*
X1649005D01*
X1648375Y1156049D01*
Y1158438D01*
X1647745Y1159068D01*
X1646275D01*
X1645645Y1158438D01*
Y1156049D01*
X1645015Y1155419D01*
X1638321D01*
X1637369Y1154467D01*
Y1151052D01*
X1635301Y1148984D01*
X1631065D01*
X1629868Y1147787D01*
X1625339D01*
X1623047Y1145495D01*
X1619251D01*
X1618531Y1146215D01*
Y1148033D01*
X1617811Y1148753D01*
X1616521D01*
X1615801Y1148033D01*
Y1146215D01*
X1615081Y1145495D01*
X1608911D01*
X1605741Y1142325D01*
X1603966D01*
X1603246Y1143045D01*
Y1144906D01*
X1602526Y1145626D01*
X1601236D01*
X1600516Y1144906D01*
Y1143045D01*
X1599796Y1142325D01*
X1595990D01*
X1588405Y1134740D01*
Y1104084D01*
X1560885Y1076564D01*
X1536609D01*
X1532693Y1074942D01*
X1529668D01*
G01X1715841Y1201837D02*
X1714024Y1200020D01*
X1709211D01*
X1706510Y1197319D01*
X1701862D01*
X1698313Y1193770D01*
X1697295D01*
X1696653Y1194412D01*
X1695636D01*
X1694723Y1193499D01*
Y1192481D01*
X1695364Y1191839D01*
Y1190821D01*
X1694711Y1190168D01*
X1691830D01*
X1687981Y1186319D01*
X1685211D01*
X1681628Y1182736D01*
X1679928D01*
X1677279Y1180087D01*
X1670889D01*
X1669670Y1178868D01*
X1668159D01*
X1666940Y1180087D01*
X1663715D01*
X1660369Y1176741D01*
X1653483D01*
X1652861Y1176119D01*
X1649351D01*
X1648721Y1176749D01*
Y1178138D01*
X1648091Y1178768D01*
X1646621D01*
X1645991Y1178138D01*
Y1176749D01*
X1645361Y1176119D01*
X1640461D01*
X1637561Y1173219D01*
X1634985D01*
X1633536Y1171770D01*
X1631914D01*
X1630794Y1170650D01*
Y1169028D01*
X1628467Y1166701D01*
X1624329D01*
X1623095Y1167935D01*
X1621599D01*
X1620724Y1167060D01*
X1618994D01*
X1615177Y1163243D01*
X1610962D01*
X1607465Y1159746D01*
X1603514D01*
X1602884Y1160376D01*
Y1161319D01*
X1602254Y1161949D01*
X1600784D01*
X1600154Y1161319D01*
Y1160376D01*
X1599524Y1159746D01*
X1594782D01*
X1578125Y1143089D01*
Y1108351D01*
X1556623Y1086844D01*
X1534558D01*
X1531033Y1085384D01*
X1528145D01*
X1527339Y1084578D01*
G01X1715841Y1191798D02*
X1714788Y1192851D01*
X1713371D01*
X1712053Y1191533D01*
X1706326D01*
X1698282Y1183489D01*
X1694118D01*
X1687918Y1177289D01*
X1684356D01*
X1678079Y1171012D01*
X1674607D01*
X1673644Y1170049D01*
X1671562D01*
X1670467Y1171144D01*
X1664533D01*
X1661069Y1167680D01*
X1658479D01*
X1657502Y1166703D01*
X1655420D01*
X1654318Y1167805D01*
X1640727D01*
X1636426Y1163504D01*
X1634913D01*
X1628998Y1157589D01*
X1623943D01*
X1622813Y1156459D01*
X1621139D01*
X1619865Y1157733D01*
X1617586D01*
X1616398Y1156544D01*
X1608666Y1153338D01*
X1596346D01*
X1583265Y1140257D01*
Y1106215D01*
X1558754Y1081704D01*
X1535582D01*
X1531995Y1080218D01*
X1529668D01*
G01X1775241Y1221916D02*
X1773171Y1219846D01*
X1768407D01*
X1767687Y1220566D01*
Y1221977D01*
X1766967Y1222697D01*
X1765677D01*
X1764957Y1221977D01*
Y1220566D01*
X1764237Y1219846D01*
X1760301D01*
X1759879Y1220268D01*
X1753578D01*
X1750210Y1216900D01*
X1744340D01*
X1743710Y1217530D01*
Y1219177D01*
X1743080Y1219807D01*
X1741610D01*
X1740980Y1219177D01*
Y1217530D01*
X1740350Y1216900D01*
X1738520D01*
X1737890Y1217530D01*
Y1218482D01*
X1737260Y1219112D01*
X1735790D01*
X1735160Y1218482D01*
Y1217530D01*
X1734530Y1216900D01*
X1723602D01*
X1720256Y1220246D01*
X1700738D01*
X1696611Y1216119D01*
X1693611D01*
X1686711Y1209219D01*
X1684711D01*
X1681711Y1206219D01*
X1678117D01*
X1675411Y1203513D01*
X1662008D01*
X1658661Y1206860D01*
X1653402D01*
X1652661Y1206119D01*
X1649553D01*
X1648871Y1206801D01*
Y1208604D01*
X1648264Y1209211D01*
X1646446D01*
X1645766Y1208531D01*
Y1207018D01*
X1644867Y1206119D01*
X1640261D01*
X1637133Y1202991D01*
X1634649D01*
X1633790Y1202132D01*
X1632900D01*
X1632554Y1202478D01*
X1631664D01*
X1630623Y1201437D01*
Y1200547D01*
X1630969Y1200201D01*
Y1199311D01*
X1627312Y1195654D01*
X1626422D01*
X1625832Y1196244D01*
X1624942D01*
X1623901Y1195203D01*
Y1194313D01*
X1624491Y1193723D01*
Y1192833D01*
X1622548Y1190890D01*
X1617804D01*
X1616805Y1191889D01*
X1615915D01*
X1614874Y1190848D01*
Y1189958D01*
X1615873Y1188959D01*
Y1188069D01*
X1614584Y1186780D01*
X1612269D01*
X1610729Y1188320D01*
Y1189210D01*
X1611410Y1189892D01*
Y1190782D01*
X1610369Y1191823D01*
X1609479D01*
X1608798Y1191141D01*
X1607908D01*
X1606517Y1192532D01*
X1601888D01*
X1600838Y1191482D01*
Y1186225D01*
X1598041Y1183428D01*
X1596321D01*
X1564605Y1151712D01*
Y1113952D01*
X1551017Y1100364D01*
X1531862D01*
X1529797Y1099508D01*
X1529359D01*
G01X1775241Y1228609D02*
X1774213Y1229637D01*
X1772313D01*
X1770557Y1227881D01*
X1759449D01*
X1756798Y1230532D01*
X1751611D01*
X1749430Y1228351D01*
X1738940D01*
X1735910Y1231381D01*
X1733773D01*
X1732678Y1230286D01*
X1731298D01*
X1730203Y1231381D01*
X1722224D01*
X1718921Y1234684D01*
X1717613D01*
X1716554Y1233625D01*
X1715103D01*
X1714050Y1234678D01*
X1709297D01*
X1702538Y1227919D01*
X1694512D01*
X1687722Y1221129D01*
X1684810D01*
X1678301Y1214620D01*
X1674349D01*
X1673282Y1213553D01*
X1671862D01*
X1670834Y1214581D01*
X1662780D01*
X1659389Y1217972D01*
X1658244D01*
X1657172Y1216900D01*
X1655706D01*
X1654715Y1217891D01*
X1641137D01*
X1624160Y1206545D01*
X1618827Y1201212D01*
X1614990D01*
X1613946Y1200168D01*
X1612472D01*
X1611373Y1201267D01*
X1603247D01*
X1599924Y1204590D01*
X1598904D01*
X1597838Y1203524D01*
X1596227D01*
X1595245Y1204506D01*
X1593810D01*
X1590427Y1201123D01*
Y1184916D01*
X1559465Y1153954D01*
Y1116083D01*
X1548929Y1105547D01*
X1528769D01*
G01X1791383Y813648D02*
X1787639Y817392D01*
X1783366D01*
X1777952Y811978D01*
X1772902D01*
X1771946Y812934D01*
X1769850D01*
X1768550Y811634D01*
X1762950D01*
X1761750Y812834D01*
X1759376D01*
X1757661Y811119D01*
X1751161D01*
X1748674Y808632D01*
X1723949D01*
X1720604Y811977D01*
X1713003D01*
X1712161Y812819D01*
X1708562D01*
X1706262Y815119D01*
X1697361D01*
X1696461Y816019D01*
X1684048D01*
X1682343Y814314D01*
X1679660D01*
X1675319Y818655D01*
X1668397D01*
X1667966Y818224D01*
X1664368D01*
X1661468Y815324D01*
X1635810D01*
X1634368Y813882D01*
X1630079D01*
X1627885Y816076D01*
X1624418D01*
X1623234Y814892D01*
X1619942D01*
X1619026Y815808D01*
Y817434D01*
X1618250Y818210D01*
X1616698D01*
X1616067Y817579D01*
Y815857D01*
X1615102Y814892D01*
X1610887D01*
X1609960Y815819D01*
X1595158D01*
X1581621Y829356D01*
Y830029D01*
X1522683Y888967D01*
G01X1791383Y806955D02*
X1787055Y811283D01*
X1785075D01*
X1779077Y805285D01*
X1768327D01*
X1767607Y804565D01*
Y803123D01*
X1766887Y802403D01*
X1765597D01*
X1764877Y803123D01*
Y804565D01*
X1764157Y805285D01*
X1758599D01*
X1755253Y801939D01*
X1731097D01*
X1730217Y802819D01*
X1723161D01*
X1716761Y805285D01*
X1709995D01*
X1706653Y808627D01*
X1680253D01*
X1679188Y809692D01*
X1676842D01*
X1674549Y811985D01*
X1670316D01*
X1668907Y810576D01*
X1664439D01*
X1662494Y808631D01*
X1610348D01*
X1609652Y809327D01*
X1594460D01*
X1577148Y826639D01*
Y828813D01*
X1530331Y875630D01*
X1529541D01*
X1528523Y875631D01*
X1527503Y876651D01*
Y877441D01*
X1527504Y878457D01*
X1525576Y880385D01*
X1523690D01*
X1522649Y881426D01*
G01X1791383Y820341D02*
X1790285Y821439D01*
X1788014D01*
X1786541Y822912D01*
X1783381D01*
X1780235Y819766D01*
X1777077D01*
X1775982Y818671D01*
X1774408D01*
X1773310Y819769D01*
X1761146D01*
X1755038Y822299D01*
X1752760D01*
X1747690Y817229D01*
X1745361D01*
X1741918Y818655D01*
X1738524D01*
X1736289Y816420D01*
X1733803D01*
X1732708Y815325D01*
X1731298D01*
X1730196Y816427D01*
X1723326D01*
X1719987Y819766D01*
X1717627D01*
X1716532Y818671D01*
X1715084D01*
X1714020Y819735D01*
X1711741D01*
X1704911Y822564D01*
X1679528D01*
X1675631Y826461D01*
X1674396D01*
X1673300Y825365D01*
X1671856D01*
X1670844Y826377D01*
X1663915D01*
X1660485Y829807D01*
X1658241D01*
X1657146Y828712D01*
X1655730D01*
X1654663Y829779D01*
X1651487D01*
X1644037Y822329D01*
X1596286D01*
X1586741Y831874D01*
Y832685D01*
X1527090Y892336D01*
X1524373D01*
G01X1791383Y837074D02*
X1789708Y838749D01*
X1781949D01*
X1781229Y839469D01*
Y841584D01*
X1780509Y842304D01*
X1779219D01*
X1778499Y841584D01*
Y839469D01*
X1777779Y838749D01*
X1768511D01*
X1767881Y839379D01*
Y841338D01*
X1767251Y841968D01*
X1765781D01*
X1765151Y841338D01*
Y839379D01*
X1764521Y838749D01*
X1723631D01*
X1720285Y842095D01*
X1700037D01*
X1697861Y839919D01*
X1693337D01*
X1691403Y841853D01*
X1690513D01*
X1689353Y840693D01*
X1688463D01*
X1687422Y841734D01*
Y842624D01*
X1688582Y843784D01*
Y844674D01*
X1687637Y845619D01*
X1683661D01*
X1682580Y844538D01*
X1675349D01*
X1674445Y845442D01*
X1661067D01*
X1657730Y848779D01*
X1650849D01*
X1644589Y842519D01*
X1640560D01*
X1637560Y839519D01*
X1623861D01*
X1622861Y838519D01*
X1620661D01*
X1616961Y842219D01*
X1611561D01*
X1610914Y841572D01*
X1593302D01*
X1532118Y902756D01*
X1526143D01*
X1524950Y903949D01*
G01X1791383Y830381D02*
X1786770Y834994D01*
X1781187D01*
X1778249Y832056D01*
X1768043D01*
X1767413Y831426D01*
Y830398D01*
X1766783Y829768D01*
X1765313D01*
X1764683Y830398D01*
Y831426D01*
X1764053Y832056D01*
X1744289D01*
X1741625Y829392D01*
X1736488D01*
X1733823Y832057D01*
X1727023D01*
X1726161Y832919D01*
X1721361D01*
X1718877Y835403D01*
X1700345D01*
X1697831Y832889D01*
X1684667D01*
X1681388Y836168D01*
X1676268D01*
X1673686Y838750D01*
X1662131D01*
X1658785Y842096D01*
X1650438D01*
X1644461Y836119D01*
X1641629D01*
X1637561Y832051D01*
X1633502D01*
X1632782Y831331D01*
Y830212D01*
X1632062Y829492D01*
X1630772D01*
X1630052Y830212D01*
Y831331D01*
X1629332Y832051D01*
X1619919D01*
X1616050Y835920D01*
X1611462D01*
X1609496Y833954D01*
X1603749D01*
X1603029Y833234D01*
Y830690D01*
X1602309Y829970D01*
X1601019D01*
X1600299Y830690D01*
Y833234D01*
X1599579Y833954D01*
X1595031D01*
X1530220Y898765D01*
X1524465D01*
G01X1791383Y823688D02*
X1790354Y822659D01*
X1788520D01*
X1787047Y824132D01*
X1782875D01*
X1779729Y820986D01*
X1777005D01*
X1775980Y822011D01*
X1774386D01*
X1773364Y820989D01*
X1761389D01*
X1755281Y823519D01*
X1752254D01*
X1747184Y818449D01*
X1745604D01*
X1742161Y819875D01*
X1738018D01*
X1735783Y817640D01*
X1733743D01*
X1732718Y818665D01*
X1731250D01*
X1730232Y817647D01*
X1723832D01*
X1720493Y820986D01*
X1717569D01*
X1716544Y822011D01*
X1715088D01*
X1714032Y820955D01*
X1711984D01*
X1705154Y823784D01*
X1685314D01*
X1684824Y824274D01*
X1682674D01*
X1682184Y823784D01*
X1680034D01*
X1676137Y827681D01*
X1674318D01*
X1673294Y828705D01*
X1671878D01*
X1670770Y827597D01*
X1664421D01*
X1660991Y831027D01*
X1658147D01*
X1657122Y832052D01*
X1655764D01*
X1654711Y830999D01*
X1650981D01*
X1648133Y828151D01*
X1647440D01*
X1645918Y826629D01*
Y825936D01*
X1643531Y823549D01*
X1640244D01*
X1639754Y824039D01*
X1637604D01*
X1637114Y823549D01*
X1634964D01*
X1634474Y824039D01*
X1632324D01*
X1631834Y823549D01*
X1629684D01*
X1629194Y824039D01*
X1627044D01*
X1626554Y823549D01*
X1624404D01*
X1623914Y824039D01*
X1621764D01*
X1621274Y823549D01*
X1619124D01*
X1618634Y824039D01*
X1616484D01*
X1615994Y823549D01*
X1613844D01*
X1613354Y824039D01*
X1611204D01*
X1610714Y823549D01*
X1608564D01*
X1608074Y824039D01*
X1605924D01*
X1605434Y823549D01*
X1602072D01*
X1601582Y824039D01*
X1599432D01*
X1598942Y823549D01*
X1596792D01*
X1587961Y832380D01*
Y833191D01*
X1527596Y893556D01*
X1524373D01*
G01X1731983Y867192D02*
X1726962Y872213D01*
X1715163D01*
X1713827Y873549D01*
X1708709D01*
X1707989Y872829D01*
Y871535D01*
X1707269Y870815D01*
X1705979D01*
X1705259Y871535D01*
Y872829D01*
X1704539Y873549D01*
X1699681D01*
X1696961Y876269D01*
X1689663D01*
X1688013Y877919D01*
X1686261D01*
X1682361Y881819D01*
X1678224D01*
X1674445Y885598D01*
X1662282D01*
X1658935Y888945D01*
X1641187D01*
X1637171Y884929D01*
X1633173D01*
X1632453Y885649D01*
Y887350D01*
X1631733Y888070D01*
X1630443D01*
X1629723Y887350D01*
Y885649D01*
X1629003Y884929D01*
X1625773D01*
X1619749Y878905D01*
X1611147D01*
X1610061Y877819D01*
X1603806D01*
X1603176Y878449D01*
Y879585D01*
X1602445Y880316D01*
X1601075D01*
X1600404Y879645D01*
Y878449D01*
X1599774Y877819D01*
X1590219D01*
X1543080Y924958D01*
X1528199D01*
G01X1731983Y850459D02*
X1728617D01*
X1720249Y858827D01*
X1713672D01*
X1712724Y857879D01*
X1698801D01*
X1694528Y862152D01*
X1680128D01*
X1676764Y865516D01*
X1662564D01*
X1659208Y868872D01*
X1640914D01*
X1635853Y863811D01*
X1634835D01*
X1633880Y864766D01*
X1632862D01*
X1631949Y863853D01*
Y862835D01*
X1632904Y861880D01*
Y860862D01*
X1630961Y858919D01*
X1618661D01*
X1616661Y860919D01*
X1610963D01*
X1610059Y861823D01*
X1608333D01*
X1607429Y860919D01*
X1591514D01*
X1538167Y914266D01*
G03X1537518Y914535I-649J-648D01*
G01X1528009D01*
G01X1731983Y843766D02*
X1729546Y846203D01*
X1727784D01*
X1717561Y852134D01*
X1699858D01*
X1696772Y853319D01*
X1692961D01*
X1689961Y855219D01*
X1685261D01*
X1682361Y858119D01*
X1675484D01*
X1674778Y858825D01*
X1667815D01*
X1667115Y859525D01*
X1661338D01*
X1658678Y862185D01*
X1654372D01*
X1653735Y861548D01*
X1640221Y857452D01*
X1635927Y853158D01*
X1625572D01*
X1624333Y851919D01*
X1618305D01*
X1613956Y856268D01*
X1611610D01*
X1610101Y854759D01*
X1604145D01*
X1603425Y855479D01*
Y856206D01*
X1602705Y856926D01*
X1601415D01*
X1600695Y856206D01*
Y855479D01*
X1599975Y854759D01*
X1591594D01*
X1535795Y910558D01*
X1528009D01*
G01X1715841Y877231D02*
X1714059Y879013D01*
X1700467D01*
X1697061Y882419D01*
X1690133D01*
X1687333Y885219D01*
X1685561D01*
X1682161Y888619D01*
X1677672D01*
X1673999Y892292D01*
X1663788D01*
X1660441Y895639D01*
X1640681D01*
X1637176Y892134D01*
X1625827D01*
X1621761Y888068D01*
X1617110D01*
X1614640Y885598D01*
X1611330D01*
X1610700Y886228D01*
Y892038D01*
X1610070Y892668D01*
X1608600D01*
X1607970Y892038D01*
Y886228D01*
X1607340Y885598D01*
X1603513D01*
X1603512Y885599D01*
X1603216D01*
X1602586Y886229D01*
Y892438D01*
X1601956Y893068D01*
X1600486D01*
X1599856Y892438D01*
Y886229D01*
X1599226Y885599D01*
X1597422D01*
X1597421Y885598D01*
X1588437D01*
X1545127Y928908D01*
X1528199D01*
G01X1731983Y860499D02*
X1731107Y859623D01*
X1727825D01*
X1727559Y859733D01*
X1720082Y867210D01*
X1718916Y867701D01*
X1717856D01*
X1716702Y868855D01*
X1714894D01*
X1712792Y866753D01*
X1701042D01*
X1700140Y867127D01*
X1697834Y869433D01*
X1696074Y870162D01*
X1688642D01*
X1683845Y873368D01*
X1679962Y874977D01*
X1677725Y877214D01*
X1676217Y877839D01*
X1674353D01*
X1673291Y878901D01*
X1671892D01*
X1670873Y877882D01*
X1664947D01*
X1663277Y878572D01*
X1661543Y880306D01*
X1659319Y881231D01*
X1658271D01*
X1657255Y882247D01*
X1655758D01*
X1654658Y881147D01*
X1641416D01*
X1640968Y880962D01*
X1640519Y880776D01*
X1636771Y877028D01*
X1633271D01*
X1628325Y872082D01*
X1626275D01*
X1623048Y873419D01*
X1610362D01*
X1608996Y872053D01*
X1590346D01*
X1541376Y921023D01*
X1527566D01*
G01X1731983Y857152D02*
X1731895D01*
X1730644Y858403D01*
X1727582D01*
X1726868Y858698D01*
X1725348Y860218D01*
X1724655D01*
X1723134Y861739D01*
Y862432D01*
X1719388Y866178D01*
X1718669Y866481D01*
X1717861D01*
X1716902Y865522D01*
X1714820D01*
X1714809Y865533D01*
X1706793D01*
X1706303Y865043D01*
X1704153D01*
X1703663Y865533D01*
X1700799D01*
X1699448Y866092D01*
X1697142Y868398D01*
X1695831Y868942D01*
X1688271D01*
X1683267Y872286D01*
X1681437Y873044D01*
X1679270Y873942D01*
X1677033Y876179D01*
X1675973Y876619D01*
X1674342D01*
X1673284Y875561D01*
X1671898D01*
X1670797Y876662D01*
X1664704D01*
X1662586Y877537D01*
X1660853Y879270D01*
X1659075Y880011D01*
X1658236D01*
X1657132Y878907D01*
X1655760D01*
X1654740Y879927D01*
X1652219D01*
X1651729Y879437D01*
X1649579D01*
X1649089Y879927D01*
X1646939D01*
X1646449Y879437D01*
X1644299D01*
X1643809Y879927D01*
X1641659D01*
X1641210Y879741D01*
X1637277Y875808D01*
X1633777D01*
X1628831Y870862D01*
X1626032D01*
X1622805Y872199D01*
X1618256D01*
X1617766Y871709D01*
X1615616D01*
X1615126Y872199D01*
X1610868D01*
X1609502Y870833D01*
X1607116D01*
X1606626Y870343D01*
X1604476D01*
X1603986Y870833D01*
X1600124D01*
X1599634Y870343D01*
X1597484D01*
X1596994Y870833D01*
X1594844D01*
X1594354Y870343D01*
X1592204D01*
X1591714Y870833D01*
X1589840D01*
X1588320Y872353D01*
X1587627D01*
X1586106Y873874D01*
Y874567D01*
X1584586Y876087D01*
X1583893D01*
X1582372Y877608D01*
Y878301D01*
X1580852Y879821D01*
X1580159D01*
X1578638Y881342D01*
Y882035D01*
X1577118Y883555D01*
X1576425D01*
X1574904Y885076D01*
Y885769D01*
X1540870Y919803D01*
X1527566D01*
G01X1731983Y904003D02*
X1729745D01*
X1728074Y902332D01*
X1712961D01*
X1711574Y903719D01*
X1709361D01*
X1707700Y905380D01*
Y906270D01*
X1708760Y907330D01*
Y908220D01*
X1707719Y909261D01*
X1706829D01*
X1705769Y908201D01*
X1704879D01*
X1700361Y912719D01*
Y914393D01*
X1694635Y920119D01*
X1694261D01*
X1688627Y925753D01*
X1663214D01*
X1659863Y929104D01*
X1651623D01*
X1650438Y927919D01*
X1647644D01*
X1646224Y929339D01*
X1639883D01*
X1636598Y926054D01*
X1634240D01*
X1633520Y926774D01*
Y928414D01*
X1632800Y929134D01*
X1631510D01*
X1630790Y928414D01*
Y926774D01*
X1630070Y926054D01*
X1625796D01*
X1624561Y924819D01*
X1619115D01*
X1614615Y929319D01*
X1611461D01*
X1608061Y925919D01*
X1597422D01*
X1597421Y925918D01*
X1578795D01*
X1557635Y947078D01*
X1529066D01*
G01X1731983Y887270D02*
X1730323Y885610D01*
X1723848D01*
X1720513Y888945D01*
X1710015D01*
X1708541Y890419D01*
X1706809D01*
X1704809Y892419D01*
X1699732D01*
X1696032Y896119D01*
X1689767D01*
X1688764Y897122D01*
Y898140D01*
X1689258Y898634D01*
Y899652D01*
X1688345Y900565D01*
X1687327D01*
X1686833Y900071D01*
X1685815D01*
X1682264Y903622D01*
X1678717D01*
X1676661Y905678D01*
X1669949D01*
X1668598Y907029D01*
X1667219D01*
X1665868Y905678D01*
X1662506D01*
X1659160Y909024D01*
X1633857D01*
X1631582Y906749D01*
X1625861D01*
X1624295Y905183D01*
X1620687D01*
X1620192Y905678D01*
X1610793D01*
X1609437Y907034D01*
X1608063D01*
X1606707Y905678D01*
X1602302D01*
X1600202Y907778D01*
Y907838D01*
X1599018Y909022D01*
X1595978D01*
X1595016Y908060D01*
X1590326D01*
X1589606Y908780D01*
Y909638D01*
X1588886Y910358D01*
X1587596D01*
X1586876Y909638D01*
Y908780D01*
X1586156Y908060D01*
X1584866D01*
X1584146Y908780D01*
Y909638D01*
X1583426Y910358D01*
X1582136D01*
X1581416Y909638D01*
Y908780D01*
X1580696Y908060D01*
X1576795D01*
X1548274Y936581D01*
X1529066D01*
G01X1731983Y880577D02*
X1730307Y882253D01*
X1709427D01*
X1705361Y886319D01*
X1698961D01*
X1696261Y889019D01*
X1687209D01*
X1677242Y898986D01*
X1662495D01*
X1659149Y902332D01*
X1654448D01*
X1653961Y902819D01*
X1649660D01*
X1648940Y902099D01*
Y899829D01*
X1648220Y899109D01*
X1646930D01*
X1646210Y899829D01*
Y902099D01*
X1645490Y902819D01*
X1639949D01*
X1635134Y898004D01*
X1618756D01*
X1617774Y898986D01*
X1609266D01*
X1608546Y898266D01*
Y896599D01*
X1607826Y895879D01*
X1606536D01*
X1605816Y896599D01*
Y898266D01*
X1605096Y898986D01*
X1602407D01*
X1599062Y902331D01*
X1595539D01*
X1594806Y901598D01*
X1576875D01*
X1546404Y932069D01*
X1528199D01*
G01X1731983Y897310D02*
X1730919Y896246D01*
X1730447D01*
X1728642Y896991D01*
X1724242D01*
X1721425Y895716D01*
X1718498Y894504D01*
X1717824D01*
X1716695Y895633D01*
X1708994D01*
X1706878Y897749D01*
X1704905D01*
X1700900Y899405D01*
X1698366Y901939D01*
X1694552D01*
X1693164Y903327D01*
Y907893D01*
X1691085Y909972D01*
Y910665D01*
X1689564Y912186D01*
X1688871D01*
X1686894Y914163D01*
X1684506D01*
X1682592Y912249D01*
X1679824D01*
X1677414Y914659D01*
X1674330D01*
X1673277Y915712D01*
X1671896D01*
X1670871Y914687D01*
X1667860D01*
X1667370Y915177D01*
X1665220D01*
X1664730Y914687D01*
X1662580D01*
X1659249Y918018D01*
X1658192D01*
X1657151Y919059D01*
X1655758D01*
X1654702Y918003D01*
X1651279D01*
X1650789Y918493D01*
X1648639D01*
X1648149Y918003D01*
X1645999D01*
X1645509Y918493D01*
X1643359D01*
X1642869Y918003D01*
X1640719D01*
X1638373Y915657D01*
X1633533D01*
X1633043Y916147D01*
X1630893D01*
X1630403Y915657D01*
X1628126D01*
X1625951Y914754D01*
X1623505Y912309D01*
X1619123D01*
X1617593Y913839D01*
Y914532D01*
X1616072Y916053D01*
X1615379D01*
X1613859Y917573D01*
X1608284D01*
X1606309Y915598D01*
X1604581D01*
X1602131Y918048D01*
X1598754D01*
X1597738Y919064D01*
X1596250D01*
X1595355Y918169D01*
X1590430D01*
X1589940Y918659D01*
X1587790D01*
X1587300Y918169D01*
X1585150D01*
X1584660Y918659D01*
X1582510D01*
X1582020Y918169D01*
X1576502D01*
X1574982Y919689D01*
Y920382D01*
X1573461Y921903D01*
X1572768D01*
X1571248Y923423D01*
Y924116D01*
X1569727Y925637D01*
X1569034D01*
X1567514Y927157D01*
Y927850D01*
X1565993Y929371D01*
X1565300D01*
X1552756Y941915D01*
X1528974D01*
G01X1731983Y893963D02*
X1730920Y895026D01*
X1730204D01*
X1728399Y895771D01*
X1724506D01*
X1721910Y894596D01*
X1718741Y893284D01*
X1717893D01*
X1716902Y892293D01*
X1714820D01*
X1712700Y894413D01*
X1708488D01*
X1706372Y896529D01*
X1704662D01*
X1700209Y898370D01*
X1697860Y900719D01*
X1694046D01*
X1691944Y902821D01*
Y907387D01*
X1686388Y912943D01*
X1685012D01*
X1683098Y911029D01*
X1679318D01*
X1676908Y913439D01*
X1674335D01*
X1673268Y912372D01*
X1671892D01*
X1670797Y913467D01*
X1662074D01*
X1658743Y916798D01*
X1658215D01*
X1657136Y915719D01*
X1655756D01*
X1654692Y916783D01*
X1641225D01*
X1638879Y914437D01*
X1628370D01*
X1626643Y913720D01*
X1624011Y911089D01*
X1618617D01*
X1613353Y916353D01*
X1608790D01*
X1606815Y914378D01*
X1604075D01*
X1601625Y916828D01*
X1598843D01*
X1597734Y915719D01*
X1596337D01*
X1595107Y916949D01*
X1575996D01*
X1552250Y940695D01*
X1528974D01*
G01X1731983Y910696D02*
X1728338D01*
X1726663Y912371D01*
X1721671D01*
X1720951Y911651D01*
Y910365D01*
X1720231Y909645D01*
X1718941D01*
X1718221Y910365D01*
Y911651D01*
X1717501Y912371D01*
X1710209D01*
X1707561Y915019D01*
Y917905D01*
X1696698Y928768D01*
X1692312D01*
X1687961Y933119D01*
X1675988D01*
X1675304Y932435D01*
X1662789D01*
X1659431Y935793D01*
X1654272D01*
X1653298Y934819D01*
X1649597D01*
X1648877Y935539D01*
Y937227D01*
X1648157Y937947D01*
X1646867D01*
X1646147Y937227D01*
Y935539D01*
X1645427Y934819D01*
X1627955D01*
X1626455Y933319D01*
X1604314D01*
X1603684Y932689D01*
Y930598D01*
X1603054Y929968D01*
X1601584D01*
X1600954Y930598D01*
Y932689D01*
X1600324Y933319D01*
X1578491D01*
X1560795Y951015D01*
X1529066D01*
G01X1821083Y964239D02*
X1818168Y961324D01*
Y951889D01*
X1815459Y949180D01*
X1788972D01*
X1785628Y945836D01*
X1759028D01*
X1756331Y943139D01*
X1752965D01*
X1752245Y942419D01*
Y939577D01*
X1751525Y938857D01*
X1750235D01*
X1749515Y939577D01*
Y942419D01*
X1748795Y943139D01*
X1743821D01*
X1742811Y942129D01*
X1738581D01*
X1734874Y945836D01*
X1730668D01*
X1727322Y942490D01*
X1685142D01*
X1682972Y940320D01*
X1678968D01*
X1676788Y942500D01*
X1671728D01*
X1670562Y943666D01*
X1667968D01*
X1665798Y945836D01*
X1640438D01*
X1637623Y943021D01*
X1623853D01*
X1619963Y939131D01*
X1592689D01*
X1588568Y943252D01*
X1579979D01*
X1566534Y956697D01*
X1518319D01*
G01X1791383Y964239D02*
X1783175Y956031D01*
X1781511D01*
X1778009Y952529D01*
X1772401D01*
X1771401Y953529D01*
X1763653D01*
X1762653Y952529D01*
X1756691D01*
X1753801Y949639D01*
X1743381D01*
X1742751Y949009D01*
X1738801D01*
X1735281Y952529D01*
X1729661D01*
X1726315Y949183D01*
X1696464D01*
X1695182Y950465D01*
X1686487D01*
X1682788Y946766D01*
X1679114D01*
X1676697Y949183D01*
X1669983D01*
X1666637Y952529D01*
X1640101D01*
X1637403Y949831D01*
X1625445D01*
X1622685Y952591D01*
X1620791D01*
X1614898Y946698D01*
X1610000D01*
X1607840Y944538D01*
X1596114D01*
X1592634Y948018D01*
X1581111D01*
X1568325Y960804D01*
X1530539D01*
X1527187Y964156D01*
X1525389D01*
X1522971Y963155D01*
X1517097D01*
X1516735Y962793D01*
G01X1686041Y960892D02*
X1683834Y963099D01*
X1679831D01*
X1677015Y965915D01*
X1663065D01*
X1659719Y969261D01*
X1653639D01*
X1652851Y970049D01*
X1647201D01*
X1645229Y972021D01*
X1640071D01*
X1636541Y975551D01*
X1626059D01*
X1622595Y979015D01*
X1620622D01*
X1620029Y979608D01*
X1615580D01*
X1614901Y978929D01*
X1610485D01*
X1607328Y982086D01*
X1590524D01*
X1588071Y984539D01*
X1561665D01*
X1558501Y981375D01*
X1546528D01*
X1537577Y990326D01*
X1489926D01*
X1486248Y994004D01*
Y996900D01*
G01X1656441Y960892D02*
X1654298D01*
X1652281Y962909D01*
X1647051D01*
X1645233Y964727D01*
X1640594D01*
X1639230Y966091D01*
X1635310D01*
X1634590Y966811D01*
Y969298D01*
X1633870Y970018D01*
X1632580D01*
X1631860Y969298D01*
Y966811D01*
X1631140Y966091D01*
X1630237D01*
X1627679Y968649D01*
X1626291D01*
X1622591Y972349D01*
X1619632D01*
X1618912Y973069D01*
Y974286D01*
X1618192Y975006D01*
X1616902D01*
X1616182Y974286D01*
Y973069D01*
X1615462Y972349D01*
X1609979D01*
X1607287Y975041D01*
X1603754D01*
X1603034Y975761D01*
Y977254D01*
X1602314Y977974D01*
X1601024D01*
X1600304Y977254D01*
Y975761D01*
X1599584Y975041D01*
X1597095D01*
X1595321Y976815D01*
X1588194D01*
X1586931Y978078D01*
X1585565D01*
X1585550Y978063D01*
X1584345D01*
X1583625Y978783D01*
Y979843D01*
X1582905Y980563D01*
X1581615D01*
X1580895Y979843D01*
Y978783D01*
X1580175Y978063D01*
X1578885D01*
X1578165Y978783D01*
Y979843D01*
X1577445Y980563D01*
X1576155D01*
X1575435Y979843D01*
Y978783D01*
X1574715Y978063D01*
X1573425D01*
X1572705Y978783D01*
Y979843D01*
X1571985Y980563D01*
X1570695D01*
X1569975Y979843D01*
Y978783D01*
X1569255Y978063D01*
X1567965D01*
X1567245Y978783D01*
Y979843D01*
X1566525Y980563D01*
X1565235D01*
X1564515Y979843D01*
Y978783D01*
X1563795Y978063D01*
X1542974D01*
X1533351Y987686D01*
X1488216D01*
X1482448Y993454D01*
Y999429D01*
X1482703Y999684D01*
G01X1686041Y957546D02*
X1685228Y958359D01*
X1681797D01*
X1676700Y960470D01*
X1674602Y962568D01*
X1671946D01*
X1671897Y962519D01*
X1665841D01*
X1665791Y962569D01*
X1664059D01*
X1659446Y964480D01*
X1658011Y965915D01*
X1650592D01*
X1646358Y967668D01*
X1643316Y969701D01*
X1639327D01*
X1635687Y973341D01*
X1625255D01*
X1621627Y976969D01*
X1609139D01*
X1606160Y979948D01*
X1588713D01*
X1586130Y982531D01*
X1563417D01*
X1560721Y979835D01*
X1544233D01*
X1535062Y989006D01*
X1489346D01*
X1484178Y994174D01*
Y996900D01*
G01X1715841Y960892D02*
X1712544Y964189D01*
X1709445D01*
X1698381Y975253D01*
X1684481D01*
X1683485Y976249D01*
X1678811D01*
X1675760Y979300D01*
X1644847D01*
X1644526Y978979D01*
X1641437D01*
X1638381Y982035D01*
X1631587D01*
X1626677Y986945D01*
X1624335D01*
X1623125Y985735D01*
X1619582D01*
X1618952Y986365D01*
Y989737D01*
X1618322Y990367D01*
X1616671D01*
X1616041Y989737D01*
Y986416D01*
X1615360Y985735D01*
X1612241D01*
X1609443Y988533D01*
X1603381D01*
X1602751Y989163D01*
Y990589D01*
X1602121Y991219D01*
X1600376D01*
X1599746Y990589D01*
Y989163D01*
X1599116Y988533D01*
X1594978D01*
X1594506Y989005D01*
Y990637D01*
X1593876Y991267D01*
X1590420D01*
X1588991Y992696D01*
X1566607D01*
X1556528Y1002775D01*
X1550050D01*
X1546814Y1002132D01*
X1544153Y1001029D01*
X1538506Y995382D01*
X1494657D01*
X1492878Y997161D01*
Y998759D01*
X1493803Y999684D01*
G01X1715841Y957546D02*
X1711244D01*
X1706214Y962576D01*
X1700626D01*
X1699321Y963881D01*
Y965709D01*
X1698249Y966781D01*
X1691808D01*
X1691308Y967281D01*
Y970114D01*
X1690678Y970744D01*
X1689308D01*
X1687810Y969246D01*
X1682204D01*
X1680056Y971394D01*
X1679038D01*
X1677280Y969636D01*
X1676262D01*
X1675349Y970549D01*
Y971567D01*
X1677107Y973325D01*
Y974343D01*
X1675496Y975954D01*
X1641424D01*
X1637641Y979737D01*
X1628125D01*
X1624425Y983437D01*
X1611289D01*
X1608492Y986234D01*
X1592079D01*
X1589854Y988459D01*
X1567646D01*
X1555000Y1001105D01*
X1550259D01*
X1547141Y1000483D01*
X1545278Y999713D01*
X1539627Y994062D01*
X1492618D01*
X1490104Y996576D01*
Y999684D01*
G01X1745541Y957546D02*
X1741514D01*
X1733145Y965915D01*
X1724075D01*
X1720729Y969261D01*
X1709779D01*
X1702832Y976208D01*
X1693592Y980035D01*
X1684801D01*
X1683555Y978789D01*
X1679691D01*
X1675833Y982647D01*
X1641659D01*
X1637916Y986390D01*
X1634032D01*
X1627087Y993335D01*
X1591268D01*
X1587628Y996975D01*
X1565619D01*
X1557883Y1004711D01*
X1550451D01*
X1546512Y1003928D01*
X1543131Y1002527D01*
X1537429Y996825D01*
X1512613D01*
G01X1715841Y1067979D02*
X1713942Y1066080D01*
X1710022D01*
X1708586Y1064644D01*
Y1059764D01*
X1709306Y1059044D01*
X1711182D01*
X1711902Y1058324D01*
Y1057034D01*
X1711182Y1056314D01*
X1709306D01*
X1708586Y1055594D01*
Y1053184D01*
X1709306Y1052464D01*
X1711083D01*
X1711803Y1051744D01*
Y1050454D01*
X1711083Y1049734D01*
X1709306D01*
X1708586Y1049014D01*
Y1034205D01*
X1706828Y1032447D01*
X1701061D01*
X1697541Y1028927D01*
X1683981D01*
X1682461Y1030447D01*
X1679212D01*
X1674916Y1026151D01*
X1669915D01*
X1666211Y1022447D01*
X1661915D01*
X1658211Y1026151D01*
X1623865D01*
X1621788Y1024074D01*
X1609355D01*
X1606726Y1026703D01*
X1603887D01*
X1603167Y1025983D01*
Y1024357D01*
X1602447Y1023637D01*
X1601157D01*
X1600437Y1024357D01*
Y1025983D01*
X1599717Y1026703D01*
X1596834D01*
X1595642Y1025511D01*
X1571668D01*
X1571665Y1025514D01*
X1548425D01*
X1539068Y1023653D01*
X1526167D01*
G01X1731818Y1071326D02*
Y1071192D01*
X1730281Y1069655D01*
X1722662D01*
X1721942Y1068935D01*
Y1067256D01*
X1721222Y1066536D01*
X1719932D01*
X1719212Y1067256D01*
Y1068935D01*
X1718492Y1069655D01*
X1709498D01*
X1706579Y1066736D01*
Y1039414D01*
X1704463Y1037298D01*
X1701713D01*
X1697862Y1033447D01*
X1692902D01*
X1692182Y1032727D01*
Y1031636D01*
X1691462Y1030916D01*
X1690172D01*
X1689452Y1031636D01*
Y1032727D01*
X1688732Y1033447D01*
X1684361D01*
X1683561Y1032647D01*
X1678553D01*
X1675403Y1029497D01*
X1670661D01*
X1667011Y1033147D01*
X1664194D01*
X1660543Y1029496D01*
X1659441Y1029497D01*
X1638836D01*
X1638247Y1028908D01*
X1624716D01*
X1623614Y1030010D01*
X1620052D01*
X1619422Y1029380D01*
Y1027432D01*
X1618710Y1026720D01*
X1617340D01*
X1616440Y1027620D01*
Y1029313D01*
X1615810Y1029943D01*
X1607571D01*
X1606667Y1029039D01*
X1596398D01*
X1594833Y1027474D01*
X1548228D01*
X1539177Y1025674D01*
X1529167D01*
G01X1731883Y1064633D02*
X1730212Y1062962D01*
X1714599D01*
X1713879Y1062242D01*
Y1033484D01*
X1710842Y1030447D01*
X1702061D01*
X1698361Y1026747D01*
X1684707D01*
X1677410Y1019450D01*
X1660615D01*
X1657261Y1022804D01*
X1644768D01*
X1643625Y1021661D01*
X1573442D01*
X1571549Y1023554D01*
X1548623D01*
X1539352Y1021710D01*
X1539311Y1021693D01*
X1526167D01*
G01X1715841Y1098097D02*
Y1097117D01*
X1714495Y1095771D01*
X1701022D01*
X1699737Y1094486D01*
Y1091867D01*
X1698765Y1090895D01*
X1684498D01*
X1676882Y1083279D01*
Y1080233D01*
X1676252Y1079603D01*
X1675142D01*
X1674512Y1078973D01*
Y1077503D01*
X1675142Y1076873D01*
X1676252D01*
X1676882Y1076243D01*
Y1074773D01*
X1676252Y1074143D01*
X1675142D01*
X1674512Y1073513D01*
Y1072043D01*
X1675142Y1071413D01*
X1676252D01*
X1676882Y1070783D01*
Y1068092D01*
X1675096Y1066306D01*
X1662159D01*
X1658816Y1062963D01*
X1654929D01*
X1654209Y1063683D01*
Y1065548D01*
X1653489Y1066268D01*
X1652199D01*
X1651479Y1065548D01*
Y1063683D01*
X1650759Y1062963D01*
X1649467D01*
X1646111Y1059607D01*
X1639790D01*
X1639070Y1060327D01*
Y1061723D01*
X1638350Y1062443D01*
X1637060D01*
X1636340Y1061723D01*
Y1060327D01*
X1635620Y1059607D01*
X1631559D01*
X1630839Y1060327D01*
Y1062858D01*
X1630119Y1063578D01*
X1628829D01*
X1628109Y1062858D01*
Y1060327D01*
X1627389Y1059607D01*
X1607895D01*
X1607216Y1060286D01*
Y1062238D01*
X1606586Y1062868D01*
X1605116D01*
X1604486Y1062238D01*
Y1060286D01*
X1603856Y1059656D01*
X1603650D01*
X1600039Y1056045D01*
X1596629D01*
X1584647Y1044063D01*
X1547310D01*
X1537007Y1042014D01*
X1529668D01*
G01X1731983Y1094751D02*
X1730306Y1093074D01*
X1723894D01*
X1723174Y1092354D01*
Y1090300D01*
X1722454Y1089580D01*
X1721164D01*
X1720444Y1090300D01*
Y1092354D01*
X1719724Y1093074D01*
X1713205D01*
X1712608Y1093671D01*
X1710483D01*
X1701967Y1089092D01*
X1699632D01*
X1695572Y1085032D01*
X1692786D01*
X1692066Y1085752D01*
Y1088154D01*
X1691346Y1088874D01*
X1690056D01*
X1689336Y1088154D01*
Y1085752D01*
X1688616Y1085032D01*
X1684198D01*
X1678946Y1079780D01*
Y1073334D01*
X1679666Y1072614D01*
X1681251D01*
X1681971Y1071894D01*
Y1070604D01*
X1681251Y1069884D01*
X1679666D01*
X1678946Y1069164D01*
Y1064847D01*
X1677061Y1062962D01*
X1669378D01*
X1668527Y1062111D01*
X1662074D01*
X1662006Y1062043D01*
X1657661Y1059616D01*
X1654622D01*
X1651431Y1056425D01*
X1640558D01*
X1638898Y1054765D01*
X1632033D01*
X1631331Y1055467D01*
X1624717D01*
X1623223Y1056961D01*
X1620243D01*
X1619550Y1056268D01*
X1603420D01*
X1600551Y1053399D01*
X1596755D01*
X1585420Y1042064D01*
X1547403D01*
X1537257Y1040046D01*
X1529668D01*
G01X1731983Y1088058D02*
X1730231D01*
X1729477Y1087304D01*
Y1085287D01*
X1728809Y1084619D01*
X1726571D01*
X1725851Y1083899D01*
Y1081481D01*
X1725131Y1080761D01*
X1723841D01*
X1723121Y1081481D01*
Y1083899D01*
X1722401Y1084619D01*
X1720424D01*
X1718660Y1086383D01*
X1708418D01*
X1702502Y1080467D01*
X1692712D01*
X1689930Y1077685D01*
Y1058494D01*
X1687710Y1056274D01*
X1663608D01*
X1662888Y1055554D01*
Y1050678D01*
X1661786Y1049576D01*
X1654570D01*
X1653827Y1050319D01*
X1640064D01*
X1636100Y1046355D01*
X1625821D01*
X1622522Y1049654D01*
X1607780D01*
X1604973Y1046847D01*
X1596587D01*
X1587773Y1038033D01*
X1547850D01*
X1538071Y1036088D01*
X1529668D01*
G01X1715841Y1104790D02*
X1713865Y1102814D01*
X1700156D01*
X1696861Y1099519D01*
X1683089D01*
X1682293Y1100315D01*
X1680455D01*
X1677840Y1097700D01*
Y1093731D01*
X1673836Y1089727D01*
X1670941D01*
X1667847Y1086633D01*
X1666096D01*
X1665466Y1086003D01*
Y1084533D01*
X1666096Y1083903D01*
X1667847D01*
X1668477Y1083273D01*
Y1081803D01*
X1667847Y1081173D01*
X1666230D01*
X1665600Y1080543D01*
Y1079073D01*
X1666230Y1078443D01*
X1667847D01*
X1668477Y1077813D01*
Y1075453D01*
X1666026Y1073002D01*
X1662692D01*
X1661458Y1071768D01*
X1659962D01*
X1658728Y1073002D01*
X1653706D01*
X1652472Y1071768D01*
X1650976D01*
X1649742Y1073002D01*
X1648340D01*
X1645584Y1070246D01*
X1642112D01*
X1641368Y1069502D01*
X1623954D01*
X1623357Y1070099D01*
X1619716D01*
X1618996Y1069379D01*
Y1066694D01*
X1618276Y1065974D01*
X1616986D01*
X1616266Y1066694D01*
Y1069379D01*
X1615546Y1070099D01*
X1609470D01*
X1607795Y1068424D01*
X1600231D01*
X1599203Y1069452D01*
X1594696D01*
X1574429Y1049185D01*
X1547014D01*
X1536600Y1047114D01*
X1529668D01*
G01X1731983Y1101444D02*
X1729458Y1098919D01*
X1727941D01*
X1727311Y1099549D01*
Y1102919D01*
X1726611Y1103619D01*
X1722582D01*
X1721811Y1102848D01*
Y1100619D01*
X1720965Y1099773D01*
X1715151D01*
X1714205Y1100719D01*
X1701161D01*
X1697589Y1097147D01*
X1683991D01*
X1679526Y1092682D01*
Y1091901D01*
X1674015Y1086390D01*
X1671459D01*
X1670540Y1085471D01*
Y1071074D01*
X1669115Y1069649D01*
X1648630D01*
X1644675Y1065694D01*
X1637459D01*
X1636182Y1066971D01*
X1625583D01*
X1622502Y1063890D01*
X1610299D01*
X1607824Y1066365D01*
X1594609D01*
X1575427Y1047183D01*
X1546998D01*
X1536725Y1045140D01*
X1529668D01*
G01X1731983Y1081365D02*
X1730961Y1080343D01*
X1729353D01*
X1725368Y1076358D01*
X1724209D01*
X1718680Y1078649D01*
X1717735D01*
X1716696Y1079688D01*
X1714685D01*
X1713751Y1078754D01*
X1711624D01*
X1708252Y1077352D01*
X1705113Y1074215D01*
X1700847Y1071929D01*
X1699395Y1069505D01*
X1699135Y1069070D01*
Y1061533D01*
X1698645Y1061043D01*
Y1058893D01*
X1699135Y1058403D01*
Y1056253D01*
X1698645Y1055763D01*
Y1053613D01*
X1699135Y1053123D01*
Y1050973D01*
X1698645Y1050483D01*
Y1048333D01*
X1699135Y1047843D01*
Y1046273D01*
X1695261Y1042399D01*
X1691986D01*
X1691496Y1042889D01*
X1689346D01*
X1688856Y1042399D01*
X1684316D01*
X1682338Y1044377D01*
X1679970D01*
X1677506Y1041913D01*
X1674608D01*
X1673644Y1042877D01*
X1671786D01*
X1671756Y1042847D01*
X1671660D01*
X1670584Y1041771D01*
X1664186D01*
X1660802Y1038387D01*
X1658521D01*
X1657377Y1039531D01*
X1655444D01*
X1654471Y1038558D01*
X1648562D01*
X1648072Y1039048D01*
X1645922D01*
X1645432Y1038558D01*
X1639053D01*
X1636632Y1036137D01*
X1632129D01*
X1631639Y1036627D01*
X1629489D01*
X1628999Y1036137D01*
X1625128D01*
X1622745Y1038520D01*
X1620595D01*
X1620105Y1039010D01*
X1617955D01*
X1617465Y1038520D01*
X1615315D01*
X1614825Y1039010D01*
X1612675D01*
X1612185Y1038520D01*
X1609600D01*
X1607276Y1036196D01*
X1602781D01*
X1602291Y1036686D01*
X1600141D01*
X1599651Y1036196D01*
X1594602D01*
X1591054Y1032648D01*
X1547622D01*
X1538629Y1030859D01*
X1530868D01*
G01X1731983Y1078018D02*
X1730878Y1079123D01*
X1729859D01*
X1725874Y1075138D01*
X1723966D01*
X1718437Y1077429D01*
X1717714D01*
X1716637Y1076352D01*
X1714817D01*
X1713635Y1077534D01*
X1711868D01*
X1708944Y1076317D01*
X1705849Y1073224D01*
X1701721Y1071012D01*
X1700818Y1069505D01*
X1700355Y1068732D01*
Y1045767D01*
X1695767Y1041179D01*
X1683810D01*
X1681832Y1043157D01*
X1680476D01*
X1678012Y1040693D01*
X1674801D01*
X1673644Y1039536D01*
X1671562D01*
X1670547Y1040551D01*
X1664692D01*
X1661308Y1037167D01*
X1658479D01*
X1657502Y1036190D01*
X1655420D01*
X1654272Y1037338D01*
X1639559D01*
X1637138Y1034917D01*
X1624622D01*
X1622239Y1037300D01*
X1610106D01*
X1607782Y1034976D01*
X1595108D01*
X1591560Y1031428D01*
X1547743D01*
X1538750Y1029639D01*
X1530868D01*
G01X1715841Y1134908D02*
X1713861Y1132928D01*
X1701152D01*
X1697507Y1136573D01*
X1664242D01*
X1657566Y1129897D01*
X1648671D01*
X1647005Y1128231D01*
Y1118544D01*
X1644360Y1115899D01*
X1639850D01*
X1630353Y1106402D01*
X1625985D01*
X1622354Y1102771D01*
X1619135D01*
X1618415Y1103491D01*
Y1106691D01*
X1617695Y1107411D01*
X1616405D01*
X1615685Y1106691D01*
Y1103491D01*
X1614965Y1102771D01*
X1610886D01*
X1607382Y1099267D01*
X1603952D01*
X1603232Y1099987D01*
Y1103492D01*
X1602512Y1104212D01*
X1601222D01*
X1600502Y1103492D01*
Y1099987D01*
X1599782Y1099267D01*
X1596319D01*
X1564616Y1067564D01*
X1545102D01*
X1534492Y1065454D01*
X1529668D01*
G01X1731983Y1131562D02*
X1730621Y1131168D01*
X1726207Y1129891D01*
X1701088D01*
X1696960Y1134019D01*
X1692506D01*
X1691876Y1133389D01*
Y1132832D01*
X1691246Y1132202D01*
X1689776D01*
X1689146Y1132832D01*
Y1133389D01*
X1688516Y1134019D01*
X1684127D01*
X1682694Y1132586D01*
X1674451D01*
X1673794Y1133243D01*
X1663768D01*
X1660835Y1130310D01*
Y1129158D01*
X1658214Y1126537D01*
X1651870D01*
X1649486Y1124153D01*
Y1117459D01*
X1645677Y1113650D01*
X1641819D01*
X1638762Y1110593D01*
Y1107036D01*
X1635983Y1104257D01*
X1627005D01*
X1623163Y1100415D01*
X1619321D01*
X1618258Y1099352D01*
X1616691D01*
X1615628Y1100415D01*
X1612289D01*
X1608481Y1096607D01*
X1603883D01*
X1603163Y1095887D01*
Y1094608D01*
X1602443Y1093888D01*
X1601153D01*
X1600433Y1094608D01*
Y1095887D01*
X1599713Y1096607D01*
X1596431D01*
X1565414Y1065590D01*
X1546261D01*
X1535642Y1063478D01*
X1529668D01*
G01X1731983Y1124869D02*
X1729294Y1127558D01*
X1724397D01*
X1720037Y1123198D01*
X1712283D01*
X1711333Y1124148D01*
X1709304D01*
X1707686Y1122530D01*
X1705825D01*
X1704707Y1123648D01*
X1701256D01*
X1700570Y1122962D01*
X1690478D01*
X1686897Y1126543D01*
X1683163D01*
X1682443Y1125823D01*
Y1124042D01*
X1681723Y1123322D01*
X1680433D01*
X1679713Y1124042D01*
Y1125823D01*
X1678993Y1126543D01*
X1669384D01*
X1659492Y1116651D01*
Y1111339D01*
X1657968Y1109815D01*
X1654511D01*
X1652127Y1107431D01*
X1648971D01*
X1647329Y1105789D01*
Y1104771D01*
X1648471Y1103629D01*
Y1102611D01*
X1647558Y1101698D01*
X1646540D01*
X1645398Y1102840D01*
X1644380D01*
X1638029Y1096489D01*
X1626105D01*
X1622816Y1093200D01*
X1611588D01*
X1608344Y1089956D01*
X1596520D01*
X1568059Y1061495D01*
X1545955D01*
X1535592Y1059434D01*
X1529668D01*
G01X1731818Y1108137D02*
X1731817Y1108136D01*
X1727471D01*
X1727111Y1107776D01*
Y1106619D01*
X1726411Y1105919D01*
X1723366D01*
X1722646Y1106639D01*
Y1109062D01*
X1721926Y1109782D01*
X1720636D01*
X1719916Y1109062D01*
Y1106639D01*
X1719196Y1105919D01*
X1717510D01*
X1716963Y1106466D01*
X1713614D01*
X1713061Y1107019D01*
X1709027D01*
X1708307Y1106299D01*
Y1105601D01*
X1707587Y1104881D01*
X1706297D01*
X1705577Y1105601D01*
Y1106299D01*
X1704857Y1107019D01*
X1700997D01*
X1698097Y1104119D01*
X1692483D01*
X1691763Y1103399D01*
Y1102257D01*
X1691043Y1101537D01*
X1689753D01*
X1689033Y1102257D01*
Y1103399D01*
X1688313Y1104119D01*
X1684503D01*
X1682859Y1102475D01*
X1679578D01*
X1675718Y1098615D01*
Y1094808D01*
X1673994Y1093084D01*
X1670416D01*
X1667730Y1090398D01*
X1664242D01*
X1663290Y1089446D01*
Y1079676D01*
X1659962Y1076348D01*
X1654978D01*
X1654007Y1077319D01*
X1649335D01*
X1644249Y1072233D01*
X1638262D01*
X1637034Y1073461D01*
X1625809D01*
X1624882Y1072534D01*
X1611101D01*
X1610199Y1073436D01*
X1595588D01*
X1573360Y1051208D01*
X1547135D01*
X1536527Y1049098D01*
X1529668D01*
G01X1715841Y1118176D02*
X1714734Y1119283D01*
X1713690D01*
X1712874Y1118467D01*
X1710724D01*
X1710234Y1117977D01*
X1708084D01*
X1707594Y1118467D01*
X1705444D01*
X1704954Y1117977D01*
X1702804D01*
X1702314Y1118467D01*
X1700164D01*
X1699674Y1117977D01*
X1697524D01*
X1697034Y1118467D01*
X1694884D01*
X1694394Y1117977D01*
X1692244D01*
X1691754Y1118467D01*
X1689604D01*
X1689114Y1117977D01*
X1686964D01*
X1686474Y1118467D01*
X1679444D01*
X1677082Y1120829D01*
X1674621D01*
X1673644Y1119852D01*
X1671562D01*
X1670488Y1120926D01*
X1668377D01*
X1662955Y1115504D01*
Y1113139D01*
X1663445Y1112649D01*
Y1110499D01*
X1662955Y1110009D01*
Y1103252D01*
X1660454Y1100751D01*
X1658479D01*
X1657502Y1099774D01*
X1655420D01*
X1654436Y1100758D01*
X1651174D01*
X1649400Y1098984D01*
Y1098291D01*
X1647878Y1096769D01*
X1647186D01*
X1644698Y1094281D01*
X1640127Y1092387D01*
X1637647Y1089909D01*
X1634951D01*
X1634461Y1089419D01*
X1632311D01*
X1631821Y1089909D01*
X1624749D01*
X1621908Y1087068D01*
X1618925D01*
X1618435Y1086578D01*
X1616285D01*
X1615795Y1087068D01*
X1613306D01*
X1608477Y1085068D01*
X1602014D01*
X1601524Y1084578D01*
X1599374D01*
X1598884Y1085068D01*
X1596689D01*
X1569929Y1058308D01*
X1546417D01*
X1536040Y1056243D01*
X1529668D01*
G01X1731983Y1118176D02*
X1730892Y1117085D01*
X1727594D01*
X1725830Y1118849D01*
X1722824D01*
X1719331Y1115356D01*
X1717838D01*
X1716699Y1116495D01*
X1714948D01*
X1713808Y1115355D01*
X1699998D01*
X1697082Y1112439D01*
X1692778D01*
X1692288Y1112929D01*
X1690138D01*
X1689648Y1112439D01*
X1685349D01*
X1683414Y1114374D01*
X1679962D01*
X1677597Y1112009D01*
X1674580D01*
X1673437Y1113152D01*
X1671428D01*
X1670493Y1112217D01*
X1668984D01*
X1667770Y1111003D01*
Y1106726D01*
X1667280Y1106236D01*
Y1104086D01*
X1667770Y1103596D01*
Y1101261D01*
X1664110Y1097601D01*
X1661848D01*
X1659716Y1095469D01*
X1658246D01*
X1657295Y1096420D01*
X1655286D01*
X1654351Y1095485D01*
X1651548D01*
X1648633Y1092570D01*
Y1088819D01*
X1647064Y1087250D01*
X1646371D01*
X1644849Y1085728D01*
Y1085035D01*
X1641818Y1082004D01*
X1640112Y1081297D01*
X1637962D01*
X1637472Y1081787D01*
X1635322D01*
X1634832Y1081297D01*
X1631741D01*
X1631251Y1081787D01*
X1629101D01*
X1628611Y1081297D01*
X1626461D01*
X1625971Y1081787D01*
X1623821D01*
X1623331Y1081297D01*
X1617008D01*
X1616518Y1081787D01*
X1614368D01*
X1613878Y1081297D01*
X1609272D01*
X1608782Y1081787D01*
X1606632D01*
X1606142Y1081297D01*
X1602669D01*
X1602179Y1081787D01*
X1600029D01*
X1599539Y1081297D01*
X1595692D01*
X1570743Y1056348D01*
X1546619D01*
X1536108Y1054257D01*
X1529668D01*
G01X1731983Y1114829D02*
X1730947Y1115865D01*
X1727088D01*
X1725324Y1117629D01*
X1723330D01*
X1719837Y1114136D01*
X1717879D01*
X1716902Y1113159D01*
X1714884D01*
X1713908Y1114135D01*
X1700504D01*
X1697588Y1111219D01*
X1684843D01*
X1682908Y1113154D01*
X1680468D01*
X1678103Y1110789D01*
X1674621D01*
X1673644Y1109812D01*
X1671562D01*
X1670377Y1110997D01*
X1669490D01*
X1668990Y1110497D01*
Y1100755D01*
X1664616Y1096381D01*
X1662354D01*
X1660222Y1094249D01*
X1658423D01*
X1657254Y1093080D01*
X1655420D01*
X1654235Y1094265D01*
X1652054D01*
X1649853Y1092064D01*
Y1088313D01*
X1642510Y1080969D01*
X1640580Y1080170D01*
X1640487Y1080077D01*
X1596198D01*
X1571249Y1055128D01*
X1546740D01*
X1536229Y1053037D01*
X1529668D01*
G01X1731983Y1198491D02*
X1730312Y1196820D01*
X1721866D01*
X1721236Y1197450D01*
Y1199538D01*
X1720606Y1200168D01*
X1719136D01*
X1718506Y1199538D01*
Y1197450D01*
X1717876Y1196820D01*
X1712283D01*
X1711833Y1197270D01*
X1710111D01*
X1708070Y1195229D01*
X1704811D01*
X1696350Y1186768D01*
X1691850D01*
X1688651Y1183569D01*
X1685261D01*
X1682361Y1180669D01*
X1680961D01*
X1677034Y1176742D01*
X1663525D01*
X1660179Y1173396D01*
X1652584D01*
X1652138Y1173842D01*
X1649175D01*
X1648545Y1173212D01*
Y1172098D01*
X1647915Y1171468D01*
X1646445D01*
X1645815Y1172098D01*
Y1173212D01*
X1645185Y1173842D01*
X1641284D01*
X1637996Y1170554D01*
X1635095D01*
X1627893Y1163352D01*
X1618670D01*
X1615439Y1160121D01*
X1611524D01*
X1609023Y1157620D01*
X1595428D01*
X1580085Y1142277D01*
Y1107538D01*
X1557435Y1084884D01*
X1534949D01*
X1531390Y1083410D01*
X1529668D01*
G01X1715841Y1178412D02*
X1713582D01*
X1711711Y1176541D01*
X1709299D01*
X1705711Y1172953D01*
Y1170819D01*
X1703611Y1168719D01*
X1698411D01*
X1695411Y1165719D01*
X1693411D01*
X1683511Y1155819D01*
X1680699D01*
X1679093Y1154213D01*
X1678075D01*
X1676649Y1155639D01*
X1675631D01*
X1674718Y1154726D01*
Y1153708D01*
X1676144Y1152282D01*
Y1151264D01*
X1674850Y1149970D01*
X1669612D01*
X1668981Y1150601D01*
Y1153269D01*
X1668041Y1154209D01*
X1665501D01*
X1657905Y1146613D01*
X1649558D01*
X1648838Y1147333D01*
Y1150372D01*
X1648118Y1151092D01*
X1646828D01*
X1646108Y1150372D01*
Y1147333D01*
X1645388Y1146613D01*
X1640725D01*
X1636931Y1142819D01*
X1631361D01*
X1629010Y1140468D01*
X1624956D01*
X1624312Y1139824D01*
X1610357D01*
X1606627Y1136094D01*
X1596407D01*
X1592325Y1132012D01*
Y1102459D01*
X1562510Y1072644D01*
X1537393D01*
X1533378Y1070981D01*
X1529668D01*
G01X1731818Y1181759D02*
X1730142Y1183435D01*
X1722668D01*
X1722038Y1182805D01*
Y1181598D01*
X1721408Y1180968D01*
X1719938D01*
X1719308Y1181598D01*
Y1182805D01*
X1718674Y1183439D01*
X1715162D01*
X1712364Y1180641D01*
X1710033D01*
X1703511Y1174119D01*
X1701111D01*
X1697611Y1170619D01*
X1694611D01*
X1687811Y1163819D01*
X1685611D01*
X1681953Y1160161D01*
X1677377D01*
X1673878Y1156662D01*
X1664254D01*
X1657561Y1149969D01*
X1655461D01*
X1652114Y1153316D01*
X1643072D01*
X1636670Y1146914D01*
X1632661D01*
X1628515Y1142768D01*
X1624602D01*
X1623851Y1143519D01*
X1610143D01*
X1606978Y1140354D01*
X1603510D01*
X1602880Y1139724D01*
Y1139723D01*
X1602250Y1139093D01*
X1600880D01*
X1600250Y1139723D01*
Y1139724D01*
X1599650Y1140324D01*
X1596762D01*
X1590365Y1133927D01*
Y1103271D01*
X1561698Y1074604D01*
X1537001D01*
X1533046Y1072966D01*
X1529668D01*
G01X1731983Y1175066D02*
X1730308Y1176741D01*
X1715161D01*
X1712055Y1173635D01*
X1709505D01*
X1707911Y1172041D01*
Y1167919D01*
X1702411Y1162419D01*
X1698711D01*
X1694811Y1158519D01*
X1689011D01*
X1684111Y1153619D01*
X1681611D01*
X1674615Y1146623D01*
X1671684D01*
X1670302Y1148005D01*
X1662497D01*
X1657769Y1143277D01*
X1655203D01*
X1654561Y1143919D01*
X1641111D01*
X1637711Y1140519D01*
X1631839D01*
X1627764Y1136444D01*
X1625777D01*
X1624389Y1137832D01*
X1611921D01*
X1608128Y1134039D01*
X1597125D01*
X1594285Y1131199D01*
Y1101647D01*
X1563322Y1070684D01*
X1537813D01*
X1533795Y1069020D01*
X1529668D01*
G01X1731983Y1191798D02*
X1730752Y1190567D01*
X1728963D01*
X1728189Y1191341D01*
X1722500D01*
X1720155Y1188996D01*
X1717809D01*
X1716684Y1190121D01*
X1714842D01*
X1713779Y1189058D01*
X1709251D01*
X1702242Y1182049D01*
X1701042D01*
X1698064Y1179071D01*
X1694237D01*
X1687650Y1172484D01*
X1686040D01*
X1681505Y1167949D01*
X1679742D01*
X1677335Y1165542D01*
X1674592D01*
X1673437Y1166697D01*
X1671428D01*
X1670359Y1165628D01*
X1664071D01*
X1660692Y1162249D01*
X1658397D01*
X1657295Y1163351D01*
X1655286D01*
X1654270Y1162335D01*
X1651168D01*
X1650678Y1162825D01*
X1648528D01*
X1648038Y1162335D01*
X1645888D01*
X1645398Y1162825D01*
X1643248D01*
X1642758Y1162335D01*
X1640364D01*
X1637636Y1159607D01*
X1636943D01*
X1635422Y1158086D01*
Y1157393D01*
X1633902Y1155873D01*
X1633209D01*
X1631688Y1154352D01*
Y1153659D01*
X1630168Y1152139D01*
X1628595D01*
X1627397Y1153337D01*
X1625696D01*
X1624556Y1152197D01*
X1622406D01*
X1621916Y1152687D01*
X1619766D01*
X1619276Y1152197D01*
X1617126D01*
X1616636Y1152687D01*
X1614486D01*
X1613996Y1152197D01*
X1611838D01*
X1604059Y1148972D01*
X1602524D01*
X1602034Y1149462D01*
X1599884D01*
X1599394Y1148972D01*
X1596991D01*
X1592693Y1144674D01*
X1592000D01*
X1590479Y1143153D01*
Y1142460D01*
X1588959Y1140940D01*
X1588266D01*
X1586745Y1139419D01*
Y1138726D01*
X1585225Y1137206D01*
Y1105403D01*
X1559566Y1079744D01*
X1535976D01*
X1532101Y1078139D01*
X1529668D01*
G01X1715841Y1195144D02*
X1714768Y1194071D01*
X1712865D01*
X1711547Y1192753D01*
X1705820D01*
X1697776Y1184709D01*
X1693612D01*
X1691583Y1182680D01*
X1690890D01*
X1689368Y1181158D01*
Y1180465D01*
X1687412Y1178509D01*
X1683850D01*
X1681307Y1175966D01*
X1680614D01*
X1679093Y1174445D01*
Y1173752D01*
X1677573Y1172232D01*
X1674594D01*
X1673437Y1173389D01*
X1671428D01*
X1670403Y1172364D01*
X1664027D01*
X1660563Y1168900D01*
X1658438D01*
X1657295Y1170043D01*
X1655286D01*
X1654268Y1169025D01*
X1652118D01*
X1651628Y1169515D01*
X1649478D01*
X1648988Y1169025D01*
X1645501D01*
X1645011Y1169515D01*
X1642861D01*
X1642371Y1169025D01*
X1640221D01*
X1635920Y1164724D01*
X1634407D01*
X1632647Y1162964D01*
X1631954D01*
X1630432Y1161442D01*
Y1160749D01*
X1628492Y1158809D01*
X1624004D01*
X1622614Y1160199D01*
X1620997D01*
X1619751Y1158953D01*
X1617080D01*
X1615706Y1157579D01*
X1608423Y1154558D01*
X1605936D01*
X1605446Y1155048D01*
X1603296D01*
X1602806Y1154558D01*
X1600656D01*
X1600166Y1155048D01*
X1598016D01*
X1597526Y1154558D01*
X1595840D01*
X1593247Y1151965D01*
X1592554D01*
X1591033Y1150444D01*
Y1149751D01*
X1589513Y1148231D01*
X1588820D01*
X1587299Y1146710D01*
Y1146017D01*
X1585779Y1144497D01*
X1585086D01*
X1583565Y1142976D01*
Y1142283D01*
X1582045Y1140763D01*
Y1106721D01*
X1558248Y1082924D01*
X1535339D01*
X1531752Y1081438D01*
X1529668D01*
G01X1731818Y1188452D02*
X1730923Y1189347D01*
X1728457D01*
X1727683Y1190121D01*
X1723006D01*
X1720661Y1187776D01*
X1717898D01*
X1716902Y1186780D01*
X1714820D01*
X1713762Y1187838D01*
X1709757D01*
X1702748Y1180829D01*
X1701548D01*
X1698570Y1177851D01*
X1694743D01*
X1688156Y1171264D01*
X1686546D01*
X1682011Y1166729D01*
X1680248D01*
X1677841Y1164322D01*
X1674609D01*
X1673644Y1163357D01*
X1672928D01*
X1672921Y1163350D01*
X1672061D01*
X1672054Y1163357D01*
X1671562D01*
X1670511Y1164408D01*
X1664577D01*
X1661198Y1161029D01*
X1658520D01*
X1657502Y1160011D01*
X1656769D01*
X1656761Y1160003D01*
X1655931D01*
X1655923Y1160011D01*
X1655420D01*
X1654316Y1161115D01*
X1640870D01*
X1630674Y1150919D01*
X1628586D01*
X1627595Y1149928D01*
X1625601D01*
X1624552Y1150977D01*
X1612081D01*
X1604302Y1147752D01*
X1597497D01*
X1586445Y1136700D01*
Y1104897D01*
X1560072Y1078524D01*
X1536219D01*
X1532344Y1076919D01*
X1529668D01*
G01X1731983Y1205184D02*
Y1204057D01*
X1731263Y1203337D01*
X1727620D01*
X1726999Y1202716D01*
X1724954D01*
X1724157Y1203513D01*
X1707964D01*
X1704412Y1199961D01*
X1701255D01*
X1697862Y1196568D01*
X1694084D01*
X1687791Y1190275D01*
X1683754D01*
X1676913Y1183434D01*
X1663570D01*
X1660224Y1180088D01*
X1652592D01*
X1651860Y1180820D01*
X1641863D01*
X1638662Y1177619D01*
X1634897D01*
X1627320Y1170042D01*
X1619090D01*
X1616016Y1166968D01*
X1613704D01*
X1613701Y1166965D01*
X1610601D01*
X1607845Y1164209D01*
X1596473D01*
X1576165Y1143901D01*
Y1109163D01*
X1555811Y1088804D01*
X1534167D01*
X1530794Y1087407D01*
X1527388D01*
X1525949Y1085968D01*
G01X1715841Y1208530D02*
X1713667Y1206356D01*
X1704426D01*
X1702911Y1204841D01*
X1701893D01*
X1701471Y1205263D01*
X1700453D01*
X1699540Y1204350D01*
Y1203332D01*
X1699962Y1202910D01*
Y1201892D01*
X1698789Y1200719D01*
X1694583D01*
X1693426Y1199562D01*
X1691766D01*
X1690665Y1198461D01*
Y1196801D01*
X1689621Y1195757D01*
X1688731D01*
X1687815Y1196673D01*
X1686925D01*
X1685884Y1195632D01*
Y1194742D01*
X1686800Y1193826D01*
Y1192936D01*
X1686135Y1192271D01*
X1678867D01*
X1673377Y1186781D01*
X1670761D01*
X1670131Y1187411D01*
Y1188930D01*
X1669501Y1189560D01*
X1668031D01*
X1667401Y1188930D01*
Y1187411D01*
X1666771Y1186781D01*
X1662555D01*
X1659209Y1183435D01*
X1650201D01*
X1649571Y1184065D01*
Y1186339D01*
X1648941Y1186969D01*
X1647471D01*
X1646841Y1186339D01*
Y1184065D01*
X1646211Y1183435D01*
X1641639D01*
X1637923Y1179719D01*
X1633973D01*
X1627643Y1173389D01*
X1624579D01*
X1623949Y1174019D01*
Y1175050D01*
X1623319Y1175680D01*
X1621849D01*
X1621219Y1175050D01*
Y1174019D01*
X1620589Y1173389D01*
X1619211D01*
X1614793Y1168971D01*
X1609549D01*
X1606767Y1166189D01*
X1595681D01*
X1574205Y1144713D01*
Y1109975D01*
X1554994Y1090764D01*
X1533777D01*
X1531505Y1089823D01*
X1528769D01*
G01X1775241Y1238648D02*
X1771409Y1234816D01*
X1768705D01*
X1767985Y1234096D01*
Y1232250D01*
X1767265Y1231530D01*
X1765975D01*
X1765255Y1232250D01*
Y1234096D01*
X1764535Y1234816D01*
X1758514D01*
X1755933Y1237397D01*
X1752654D01*
X1751992Y1236735D01*
Y1234719D01*
X1751126Y1233853D01*
X1749756D01*
X1748977Y1234632D01*
Y1236751D01*
X1748347Y1237381D01*
X1744434D01*
X1741820Y1234767D01*
X1739049D01*
X1736844Y1236972D01*
X1727030D01*
X1726161Y1237841D01*
X1721361D01*
X1718877Y1240325D01*
X1713277D01*
X1712361Y1241241D01*
X1710262D01*
X1703640Y1234619D01*
X1700640D01*
X1697666Y1231645D01*
X1692911D01*
X1688634Y1227368D01*
X1683789D01*
X1676657Y1220236D01*
X1665094D01*
X1661737Y1223593D01*
X1651475D01*
X1650419Y1224649D01*
X1648745D01*
X1647689Y1223593D01*
X1646015D01*
X1644959Y1224649D01*
X1643285D01*
X1642229Y1223593D01*
X1640735D01*
X1637861Y1220719D01*
X1635059D01*
X1632296Y1217956D01*
X1631406D01*
X1630403Y1218959D01*
X1629513D01*
X1628472Y1217918D01*
Y1217028D01*
X1629475Y1216025D01*
Y1215135D01*
X1629159Y1214819D01*
X1626059D01*
X1623559Y1217319D01*
X1621553D01*
X1619402Y1215168D01*
X1616930D01*
X1616314Y1214552D01*
Y1213662D01*
X1618355Y1211621D01*
Y1210731D01*
X1617314Y1209690D01*
X1616424D01*
X1614383Y1211731D01*
X1613493D01*
X1609326Y1207564D01*
X1607458D01*
X1606828Y1208194D01*
Y1209483D01*
X1606198Y1210113D01*
X1604728D01*
X1604098Y1209483D01*
Y1208194D01*
X1603468Y1207564D01*
X1601512D01*
X1598865Y1210211D01*
X1594646D01*
X1587207Y1202772D01*
Y1186228D01*
X1556285Y1155306D01*
Y1117682D01*
X1547393Y1108790D01*
X1528769D01*
G01X1791383Y1235302D02*
X1786918D01*
X1786352Y1235868D01*
Y1236886D01*
X1787816Y1238350D01*
Y1239368D01*
X1786903Y1240281D01*
X1785885D01*
X1784421Y1238817D01*
X1783403D01*
X1781896Y1240324D01*
X1768616D01*
X1765111Y1236819D01*
X1760211D01*
X1757662Y1239368D01*
X1743833D01*
X1742877Y1240324D01*
X1727444D01*
X1726961Y1239841D01*
X1722460D01*
X1718631Y1243670D01*
X1709862D01*
X1702811Y1236619D01*
X1699811D01*
X1696823Y1233631D01*
X1692044D01*
X1687873Y1229460D01*
X1683004D01*
X1677135Y1223591D01*
X1665140D01*
X1661793Y1226938D01*
X1653575D01*
X1652855Y1227658D01*
Y1228469D01*
X1652135Y1229189D01*
X1650845D01*
X1650125Y1228469D01*
Y1227658D01*
X1649405Y1226938D01*
X1641080D01*
X1637661Y1223519D01*
X1634162D01*
X1633442Y1222799D01*
Y1221912D01*
X1632722Y1221192D01*
X1631432D01*
X1630712Y1221912D01*
Y1222799D01*
X1629992Y1223519D01*
X1627561D01*
X1623461Y1219419D01*
X1620761D01*
X1618922Y1217580D01*
X1611733D01*
X1608537Y1214384D01*
X1603250D01*
X1602430Y1213564D01*
X1600620D01*
X1599800Y1214384D01*
X1595193D01*
X1585175Y1204366D01*
Y1187064D01*
X1554325Y1156214D01*
Y1118767D01*
X1546318Y1110760D01*
X1528658D01*
G01X1775241Y1215223D02*
X1773043D01*
X1770162Y1212342D01*
X1757964D01*
X1756350Y1213956D01*
X1753768D01*
X1749253Y1209441D01*
X1744661D01*
X1743361Y1210741D01*
X1740367D01*
X1738532Y1208906D01*
X1735270D01*
X1734640Y1209536D01*
Y1209577D01*
X1734010Y1210207D01*
X1730236D01*
X1729004Y1211439D01*
X1727506D01*
X1726274Y1210207D01*
X1723019D01*
X1721461Y1211765D01*
Y1212833D01*
X1720742Y1213552D01*
X1708249D01*
X1706882Y1212185D01*
X1705563D01*
X1704196Y1213552D01*
X1700344D01*
X1696611Y1209819D01*
X1693311D01*
X1686111Y1202619D01*
X1684711D01*
X1681711Y1199619D01*
X1677435D01*
X1674635Y1196819D01*
X1670464D01*
X1669277Y1198006D01*
X1667734D01*
X1666547Y1196819D01*
X1661561D01*
X1658214Y1200166D01*
X1653158D01*
X1652509Y1199517D01*
X1649401D01*
X1648681Y1200237D01*
Y1201414D01*
X1647961Y1202134D01*
X1646671D01*
X1645951Y1201414D01*
Y1200237D01*
X1645231Y1199517D01*
X1643559D01*
X1640696Y1196654D01*
X1639678D01*
X1638333Y1197999D01*
X1637315D01*
X1636402Y1197086D01*
Y1196068D01*
X1637747Y1194723D01*
Y1193705D01*
X1636834Y1192792D01*
X1635816D01*
X1634471Y1194137D01*
X1633453D01*
X1632540Y1193224D01*
Y1192206D01*
X1633885Y1190861D01*
Y1189843D01*
X1632972Y1188930D01*
X1631954D01*
X1630609Y1190275D01*
X1629591D01*
X1628678Y1189362D01*
Y1188344D01*
X1630023Y1186999D01*
Y1185981D01*
X1629181Y1185139D01*
X1625151D01*
X1623141Y1183129D01*
X1621123Y1182293D01*
X1620183Y1182683D01*
X1619576Y1184149D01*
X1618637Y1184539D01*
X1617443Y1184044D01*
X1617053Y1183104D01*
X1617660Y1181638D01*
X1617270Y1180698D01*
X1615801Y1180089D01*
X1611918D01*
X1610770Y1181237D01*
X1609076D01*
X1607928Y1180089D01*
X1604816D01*
X1603773Y1179046D01*
X1602883D01*
X1601650Y1180279D01*
X1600760D01*
X1599719Y1179238D01*
Y1178348D01*
X1600952Y1177115D01*
Y1176225D01*
X1597842Y1173115D01*
X1594561D01*
X1568525Y1147079D01*
Y1112328D01*
X1552641Y1096444D01*
X1532645D01*
X1530465Y1095541D01*
X1528769D01*
G01X1791383Y1218570D02*
X1788707Y1215894D01*
X1787526D01*
X1786611Y1216809D01*
Y1221946D01*
X1785980Y1222577D01*
X1784717D01*
X1782157Y1222581D01*
X1781436Y1221862D01*
Y1217530D01*
X1780806Y1216900D01*
X1774522D01*
X1773566Y1217856D01*
X1768788D01*
X1768068Y1217136D01*
Y1215525D01*
X1767348Y1214805D01*
X1766058D01*
X1765338Y1215525D01*
Y1217136D01*
X1764618Y1217856D01*
X1758306D01*
X1756491Y1216041D01*
X1752857D01*
X1751057Y1214241D01*
X1744961D01*
X1743561Y1212841D01*
X1736867D01*
X1736154Y1213554D01*
X1728048D01*
X1727261Y1214341D01*
X1723162D01*
X1720562Y1216941D01*
X1717745D01*
X1717703Y1216899D01*
X1700220D01*
X1697440Y1214119D01*
X1694440D01*
X1687540Y1207219D01*
X1685540D01*
X1682540Y1204219D01*
X1678922D01*
X1674869Y1200166D01*
X1662008D01*
X1658661Y1203513D01*
X1653367D01*
X1652761Y1204119D01*
X1641461D01*
X1637905Y1200563D01*
X1635052D01*
X1623231Y1188742D01*
X1619332D01*
X1614024Y1183434D01*
X1611968D01*
X1611338Y1184064D01*
Y1184694D01*
X1610336Y1185696D01*
X1609238D01*
X1608608Y1185066D01*
Y1184064D01*
X1607978Y1183434D01*
X1606508D01*
X1605878Y1184064D01*
Y1186913D01*
X1605248Y1187543D01*
X1603778D01*
X1603148Y1186913D01*
Y1184064D01*
X1602518Y1183434D01*
X1601081D01*
X1597731Y1180084D01*
X1596265D01*
X1566565Y1150384D01*
Y1113140D01*
X1551829Y1098404D01*
X1532253D01*
X1530134Y1097526D01*
X1529359D01*
G01X1791383Y1211877D02*
X1789706Y1213554D01*
X1774448D01*
X1771214Y1210320D01*
X1758061D01*
X1749385Y1206861D01*
X1731332D01*
X1730975Y1207009D01*
X1729207Y1207741D01*
X1721951D01*
X1719485Y1210207D01*
X1700111D01*
X1697523Y1207619D01*
X1694223D01*
X1687023Y1200419D01*
X1685333D01*
X1682333Y1197419D01*
X1678211D01*
X1674266Y1193474D01*
X1670294D01*
X1669067Y1194701D01*
X1667564D01*
X1666337Y1193474D01*
X1661906D01*
X1658561Y1196819D01*
X1649135D01*
X1648709Y1196393D01*
X1647691D01*
X1646605Y1197479D01*
X1645587D01*
X1644674Y1196566D01*
Y1195548D01*
X1645760Y1194462D01*
Y1193444D01*
X1644686Y1192370D01*
X1643796D01*
X1642774Y1193392D01*
X1641884D01*
X1640843Y1192351D01*
Y1191461D01*
X1641865Y1190439D01*
Y1189549D01*
X1640824Y1188508D01*
X1639934D01*
X1639146Y1189296D01*
X1638256D01*
X1637215Y1188255D01*
Y1187365D01*
X1638003Y1186577D01*
Y1185687D01*
X1637135Y1184819D01*
X1633311D01*
X1627591Y1179099D01*
X1624821D01*
X1623832Y1180088D01*
X1620940D01*
X1617593Y1176741D01*
X1612040D01*
X1611665Y1176366D01*
X1610647D01*
X1608931Y1178082D01*
X1607913D01*
X1607000Y1177169D01*
Y1176151D01*
X1608716Y1174435D01*
Y1173417D01*
X1605469Y1170170D01*
X1604008D01*
X1603288Y1170890D01*
Y1172994D01*
X1602568Y1173714D01*
X1601278D01*
X1600558Y1172994D01*
Y1170890D01*
X1599838Y1170170D01*
X1594394D01*
X1570485Y1146261D01*
Y1111516D01*
X1553453Y1094484D01*
X1533036D01*
X1530769Y1093545D01*
X1528769D01*
G01X1791383Y1228609D02*
X1790295Y1227521D01*
X1787572D01*
X1785971Y1228184D01*
X1782005D01*
X1779729Y1225908D01*
X1777057D01*
X1776032Y1226933D01*
X1774508D01*
X1773485Y1225910D01*
X1758567D01*
X1755946Y1228531D01*
X1752577D01*
X1747507Y1223461D01*
X1744467D01*
X1742894Y1225034D01*
X1739436D01*
X1736917Y1222515D01*
X1733744D01*
X1732672Y1223587D01*
X1731168D01*
X1730181Y1222600D01*
X1727828D01*
X1727338Y1223090D01*
X1725188D01*
X1724698Y1222600D01*
X1722548D01*
X1719300Y1225848D01*
X1717621D01*
X1716536Y1226933D01*
X1715066D01*
X1713996Y1225863D01*
X1711846D01*
X1711356Y1226353D01*
X1709206D01*
X1708716Y1225863D01*
X1706566D01*
X1706076Y1226353D01*
X1703926D01*
X1703436Y1225863D01*
X1701402D01*
X1697748Y1222209D01*
X1694000D01*
X1691928Y1220137D01*
X1691235D01*
X1689713Y1218615D01*
Y1217922D01*
X1688000Y1216209D01*
X1685350D01*
X1680537Y1211396D01*
X1678761D01*
X1676462Y1209097D01*
X1674451D01*
X1673347Y1210201D01*
X1671828D01*
X1670819Y1209192D01*
X1668344D01*
X1667854Y1209682D01*
X1665704D01*
X1665214Y1209192D01*
X1663064D01*
X1659835Y1212421D01*
X1658278D01*
X1657151Y1213548D01*
X1655462D01*
X1654622Y1212708D01*
X1652550D01*
X1652060Y1213198D01*
X1649910D01*
X1649420Y1212708D01*
X1647270D01*
X1646780Y1213198D01*
X1644630D01*
X1644140Y1212708D01*
X1640824D01*
X1637255Y1209139D01*
X1633173D01*
X1630919Y1206885D01*
X1630226D01*
X1628705Y1205364D01*
Y1204671D01*
X1625913Y1201879D01*
X1624531D01*
X1622265Y1199613D01*
X1621572D01*
X1620051Y1198092D01*
Y1197399D01*
X1618391Y1195739D01*
X1614949D01*
X1613873Y1196815D01*
X1612500D01*
X1611494Y1195809D01*
X1605692D01*
X1602341Y1199160D01*
X1598772D01*
X1597779Y1200153D01*
X1596251D01*
X1595278Y1199180D01*
X1594034D01*
X1592404Y1197550D01*
Y1184058D01*
X1561425Y1153079D01*
Y1115270D01*
X1549699Y1103544D01*
X1531184D01*
X1529146Y1102700D01*
X1528769D01*
G01X1775241Y1231955D02*
X1774143Y1230857D01*
X1771807D01*
X1770051Y1229101D01*
X1766011D01*
X1765521Y1229591D01*
X1763371D01*
X1762881Y1229101D01*
X1759955D01*
X1757304Y1231752D01*
X1751105D01*
X1748924Y1229571D01*
X1746774D01*
X1746284Y1230061D01*
X1744134D01*
X1743644Y1229571D01*
X1739446D01*
X1736416Y1232601D01*
X1733709D01*
X1732684Y1233626D01*
X1731294D01*
X1730269Y1232601D01*
X1728135D01*
X1727645Y1233091D01*
X1725495D01*
X1725005Y1232601D01*
X1722730D01*
X1719427Y1235904D01*
X1717609D01*
X1716540Y1236973D01*
X1715146D01*
X1714071Y1235898D01*
X1708791D01*
X1707237Y1234344D01*
X1706544D01*
X1705023Y1232823D01*
Y1232130D01*
X1702032Y1229139D01*
X1699882D01*
X1699392Y1229629D01*
X1697242D01*
X1696752Y1229139D01*
X1694006D01*
X1692245Y1227378D01*
X1691552D01*
X1690030Y1225856D01*
Y1225163D01*
X1687216Y1222349D01*
X1684304D01*
X1681529Y1219574D01*
X1680836D01*
X1679315Y1218053D01*
Y1217360D01*
X1677795Y1215840D01*
X1674374D01*
X1673321Y1216893D01*
X1671824D01*
X1670732Y1215801D01*
X1668166D01*
X1667676Y1216291D01*
X1665526D01*
X1665036Y1215801D01*
X1663286D01*
X1659895Y1219192D01*
X1658199D01*
X1657151Y1220240D01*
X1655596D01*
X1654467Y1219111D01*
X1652525D01*
X1652035Y1219601D01*
X1649885D01*
X1649395Y1219111D01*
X1646533D01*
X1646043Y1219601D01*
X1643893D01*
X1643403Y1219111D01*
X1640766D01*
X1635218Y1215404D01*
X1634539Y1215539D01*
X1632750Y1214343D01*
X1632615Y1213663D01*
X1623382Y1207493D01*
X1618321Y1202432D01*
X1614985D01*
X1613909Y1203508D01*
X1612444D01*
X1611423Y1202487D01*
X1609033D01*
X1608543Y1202977D01*
X1606393D01*
X1605903Y1202487D01*
X1603753D01*
X1600430Y1205810D01*
X1598849D01*
X1597815Y1206844D01*
X1596345D01*
X1595227Y1205726D01*
X1593304D01*
X1589207Y1201629D01*
Y1185422D01*
X1558245Y1154460D01*
Y1116589D01*
X1548423Y1106767D01*
X1528769D01*
G01X1791383Y1225263D02*
X1790345Y1226301D01*
X1787329D01*
X1785728Y1226964D01*
X1782511D01*
X1780235Y1224688D01*
X1777033D01*
X1775938Y1223593D01*
X1774536D01*
X1773439Y1224690D01*
X1758061D01*
X1755440Y1227311D01*
X1753083D01*
X1748013Y1222241D01*
X1743961D01*
X1742388Y1223814D01*
X1739942D01*
X1737423Y1221295D01*
X1733734D01*
X1732679Y1220240D01*
X1731273D01*
X1730133Y1221380D01*
X1722042D01*
X1718794Y1224628D01*
X1717589D01*
X1716554Y1223593D01*
X1715088D01*
X1714038Y1224643D01*
X1701908D01*
X1698254Y1220989D01*
X1694506D01*
X1688506Y1214989D01*
X1685856D01*
X1681043Y1210176D01*
X1679267D01*
X1676968Y1207877D01*
X1674332D01*
X1673319Y1206864D01*
X1671823D01*
X1670715Y1207972D01*
X1662558D01*
X1659329Y1211201D01*
X1658355D01*
X1657362Y1210208D01*
X1655762D01*
X1654482Y1211488D01*
X1641330D01*
X1637761Y1207919D01*
X1633679D01*
X1626419Y1200659D01*
X1625037D01*
X1618897Y1194519D01*
X1614924D01*
X1613880Y1193475D01*
X1612496D01*
X1611382Y1194589D01*
X1605186D01*
X1601835Y1197940D01*
X1598919D01*
X1597783Y1196804D01*
X1596300D01*
X1595144Y1197960D01*
X1594540D01*
X1593624Y1197044D01*
Y1183552D01*
X1562645Y1152573D01*
Y1114764D01*
X1550205Y1102324D01*
X1531427D01*
X1529389Y1101480D01*
X1528769D01*
G01X1791383Y1241995D02*
X1789705Y1243673D01*
X1782362D01*
X1781642Y1244393D01*
Y1246500D01*
X1780922Y1247220D01*
X1779632D01*
X1778912Y1246500D01*
Y1244393D01*
X1778192Y1243673D01*
X1769074D01*
X1763251Y1241319D01*
X1759497D01*
X1755067Y1243658D01*
X1752579D01*
X1751859Y1242938D01*
Y1242048D01*
X1751139Y1241328D01*
X1749849D01*
X1749129Y1242048D01*
Y1242938D01*
X1748409Y1243658D01*
X1724866D01*
X1716759Y1247017D01*
X1709909D01*
X1705216Y1242324D01*
X1702541Y1241319D01*
X1700251Y1240659D01*
X1697311Y1237719D01*
X1692595D01*
X1691875Y1236999D01*
Y1236098D01*
X1691155Y1235378D01*
X1689865D01*
X1689145Y1236098D01*
Y1236999D01*
X1688425Y1237719D01*
X1687641D01*
X1685452Y1237264D01*
X1683547Y1235359D01*
X1674581Y1230285D01*
X1671906D01*
X1670081Y1230386D01*
X1668753Y1230565D01*
X1668045Y1230025D01*
X1667743Y1227794D01*
X1667035Y1227254D01*
X1665676Y1227439D01*
X1665136Y1228147D01*
X1665438Y1230378D01*
X1664898Y1231086D01*
X1662916Y1231355D01*
X1657699Y1233527D01*
X1657449Y1233631D01*
X1650647D01*
X1646970Y1231960D01*
X1646657Y1231127D01*
X1647016Y1230339D01*
X1646703Y1229506D01*
X1645454Y1228937D01*
X1644621Y1229250D01*
X1644262Y1230038D01*
X1643429Y1230351D01*
X1641742Y1229583D01*
X1634974Y1228512D01*
X1634376Y1227690D01*
X1634545Y1226630D01*
X1633946Y1225807D01*
X1632671Y1225604D01*
X1631848Y1226203D01*
X1631679Y1227262D01*
X1630856Y1227861D01*
X1624657Y1226879D01*
X1623913Y1226471D01*
X1617522Y1220080D01*
X1611406D01*
X1607977Y1216651D01*
X1604173D01*
X1603453Y1217371D01*
Y1219222D01*
X1602733Y1219942D01*
X1601443D01*
X1600723Y1219222D01*
Y1217371D01*
X1600003Y1216651D01*
X1593536D01*
X1583209Y1206324D01*
Y1187936D01*
X1552365Y1157092D01*
Y1119886D01*
X1545212Y1112733D01*
X1527337D01*
X1527011Y1112407D01*
G01X1715841Y796916D02*
X1714180Y795255D01*
X1679685D01*
X1676348Y798592D01*
X1670034D01*
X1666687Y795245D01*
X1663157D01*
X1661934Y796468D01*
X1660427D01*
X1659204Y795245D01*
X1653487D01*
X1652961Y794719D01*
X1648984D01*
X1648264Y795439D01*
Y796690D01*
X1647544Y797410D01*
X1646254D01*
X1645534Y796690D01*
Y795439D01*
X1644814Y794719D01*
X1641261D01*
X1639961Y796019D01*
X1633505D01*
X1632875Y795389D01*
Y794498D01*
X1632245Y793868D01*
X1630775D01*
X1630145Y794498D01*
Y795389D01*
X1629515Y796019D01*
X1624961D01*
X1623561Y794619D01*
X1612061D01*
X1611261Y795419D01*
X1603855D01*
X1603225Y794789D01*
Y791235D01*
X1602595Y790605D01*
X1601125D01*
X1600495Y791235D01*
Y794789D01*
X1599865Y795419D01*
X1595861D01*
X1569316Y821964D01*
Y825719D01*
X1536845Y858190D01*
G01X1745541Y960892D02*
X1745441D01*
X1744403Y961930D01*
X1732921Y969261D01*
X1730691D01*
X1725600Y972607D01*
X1710023D01*
X1705177Y977453D01*
X1694006Y982080D01*
X1692536D01*
X1691816Y982800D01*
Y986075D01*
X1691096Y986795D01*
X1689806D01*
X1689086Y986075D01*
Y982800D01*
X1688366Y982080D01*
X1684354D01*
X1680441Y985993D01*
X1641447D01*
X1638755Y988685D01*
X1635107D01*
X1627674Y996118D01*
X1592898D01*
X1588613Y1000403D01*
X1565952D01*
X1559845Y1006510D01*
X1550297D01*
X1545847Y1005625D01*
X1542139Y1004089D01*
X1536365Y998315D01*
X1518204D01*
G01X1804941Y960892D02*
X1804841D01*
X1802458Y958509D01*
X1799879D01*
X1794715Y963673D01*
Y970604D01*
X1792711Y972608D01*
X1782974D01*
X1776281Y979301D01*
X1766101D01*
X1760973Y984429D01*
X1756908D01*
X1731920Y1009417D01*
X1730796D01*
X1730795Y1009416D01*
X1725994D01*
X1725274Y1008696D01*
Y1005588D01*
X1724554Y1004868D01*
X1723264D01*
X1722544Y1005588D01*
Y1008696D01*
X1721824Y1009416D01*
X1572032D01*
X1567294Y1014154D01*
X1549559D01*
X1542808Y1012811D01*
X1533424Y1008924D01*
X1531100Y1006600D01*
X1527067D01*
G01X1775241Y960892D02*
X1774106Y960422D01*
X1773463D01*
X1764787Y969098D01*
X1746931Y978749D01*
X1739686Y985994D01*
X1726655D01*
X1716044Y996605D01*
X1715026D01*
X1710849Y992428D01*
X1709831D01*
X1708918Y993341D01*
Y994359D01*
X1713095Y998536D01*
Y999554D01*
X1712182Y1000467D01*
X1711164D01*
X1706987Y996290D01*
X1705969D01*
X1705056Y997203D01*
Y998221D01*
X1709233Y1002398D01*
Y1003416D01*
X1707210Y1005439D01*
X1625373D01*
Y1005438D01*
X1566282D01*
X1561490Y1010230D01*
X1549928D01*
X1544484Y1009147D01*
X1538417Y1006634D01*
X1534057Y1002274D01*
X1527067D01*
G01X1804941Y957546D02*
Y957646D01*
X1807151Y959856D01*
Y961489D01*
X1806072Y962568D01*
X1802462D01*
X1798061Y966969D01*
Y970972D01*
X1793079Y975954D01*
X1782782D01*
X1776089Y982647D01*
X1771163D01*
X1762221Y991589D01*
X1756141D01*
X1752111Y995619D01*
X1748954D01*
X1733190Y1011383D01*
X1572984D01*
X1568253Y1016114D01*
X1549364D01*
X1541572Y1014564D01*
X1531855Y1010539D01*
X1530144Y1008828D01*
X1527067D01*
G01X1775241Y957546D02*
Y957646D01*
X1777111Y959516D01*
Y961662D01*
X1776211Y962562D01*
X1774453D01*
X1772561Y964454D01*
Y969957D01*
X1771169Y971349D01*
X1767073D01*
X1760893Y977529D01*
X1759061D01*
X1755661Y980929D01*
X1752391D01*
X1743980Y989340D01*
X1739111D01*
X1738391Y990060D01*
Y991815D01*
X1737671Y992535D01*
X1736381D01*
X1735661Y991815D01*
Y990060D01*
X1734941Y989340D01*
X1729591D01*
X1719462Y999469D01*
Y1000487D01*
X1720615Y1001640D01*
Y1002658D01*
X1719702Y1003571D01*
X1718684D01*
X1717531Y1002418D01*
X1716513D01*
X1715600Y1003331D01*
Y1004349D01*
X1716753Y1005502D01*
Y1006520D01*
X1715840Y1007433D01*
X1714822D01*
X1713669Y1006280D01*
X1712651D01*
X1711482Y1007449D01*
X1567725D01*
X1562980Y1012194D01*
X1549755D01*
X1543505Y1010951D01*
X1536064Y1007869D01*
X1532810Y1004615D01*
X1527067D01*
G01X1775241Y1245341D02*
X1773565Y1247017D01*
X1766589D01*
X1762891Y1243319D01*
X1760288D01*
X1757908Y1245699D01*
X1752891D01*
X1752171Y1246419D01*
Y1250957D01*
X1751451Y1251677D01*
X1750161D01*
X1749441Y1250957D01*
Y1246419D01*
X1748721Y1245699D01*
X1743780D01*
X1742462Y1247017D01*
X1740678D01*
X1739662Y1248033D01*
Y1249942D01*
X1738880Y1250724D01*
X1736826D01*
X1735927Y1249825D01*
Y1247840D01*
X1735104Y1247017D01*
X1730509D01*
X1729339Y1245847D01*
X1724773D01*
X1720129Y1250491D01*
X1714605D01*
X1713099Y1248985D01*
X1708907D01*
X1704021Y1244099D01*
X1702453Y1243388D01*
X1699260D01*
X1695691Y1239819D01*
X1685111D01*
X1682396Y1237104D01*
X1680951Y1236409D01*
X1676551D01*
X1673759Y1233617D01*
X1663910D01*
X1660549Y1236978D01*
X1649247D01*
X1648527Y1237698D01*
Y1239908D01*
X1647807Y1240628D01*
X1646517D01*
X1645797Y1239908D01*
Y1237698D01*
X1645077Y1236978D01*
X1643520D01*
X1637498Y1230956D01*
X1633045D01*
X1632325Y1231676D01*
Y1234890D01*
X1631605Y1235610D01*
X1630315D01*
X1629595Y1234890D01*
Y1231676D01*
X1628875Y1230956D01*
X1624998D01*
X1617937Y1223895D01*
X1608564D01*
X1606653Y1221984D01*
X1595644D01*
X1581242Y1207582D01*
Y1188808D01*
X1550405Y1157971D01*
Y1120974D01*
X1544124Y1114693D01*
X1525350D01*
X1525037Y1114380D01*
G01X1715841Y773491D02*
X1710824Y768474D01*
X1670815D01*
X1667300Y764959D01*
X1649450D01*
X1648730Y765679D01*
Y766389D01*
X1648010Y767109D01*
X1646720D01*
X1646000Y766389D01*
Y765679D01*
X1645280Y764959D01*
X1637293D01*
X1636573Y765679D01*
Y767668D01*
X1635853Y768388D01*
X1634563D01*
X1633843Y767668D01*
Y765679D01*
X1633123Y764959D01*
X1619511D01*
X1615436Y769034D01*
X1607352D01*
X1607237Y768919D01*
X1607211D01*
X1606516Y768224D01*
X1596530D01*
X1553925Y810829D01*
Y820233D01*
X1529337Y844821D01*
G01X1731983Y776837D02*
X1731947Y776856D01*
X1726370Y775168D01*
X1701357D01*
X1698009Y771820D01*
X1670362D01*
X1667016Y768474D01*
X1653406D01*
X1652761Y769119D01*
X1642431D01*
X1637773Y770515D01*
X1636069Y772219D01*
X1633495D01*
X1632775Y771499D01*
Y769574D01*
X1632055Y768854D01*
X1630765D01*
X1630045Y769574D01*
Y771499D01*
X1629325Y772219D01*
X1624961D01*
X1624161Y771419D01*
X1622411D01*
X1621781Y770789D01*
Y769098D01*
X1621151Y768468D01*
X1619681D01*
X1619051Y769098D01*
Y770789D01*
X1618421Y771419D01*
X1610461D01*
X1610028Y771852D01*
X1596166D01*
X1556127Y811989D01*
X1556138Y820842D01*
X1530776Y846260D01*
G01X1731983Y770144D02*
X1726592Y767911D01*
X1709820Y762822D01*
X1694228Y762794D01*
X1693507Y763513D01*
X1693505Y764365D01*
X1693502Y765737D01*
X1692782Y766455D01*
X1691491Y766451D01*
X1690772Y765730D01*
X1690775Y764365D01*
X1690777Y763506D01*
X1690059Y762786D01*
X1617244Y762651D01*
X1615081Y764814D01*
X1597162D01*
X1551937Y810039D01*
Y819323D01*
X1527888Y843372D01*
G01X1715841Y803609D02*
X1713486Y801254D01*
X1701008D01*
X1700378Y801884D01*
Y803935D01*
X1699748Y804565D01*
X1698278D01*
X1697648Y803935D01*
Y801884D01*
X1697018Y801254D01*
X1696300D01*
X1693681Y803873D01*
X1685115D01*
X1683040Y801798D01*
X1680548D01*
X1677061Y805285D01*
X1669527D01*
X1666180Y801938D01*
X1663776D01*
X1663056Y802658D01*
Y803935D01*
X1662336Y804655D01*
X1661046D01*
X1660326Y803935D01*
Y802658D01*
X1659606Y801938D01*
X1649285D01*
X1648565Y802658D01*
Y804171D01*
X1647845Y804891D01*
X1646555D01*
X1645835Y804171D01*
Y802658D01*
X1645115Y801938D01*
X1641242D01*
X1640061Y803119D01*
X1626261D01*
X1624663Y801521D01*
X1619968D01*
X1619248Y802241D01*
Y804036D01*
X1618528Y804756D01*
X1617238D01*
X1616518Y804036D01*
Y802241D01*
X1615798Y801521D01*
X1610659D01*
X1609846Y802334D01*
X1602983D01*
X1602263Y803054D01*
Y804743D01*
X1601543Y805463D01*
X1600253D01*
X1599533Y804743D01*
Y803054D01*
X1598813Y802334D01*
X1595346D01*
X1573309Y824371D01*
Y827327D01*
X1536765Y863871D01*
G01X1731983Y800263D02*
Y799231D01*
X1731034Y798282D01*
X1721748D01*
X1721445Y798585D01*
X1679915D01*
X1676561Y801939D01*
X1669981D01*
X1666634Y798592D01*
X1653288D01*
X1652461Y799419D01*
X1641161D01*
X1639811Y798069D01*
X1633293D01*
X1632663Y798699D01*
Y799722D01*
X1632033Y800352D01*
X1630563D01*
X1629933Y799722D01*
Y798699D01*
X1629303Y798069D01*
X1625011D01*
X1623530Y799550D01*
X1620407D01*
X1619687Y798830D01*
Y797456D01*
X1618967Y796736D01*
X1617677D01*
X1616957Y797456D01*
Y798830D01*
X1616237Y799550D01*
X1612892D01*
X1610886Y797544D01*
X1604500D01*
X1603780Y798264D01*
Y799403D01*
X1603060Y800123D01*
X1601770D01*
X1601050Y799403D01*
Y798264D01*
X1600330Y797544D01*
X1597347D01*
X1571305Y823586D01*
Y826542D01*
X1537251Y860596D01*
G01X1731983Y793570D02*
X1730306Y791893D01*
X1679701D01*
X1676348Y795246D01*
X1670388D01*
X1667041Y791899D01*
X1663193D01*
X1662563Y791269D01*
Y788998D01*
X1661933Y788368D01*
X1660463D01*
X1659833Y788998D01*
Y791269D01*
X1659203Y791899D01*
X1649855D01*
X1649225Y791269D01*
Y788898D01*
X1648595Y788268D01*
X1647125D01*
X1646495Y788898D01*
Y791269D01*
X1645865Y791899D01*
X1624081D01*
X1623461Y792519D01*
X1620173D01*
X1619543Y791889D01*
Y790150D01*
X1618913Y789520D01*
X1617443D01*
X1616813Y790150D01*
Y791889D01*
X1616183Y792519D01*
X1612915D01*
X1609013Y788617D01*
X1598709D01*
X1567210Y820116D01*
Y824961D01*
X1536893Y855278D01*
G01X1715841Y780184D02*
X1713376Y777719D01*
X1700792D01*
X1698240Y775167D01*
X1669209D01*
X1665862Y771820D01*
X1653262D01*
X1652761Y771319D01*
X1649518D01*
X1648798Y772039D01*
Y773491D01*
X1648078Y774211D01*
X1646788D01*
X1646068Y773491D01*
Y772039D01*
X1645348Y771319D01*
X1641995D01*
X1639135Y774179D01*
X1633303D01*
X1632583Y774899D01*
Y775969D01*
X1631863Y776689D01*
X1630573D01*
X1629853Y775969D01*
Y774899D01*
X1629133Y774179D01*
X1624601D01*
X1623561Y775219D01*
X1608561D01*
X1607233Y773891D01*
X1603612D01*
X1602892Y774611D01*
Y776086D01*
X1602172Y776806D01*
X1600882D01*
X1600162Y776086D01*
Y774611D01*
X1599442Y773891D01*
X1597062D01*
X1558209Y812744D01*
Y821830D01*
X1532277Y847762D01*
G01X1715841Y786877D02*
X1714835Y787883D01*
X1713246D01*
X1711610Y786247D01*
X1701408D01*
X1699175Y788480D01*
X1696387D01*
X1693985Y786078D01*
X1691485D01*
X1689031Y788532D01*
X1686715D01*
X1684351Y786168D01*
X1680074D01*
X1676594Y789648D01*
X1674455D01*
X1673360Y788553D01*
X1671892D01*
X1670797Y789648D01*
X1669817D01*
X1667118Y786949D01*
X1665578D01*
X1661584Y782955D01*
X1658283D01*
X1657188Y781860D01*
X1655706D01*
X1654735Y782831D01*
X1643422D01*
X1640979Y785274D01*
X1596507D01*
X1563915Y817866D01*
Y823637D01*
X1536034Y851518D01*
G01X1731983Y786877D02*
X1730991Y785885D01*
X1729715D01*
X1726004Y786623D01*
X1724434D01*
X1718508Y784175D01*
X1717631D01*
X1716606Y785200D01*
X1714962D01*
X1713937Y784175D01*
X1702279D01*
X1696023Y781582D01*
X1685343D01*
X1684580Y781899D01*
X1683816Y782662D01*
X1682275Y783302D01*
X1679388D01*
X1678096Y782764D01*
X1676658Y781326D01*
X1675466Y780829D01*
X1674427D01*
X1673402Y781854D01*
X1671836D01*
X1670841Y780859D01*
X1666776D01*
X1662875Y779238D01*
X1661657Y778020D01*
X1660228Y777425D01*
X1658238D01*
X1657156Y778507D01*
X1655718D01*
X1654668Y777457D01*
X1642833D01*
X1636698Y779999D01*
X1626382D01*
X1623145Y778447D01*
X1610441D01*
X1606609Y780039D01*
X1597568D01*
X1561556Y816051D01*
Y823185D01*
X1534629Y850112D01*
G01X1715841Y790223D02*
X1714721Y789103D01*
X1712740D01*
X1711104Y787467D01*
X1701914D01*
X1699681Y789700D01*
X1695881D01*
X1693479Y787298D01*
X1691991D01*
X1689537Y789752D01*
X1686209D01*
X1683845Y787388D01*
X1680580D01*
X1677100Y790868D01*
X1674369D01*
X1673344Y791893D01*
X1671780D01*
X1670755Y790868D01*
X1669311D01*
X1666612Y788169D01*
X1665072D01*
X1661078Y784175D01*
X1658253D01*
X1657228Y785200D01*
X1655642D01*
X1654493Y784051D01*
X1643928D01*
X1641485Y786494D01*
X1597013D01*
X1565135Y818372D01*
Y824143D01*
X1536897Y852381D01*
G01X1731983Y783530D02*
X1730848Y784665D01*
X1729594D01*
X1725883Y785403D01*
X1724677D01*
X1718751Y782955D01*
X1717673D01*
X1716578Y781860D01*
X1715160D01*
X1714065Y782955D01*
X1702522D01*
X1696266Y780362D01*
X1685100D01*
X1683890Y780863D01*
X1683120Y781630D01*
X1682031Y782082D01*
X1679633D01*
X1678788Y781730D01*
X1677351Y780292D01*
X1675711Y779609D01*
X1674459D01*
X1673364Y778514D01*
X1671872D01*
X1670747Y779639D01*
X1667020D01*
X1663567Y778203D01*
X1662958Y777595D01*
X1662349Y776986D01*
X1660472Y776205D01*
X1658218D01*
X1657180Y775167D01*
X1655644D01*
X1654574Y776237D01*
X1642590D01*
X1636455Y778779D01*
X1626660D01*
X1623423Y777227D01*
X1610197D01*
X1606365Y778819D01*
X1597062D01*
X1560336Y815545D01*
Y822679D01*
X1533766Y849249D01*
G01X1945484Y1670313D02*
Y1375677D01*
X1946654Y1374507D01*
X1954234D01*
X1955484Y1375757D01*
Y1670313D01*
G54D21*
G01X335227Y852413D02*
Y851898D01*
X332298Y848969D01*
Y848938D01*
X309900Y826540D01*
X285607Y767893D01*
X270764Y753050D01*
X265630D01*
X251856Y739276D01*
X226536D01*
X225275Y738015D01*
Y737825D01*
X216995Y729545D01*
X111900D01*
X89005Y706650D01*
Y698325D01*
X93547Y693783D01*
Y692260D01*
G01X336627Y852413D02*
Y851145D01*
X311400Y825918D01*
X287107Y767271D01*
X271187Y751351D01*
X266271D01*
X252262Y737342D01*
X226914D01*
X217317Y727745D01*
X112646D01*
X91054Y706153D01*
Y699470D01*
X98424Y692100D01*
X102060D01*
G01X132490Y420062D02*
X127840Y415412D01*
X118770D01*
X110820Y407462D01*
Y402472D01*
X103280Y394932D01*
Y385562D01*
X138780Y350062D01*
X182000D01*
X186120Y345942D01*
X278330D01*
X317250Y307022D01*
X408720D01*
X425160Y323462D01*
X430880D01*
X440991Y333573D01*
X503141D01*
X504920Y335352D01*
X512060D01*
X513870Y333542D01*
X546530D01*
X547490Y334502D01*
X578200D01*
X592600Y348902D01*
X710548D01*
X720146Y358500D01*
X744438D01*
X764200Y378262D01*
X794590D01*
X818588Y402260D01*
X826130D01*
X833962Y410092D01*
X846292D01*
X856966Y420766D01*
X872629D01*
X884123Y409272D01*
X954510D01*
X983200Y437962D01*
X998074D01*
X1010874Y425162D01*
X1020820D01*
X1023334Y422648D01*
X1093934D01*
X1095820Y420762D01*
G01X107200Y393562D02*
X120000Y406362D01*
X148720D01*
X152720Y402362D01*
Y391742D01*
X160720Y383742D01*
X183050D01*
X185990Y380802D01*
X256395D01*
X303135Y334062D01*
X424752D01*
X429011Y338321D01*
Y340032D01*
X436241Y347262D01*
X564121D01*
X583961Y367102D01*
X711140D01*
X713738Y369700D01*
X715884D01*
X715984Y369800D01*
X738800D01*
X754462Y385462D01*
X781920D01*
X791420Y394962D01*
Y402786D01*
X808776Y420142D01*
X810088D01*
X821746Y431800D01*
X859688D01*
X861450Y433562D01*
X863190D01*
X864952Y431800D01*
X873954D01*
X874616Y431138D01*
X876536D01*
X890742Y416932D01*
X950696D01*
X978926Y445162D01*
X1026574D01*
X1039764Y431972D01*
X1243791D01*
X1268291Y456472D01*
X1330125D01*
X1344720Y441877D01*
Y423162D01*
G01X201392Y642271D02*
X198983Y639862D01*
X196500D01*
X194000Y642362D01*
X190500D01*
X178500Y630362D01*
X168000D01*
X152882Y645480D01*
X140967D01*
X138728Y643241D01*
Y632147D01*
X135331Y628750D01*
X114467D01*
X110908Y627276D01*
X106049D01*
X102269Y631056D01*
Y634466D01*
G01X110522Y675709D02*
X107521Y672708D01*
Y662393D01*
X107045Y661917D01*
G01X119457Y392071D02*
Y396862D01*
X126957Y404362D01*
X145720D01*
X148720Y401362D01*
Y391782D01*
X159220Y381282D01*
X182110D01*
X184970Y378422D01*
X255409D01*
X302369Y331462D01*
X425940D01*
X432570Y338092D01*
Y340542D01*
X437120Y345092D01*
X574069D01*
X594279Y365302D01*
X673298D01*
X679300Y359300D01*
X710800D01*
X713500Y362000D01*
Y364770D01*
X716730Y368000D01*
X739800D01*
X755462Y383662D01*
X790874D01*
X793220Y386008D01*
Y394362D01*
X794815Y395957D01*
X797027D01*
X817972Y416902D01*
Y421172D01*
X826800Y430000D01*
X860000D01*
X860900Y429100D01*
X875208D01*
X889236Y415072D01*
X952204D01*
X980494Y443362D01*
X1025828D01*
X1039598Y429592D01*
X1254480D01*
X1278980Y454092D01*
X1329139D01*
X1342340Y440891D01*
Y425232D01*
X1342220Y425112D01*
Y423162D01*
G01X125990Y529952D02*
Y543664D01*
X127948Y545622D01*
X132962D01*
X139620Y552280D01*
Y587656D01*
X162671Y610707D01*
X193925D01*
X196361Y608271D01*
X198336D01*
G01X201392D02*
X199183Y606062D01*
X196300D01*
X193260Y609102D01*
X163336D01*
X141120Y586886D01*
Y551658D01*
X133584Y544122D01*
X128570D01*
X127490Y543042D01*
Y534214D01*
X129762Y531942D01*
G01X201392Y574271D02*
Y574370D01*
X199300Y576462D01*
X197400D01*
X195900Y574962D01*
Y573584D01*
X186832Y564516D01*
X166981D01*
X134467Y532002D01*
X133160D01*
G01X133100Y528492D02*
X147479Y542871D01*
Y542892D01*
X167603Y563016D01*
X187454D01*
X198336Y573898D01*
Y574271D01*
G01X131740Y640103D02*
X133673Y638170D01*
X135414D01*
X137226Y639982D01*
Y644056D01*
X140150Y646980D01*
X153504D01*
X168622Y631862D01*
X177878D01*
X189878Y643862D01*
X194622D01*
X196213Y642271D01*
X198336D01*
G01X154220Y375682D02*
X156110Y373792D01*
X253491D01*
X318141Y309142D01*
X407400D01*
X424730Y326472D01*
X428900D01*
X438150Y335722D01*
X479150D01*
X482280Y338852D01*
X482440D01*
X483200Y339612D01*
X544330D01*
X546770Y337172D01*
X577119D01*
X590649Y350702D01*
X709802D01*
X719400Y360300D01*
X743100D01*
X762862Y380062D01*
X792850D01*
X822059Y409271D01*
Y414779D01*
X823370Y416090D01*
X828048D01*
X836558Y424600D01*
X873160D01*
X886478Y411282D01*
X953865D01*
X982345Y439762D01*
X998820D01*
X1011320Y427262D01*
X1021820D01*
X1024120Y424962D01*
X1256830D01*
X1281330Y449462D01*
X1327221D01*
X1337710Y438973D01*
Y428862D01*
X1337220Y428372D01*
Y423162D01*
G01X1339720D02*
Y426892D01*
X1340090Y427262D01*
Y439959D01*
X1328207Y451842D01*
X1280364D01*
X1255284Y426762D01*
X1031320D01*
X1029720Y428362D01*
X1024920D01*
X1011720Y441562D01*
X981599D01*
X953289Y413252D01*
X887874D01*
X874226Y426900D01*
X835728D01*
X827418Y418590D01*
X822320D01*
X799525Y395795D01*
Y389767D01*
X791620Y381862D01*
X756462D01*
X736700Y362100D01*
X718200D01*
X713200Y357100D01*
X667300D01*
X660898Y363502D01*
X600441D01*
X579791Y342852D01*
X440690D01*
X426700Y328862D01*
X423250D01*
X405560Y311172D01*
X319477D01*
X254477Y376172D01*
X158110D01*
G01X173727Y1452134D02*
X172848Y1451255D01*
X159096D01*
X148717Y1440876D01*
Y1410835D01*
X152257Y1407295D01*
X155232D01*
X155858Y1406669D01*
G01X173727Y1448734D02*
X172766Y1449695D01*
X159730D01*
X150268Y1440233D01*
Y1411895D01*
X153348Y1408815D01*
X155283D01*
X155858Y1409390D01*
G01X1078545Y435637D02*
X1076020Y438162D01*
X1036120D01*
X1026921Y447361D01*
X977237D01*
X948645Y418769D01*
X891841D01*
X877672Y432938D01*
X875362D01*
X871750Y436550D01*
X823950D01*
X809342Y421942D01*
X808030D01*
X789620Y403532D01*
Y395708D01*
X781174Y387262D01*
X755328D01*
X754427Y388163D01*
X742805D01*
X740604Y385962D01*
X726750D01*
X720550Y379762D01*
X716400D01*
X715562Y380600D01*
X705800D01*
X703200Y378000D01*
Y374000D01*
X702300Y373100D01*
X674108D01*
X669910Y368902D01*
X581991D01*
X563071Y349982D01*
X428261D01*
X415911Y337632D01*
X304869D01*
X257949Y384552D01*
X238776D01*
X223586Y399742D01*
X207980D01*
X203340Y404382D01*
X190020D01*
X176808Y391170D01*
X160090D01*
G01Y397470D02*
X174048D01*
X183880Y407302D01*
X189450D01*
X190300Y406452D01*
X204740D01*
X209340Y401852D01*
X224460D01*
X239650Y386662D01*
X258823D01*
X305613Y339872D01*
X414180D01*
X426160Y351852D01*
X562077D01*
X580927Y370702D01*
X669164D01*
X676662Y378200D01*
X699300D01*
X703600Y382500D01*
X716358D01*
X717850Y383992D01*
X719092D01*
X725702Y390602D01*
X755100D01*
X756640Y389062D01*
X780163D01*
X787720Y396619D01*
Y404232D01*
X807500Y424012D01*
X808812D01*
X823150Y438350D01*
X873750D01*
X877296Y434804D01*
X878445D01*
X892627Y420622D01*
X947819D01*
X970828Y443631D01*
Y443667D01*
X976344Y449183D01*
X1027645D01*
X1036766Y440062D01*
X1077820D01*
X1081045Y436837D01*
Y435637D01*
G01X217469Y1454725D02*
X218428Y1453766D01*
Y1450122D01*
X213727Y1445421D01*
Y1421025D01*
X210921Y1418219D01*
X191051D01*
X189167Y1416335D01*
Y1410745D01*
X192317Y1407595D01*
X193375D01*
X193941Y1407029D01*
G01X220869Y1454725D02*
X219969Y1453825D01*
Y1449502D01*
X215227Y1444760D01*
Y1420345D01*
X211560Y1416678D01*
X191768D01*
X190708Y1415618D01*
Y1411383D01*
X192953Y1409138D01*
X193329D01*
X193941Y1409750D01*
G01X459321Y1393009D02*
X460280Y1393968D01*
X461717D01*
X463129Y1392556D01*
Y1389290D01*
X461701Y1387862D01*
X452178D01*
X435074Y1370758D01*
X389297D01*
X382407Y1363868D01*
X343899D01*
X328728Y1379039D01*
X303707D01*
X302805Y1379941D01*
G01X459321Y1396409D02*
X460262Y1395468D01*
X462339D01*
X464629Y1393178D01*
Y1388668D01*
X462323Y1386362D01*
X452800D01*
X435696Y1369258D01*
X389919D01*
X383029Y1362368D01*
X343277D01*
X328106Y1377539D01*
X303803D01*
X302805Y1376541D01*
G01X445339Y1415731D02*
Y1415751D01*
X445739Y1416151D01*
X448963D01*
X453540Y1411574D01*
Y1408222D01*
X454970Y1406792D01*
X456530D01*
X458470Y1408732D01*
X463820D01*
X468622Y1403930D01*
X476391D01*
X482944Y1397377D01*
X492860D01*
X497241Y1401758D01*
X521203D01*
X531820Y1412375D01*
X648420D01*
X653694Y1417649D01*
X671262D01*
X673477Y1415434D01*
Y1409386D01*
G01X438645Y1426890D02*
Y1427946D01*
X443772Y1433073D01*
X445653D01*
X449390Y1436810D01*
X464522D01*
X469670Y1431662D01*
X512039D01*
X528326Y1415375D01*
X620175D01*
X625449Y1420649D01*
X675235D01*
X680121Y1415763D01*
Y1410159D01*
X678849Y1408887D01*
X677619D01*
G01X437299Y1436774D02*
X445095Y1444570D01*
X468601D01*
X478035Y1435136D01*
X513478D01*
X529765Y1418849D01*
X617353D01*
X638979Y1440475D01*
X708051D01*
X722597Y1434450D01*
X727122Y1429925D01*
Y1413939D01*
X722070Y1408887D01*
X715762D01*
G01X468880Y1418400D02*
X469340Y1417940D01*
Y1417480D01*
X471528Y1415292D01*
X474890D01*
X480227Y1409955D01*
X481997D01*
G01X754219Y75707D02*
X753378Y73678D01*
X748438Y68738D01*
X745900D01*
X745130Y69508D01*
G01X754219Y75707D02*
Y75939D01*
X762368Y84088D01*
G01D02*
X762606D01*
X765858Y87340D01*
G01X767028Y91490D02*
Y88510D01*
X765858Y87340D01*
G01X767028Y91490D02*
Y95943D01*
X767045Y95960D01*
G01D02*
Y99943D01*
X767061Y99959D01*
G01D02*
Y101672D01*
X769284Y103895D01*
G01D02*
Y107486D01*
X769775Y107977D01*
G01X771131Y111788D02*
Y111821D01*
X773943Y114633D01*
G01D02*
Y114692D01*
X776730Y117479D01*
G01X769775Y107977D02*
Y108514D01*
X771131Y111788D01*
G01X819114Y115223D02*
Y123044D01*
X817810Y124348D01*
X784207D01*
X782781Y122922D01*
X782771D01*
X780133Y120284D01*
X779508D01*
X776730Y117506D01*
Y117479D01*
G01X1137311Y1445191D02*
X1139423Y1447303D01*
X1159326D01*
X1161539Y1449516D01*
Y1451731D01*
X1163664Y1453856D01*
X1185930D01*
X1192101Y1460027D01*
X1301135D01*
X1311931Y1449231D01*
X1364800D01*
G01X1155187Y1590738D02*
X1154437Y1591488D01*
Y1593525D01*
X1152559Y1595403D01*
X1149900D01*
X1148022Y1593525D01*
Y1559591D01*
X1150747Y1556866D01*
Y1551520D01*
X1149528Y1550301D01*
G01X1152187Y1590738D02*
X1152937Y1591488D01*
Y1592903D01*
X1151937Y1593903D01*
X1150522D01*
X1149522Y1592903D01*
Y1560213D01*
X1152247Y1557488D01*
Y1551519D01*
X1153465Y1550301D01*
G01X1152187Y1574738D02*
X1152937Y1573988D01*
Y1563439D01*
X1156322Y1560054D01*
Y1554590D01*
X1158620Y1552292D01*
Y1551519D01*
X1157402Y1550301D01*
G01X1155187Y1574738D02*
X1154437Y1573988D01*
Y1564061D01*
X1157822Y1560676D01*
Y1555212D01*
X1160120Y1552914D01*
Y1551520D01*
X1161339Y1550301D01*
G01X1362410Y1445272D02*
X1310130D01*
X1305350Y1450052D01*
X1173310D01*
X1171342Y1448084D01*
Y1445650D01*
G01X1175454Y1445191D02*
X1177089Y1446826D01*
X1302326D01*
X1307630Y1441522D01*
X1363730D01*
X1368842Y1446634D01*
Y1449261D01*
G01X1668786Y1440290D02*
X1667861Y1441215D01*
X1666987D01*
X1663827Y1444375D01*
Y1449845D01*
X1668570Y1454588D01*
X1683700D01*
X1686122Y1457010D01*
Y1472936D01*
X1675053Y1484005D01*
X1477756D01*
X1439666Y1445915D01*
X1411067D01*
X1406462Y1441310D01*
Y1429374D01*
X1401160Y1424072D01*
Y1402171D01*
X1405299Y1398032D01*
X1414240D01*
X1415620Y1396652D01*
G01X1668786Y1443256D02*
X1667068D01*
X1665327Y1444997D01*
Y1449223D01*
X1669192Y1453088D01*
X1684322D01*
X1687622Y1456388D01*
Y1473558D01*
X1675675Y1485505D01*
X1477134D01*
X1439044Y1447415D01*
X1409921D01*
X1404962Y1442456D01*
Y1429996D01*
X1399660Y1424694D01*
Y1401549D01*
X1405017Y1396192D01*
X1410920D01*
G01X1630643Y1440290D02*
X1629193Y1440891D01*
X1616806Y1453278D01*
X1544928D01*
X1492843Y1401193D01*
X1475129D01*
X1470667Y1396731D01*
X1464743D01*
X1461826Y1393814D01*
X1449054D01*
X1441599Y1401269D01*
X1426311D01*
X1420742Y1398964D01*
X1419995Y1398217D01*
Y1397492D01*
G01X1426360Y1402789D02*
X1442201D01*
X1449676Y1395314D01*
X1461204D01*
X1464121Y1398231D01*
X1469881D01*
X1474476Y1402826D01*
X1492354D01*
X1544306Y1454778D01*
X1617428D01*
X1629116Y1443090D01*
X1630643D01*
G01X1634643Y1442982D02*
Y1444239D01*
X1628967Y1449915D01*
X1626597D01*
X1618727Y1457785D01*
X1536087D01*
X1508627Y1430325D01*
X1450531D01*
X1449254Y1429048D01*
X1439946D01*
X1435950Y1433044D01*
X1432270D01*
X1429150Y1429924D01*
Y1422028D01*
X1422853Y1415731D01*
X1421480D01*
G01X1487958Y236062D02*
Y179320D01*
X1462000Y153362D01*
G01X1687800Y507462D02*
X1658388D01*
X1634830Y531020D01*
Y560382D01*
X1640510Y566062D01*
X1678178D01*
X1687820Y575704D01*
Y605080D01*
X1673830Y619070D01*
Y635122D01*
X1665500Y643452D01*
X1658466D01*
X1655637Y646281D01*
Y646311D01*
G01X1707200Y498962D02*
Y500800D01*
X1705561Y502439D01*
X1704694Y504533D01*
X1702376Y506851D01*
X1701011D01*
X1698900Y508962D01*
X1659010D01*
X1636330Y531642D01*
Y559760D01*
X1641132Y564562D01*
X1678800D01*
X1689320Y575082D01*
Y605702D01*
X1675330Y619692D01*
Y635744D01*
X1666122Y644952D01*
X1660620D01*
X1657230Y648342D01*
X1654612D01*
X1652581Y646311D01*
G01X1678860Y556752D02*
X1686484D01*
X1710871Y581139D01*
Y615133D01*
X1729160Y633422D01*
Y661152D01*
X1718500Y671812D01*
X1716132D01*
X1702996Y684948D01*
Y687316D01*
X1677360Y712952D01*
X1660650D01*
X1657230Y716372D01*
X1654642D01*
X1652581Y714311D01*
G01X1675480Y557233D02*
X1677309Y559062D01*
X1686600D01*
X1709320Y581782D01*
Y615704D01*
X1727660Y634044D01*
Y660530D01*
X1717878Y670312D01*
X1715510D01*
X1701496Y684326D01*
Y686694D01*
X1676738Y711452D01*
X1658496D01*
X1655637Y714311D01*
G54D12*
X158318Y1384286D03*
X155718D03*
X158318Y1387393D03*
X155718D03*
X160201Y1399732D03*
X157731D03*
Y1394132D03*
X160201D03*
X160918Y1384286D03*
X163518D03*
Y1387393D03*
X160918D03*
X169318Y1384286D03*
X166118D03*
X172262Y1384302D03*
Y1387409D03*
X163718Y1390500D03*
X161118D03*
X162631Y1399732D03*
Y1394132D03*
X172231Y1390532D03*
X208312Y576125D03*
Y581085D03*
Y578605D03*
Y615085D03*
Y610125D03*
Y612605D03*
Y649085D03*
Y644125D03*
Y646605D03*
X207856Y686443D03*
X203043Y686483D03*
X207824Y681560D03*
X203044Y684036D03*
X207834Y684006D03*
X203237Y681549D03*
X201661Y1384286D03*
X193861D03*
X196461D03*
X199061D03*
X201661Y1387393D03*
X193861D03*
X196461D03*
X199061D03*
X204261Y1384286D03*
X207461D03*
X201861Y1390500D03*
X199261D03*
X195874Y1399732D03*
X198344D03*
X200774D03*
X195874Y1394132D03*
X198344D03*
X200774D03*
X213912Y576125D03*
X220668Y574131D03*
X223775D03*
X213912Y578605D03*
Y581085D03*
X217556Y590575D03*
X217561Y582131D03*
Y579531D03*
X223775Y587731D03*
X223759Y590675D03*
X220652D03*
X223775Y584531D03*
X220668Y576731D03*
Y579331D03*
X223775Y581931D03*
Y579331D03*
Y576731D03*
X220668Y581931D03*
Y608131D03*
X223775D03*
X213912Y612605D03*
Y615085D03*
Y610125D03*
X217561Y616131D03*
Y613531D03*
X217556Y624575D03*
X223759Y624675D03*
X220652D03*
X223775Y618531D03*
X220668Y610731D03*
Y613331D03*
X223775Y615931D03*
Y613331D03*
Y610731D03*
X220668Y615931D03*
X223775Y621731D03*
X213912Y646605D03*
Y649085D03*
Y644125D03*
X217561Y650131D03*
Y647531D03*
X223775Y655731D03*
Y652531D03*
X220668Y644731D03*
Y647331D03*
Y642131D03*
X223775Y649931D03*
Y647331D03*
Y644731D03*
Y642131D03*
X220668Y649931D03*
X217556Y658575D03*
X223759Y658675D03*
X220652D03*
X210405Y1384302D03*
Y1387409D03*
X210374Y1390532D03*
X312301Y1345539D03*
Y1342432D03*
X309701Y1345539D03*
Y1342432D03*
X316655Y1352295D03*
X314175D03*
X311695D03*
X320101Y1342432D03*
X317701Y1348646D03*
X315101D03*
X314901Y1345539D03*
X317501D03*
X314901Y1342432D03*
X317501D03*
X316655Y1357895D03*
X311695D03*
X314175D03*
X326145Y1348651D03*
X326245Y1345555D03*
Y1342448D03*
X323301Y1342432D03*
X344429Y1322741D03*
X347029D03*
X341829D03*
X347029Y1319634D03*
X344429D03*
X341829D03*
X349629Y1322741D03*
Y1319634D03*
X352229D03*
X355429D03*
X346303Y1335097D03*
X343823D03*
Y1329497D03*
X346303D03*
X347229Y1325848D03*
X348783Y1329497D03*
X349829Y1325848D03*
X348783Y1335097D03*
X358373Y1322757D03*
Y1319650D03*
X358273Y1325853D03*
X373957Y1306208D03*
X381757D03*
X379157D03*
X376557D03*
X384357D03*
X387557D03*
X375951Y1321671D03*
X380911Y1316071D03*
X378431D03*
Y1321671D03*
X380911D03*
X373957Y1309315D03*
X381957Y1312422D03*
X381757Y1309315D03*
X379357Y1312422D03*
X379157Y1309315D03*
X376557D03*
X375951Y1316071D03*
X390501Y1306224D03*
X390401Y1312427D03*
X390501Y1309331D03*
X416485Y1306208D03*
X419685D03*
X413885D03*
X406085D03*
X411285D03*
X408685D03*
X414085Y1312422D03*
X413885Y1309315D03*
X411485Y1312422D03*
X408685Y1309315D03*
X406085D03*
X411285D03*
X413039Y1316071D03*
X408079D03*
X410559D03*
X413039Y1321671D03*
X408079D03*
X410559D03*
X422629Y1306224D03*
X422529Y1312427D03*
X422629Y1309331D03*
X448613Y1306208D03*
X446013D03*
X443413D03*
X440813D03*
X438213D03*
X451813D03*
X443613Y1312422D03*
X443413Y1309315D03*
X440813D03*
X438213D03*
X446213Y1312422D03*
X446013Y1309315D03*
X440207Y1316071D03*
X445167D03*
X442687D03*
X440207Y1321671D03*
X445167D03*
X442687D03*
X454757Y1306224D03*
X454657Y1312427D03*
X454757Y1309331D03*
X480741Y1306208D03*
X478141D03*
X475541D03*
X472941D03*
X470341D03*
X483941D03*
X472941Y1309315D03*
X478141D03*
X470341D03*
X478341Y1312422D03*
X475741D03*
X475541Y1309315D03*
X472335Y1316071D03*
X477295D03*
X474815D03*
X472335Y1321671D03*
X477295D03*
X474815D03*
X486885Y1306224D03*
X486785Y1312427D03*
X486885Y1309331D03*
X516069Y1319634D03*
X502469D03*
Y1322741D03*
X512869Y1319634D03*
X510269D03*
X507669D03*
X505069D03*
X507669Y1322741D03*
X505069D03*
X510269D03*
X504463Y1329497D03*
Y1335097D03*
X509423Y1329497D03*
X506943D03*
X509423Y1335097D03*
X506943D03*
X510469Y1325848D03*
X507869D03*
X519013Y1319650D03*
Y1322757D03*
X518913Y1325853D03*
X534597Y1345539D03*
Y1342432D03*
X548197D03*
X539997Y1348646D03*
X542397Y1345539D03*
X542597Y1348646D03*
X537197Y1342432D03*
X539797D03*
X542397D03*
X544997D03*
X537197Y1345539D03*
X539797D03*
X539071Y1352295D03*
X536591D03*
X541551D03*
Y1357895D03*
X536591D03*
X539071D03*
X551141Y1345555D03*
X551041Y1348651D03*
X551141Y1342448D03*
X677137Y1384311D03*
X674537D03*
X671937D03*
X669337D03*
X677137Y1387418D03*
X674537D03*
X671937D03*
X669337D03*
X679737Y1384311D03*
X677337Y1390525D03*
X674737D03*
X676250Y1399757D03*
X673820D03*
X671350D03*
X676250Y1394157D03*
X673820D03*
X671350D03*
X682937Y1384311D03*
X685881Y1384327D03*
Y1387434D03*
X685850Y1390557D03*
X707480Y1384311D03*
X710080D03*
X707480Y1387418D03*
X710080D03*
X712680Y1384311D03*
Y1387418D03*
X709493Y1399757D03*
Y1394157D03*
X712880Y1390525D03*
X711963Y1399757D03*
Y1394157D03*
X715280Y1384311D03*
X717880D03*
X715280Y1387418D03*
X721080Y1384311D03*
X724024Y1384327D03*
Y1387434D03*
X715480Y1390525D03*
X723993Y1390557D03*
X714393Y1399757D03*
Y1394157D03*
X924623Y492097D03*
X929654Y492103D03*
X1131629Y1420615D03*
X1129029D03*
X1134229D03*
X1131629Y1423722D03*
X1129029D03*
X1134229D03*
X1131042Y1436061D03*
X1135942D03*
X1133512D03*
X1131042Y1430461D03*
X1135942D03*
X1133512D03*
X1134429Y1426829D03*
X1142629Y1420615D03*
X1145573Y1420631D03*
X1139429Y1420615D03*
X1136829D03*
X1145573Y1423738D03*
X1136829Y1423722D03*
X1145542Y1426861D03*
X1137029Y1426829D03*
X1167172Y1420615D03*
Y1423722D03*
X1183716Y1420631D03*
X1180772Y1420615D03*
X1174972D03*
X1177572D03*
X1172372D03*
X1169772D03*
X1183716Y1423738D03*
X1174972Y1423722D03*
X1172372D03*
X1169772D03*
X1174085Y1436061D03*
Y1430461D03*
X1171655Y1436061D03*
X1169185D03*
X1171655Y1430461D03*
X1169185D03*
X1183685Y1426861D03*
X1175172Y1426829D03*
X1172572D03*
X1197700Y1432672D03*
X1198010Y1441902D03*
X1198880Y1457162D03*
X1276745Y125850D03*
X1275807Y132922D03*
X1284930Y124922D03*
X1291205Y1345875D03*
X1286005Y1342768D03*
Y1345875D03*
X1296405Y1342768D03*
X1293805D03*
X1288605D03*
X1291205D03*
X1288605Y1345875D03*
X1293805D03*
X1291405Y1348982D03*
X1294005D03*
X1292916Y1352531D03*
X1290436D03*
X1287956D03*
X1292916Y1358131D03*
X1290436D03*
X1287956D03*
X1299605Y1342768D03*
X1302549Y1345891D03*
X1302520Y1348762D03*
X1302549Y1342784D03*
X1317970Y1322741D03*
Y1319634D03*
X1325770Y1322741D03*
X1323170D03*
X1331570Y1319634D03*
X1323170D03*
X1325770D03*
X1328370D03*
X1320570Y1322741D03*
Y1319634D03*
X1322444Y1329497D03*
X1324924D03*
X1319964D03*
X1322444Y1335097D03*
X1324924D03*
X1319964D03*
X1323370Y1325848D03*
X1325970D03*
X1334514Y1322757D03*
Y1319650D03*
X1334414Y1325853D03*
X1350098Y1306208D03*
X1352698D03*
X1355298D03*
X1360498D03*
X1363698D03*
X1357898D03*
X1352698Y1309315D03*
X1350098D03*
X1355498Y1312422D03*
X1358098D03*
X1355298Y1309315D03*
X1357898D03*
X1352092Y1316071D03*
Y1321671D03*
X1357052Y1316071D03*
X1354572D03*
X1357052Y1321671D03*
X1354572D03*
X1366642Y1306224D03*
X1366542Y1312427D03*
X1366642Y1309331D03*
X1382226Y1306208D03*
X1384826D03*
X1387426D03*
X1390026D03*
X1392626D03*
X1395826D03*
X1386700Y1321671D03*
X1389180D03*
X1382226Y1309315D03*
X1384826D03*
X1390226Y1312422D03*
X1387626D03*
X1390026Y1309315D03*
X1387426D03*
X1384220Y1316071D03*
Y1321671D03*
X1389180Y1316071D03*
X1386700D03*
X1398770Y1306224D03*
X1398670Y1312427D03*
X1398770Y1309331D03*
X1414354Y1306208D03*
X1416954D03*
X1419554D03*
X1422154D03*
X1424754D03*
X1427954D03*
X1418828Y1316071D03*
X1416348D03*
X1418828Y1321671D03*
X1416348D03*
X1421308Y1316071D03*
Y1321671D03*
X1414354Y1309315D03*
X1416954D03*
X1419554D03*
X1422354Y1312422D03*
X1419754D03*
X1422154Y1309315D03*
X1430898Y1306224D03*
X1430798Y1312427D03*
X1430898Y1309331D03*
X1446482Y1306208D03*
X1449082D03*
X1451682D03*
X1456882D03*
X1460082D03*
X1454282D03*
X1450956Y1321671D03*
X1448476D03*
X1453436Y1316071D03*
Y1321671D03*
X1446482Y1309315D03*
X1451882Y1312422D03*
X1449082Y1309315D03*
X1451682D03*
X1454482Y1312422D03*
X1454282Y1309315D03*
X1450956Y1316071D03*
X1448476D03*
X1463026Y1306224D03*
X1462926Y1312427D03*
X1463026Y1309331D03*
X1486410Y1322741D03*
X1483810D03*
X1486410Y1319634D03*
X1483810D03*
X1481210Y1322741D03*
Y1319634D03*
X1492210D03*
X1489010D03*
X1478610Y1322741D03*
Y1319634D03*
X1484010Y1325848D03*
X1486610D03*
X1485564Y1335097D03*
X1483084D03*
X1485564Y1329497D03*
X1483084D03*
X1480604Y1335097D03*
Y1329497D03*
X1495154Y1322757D03*
Y1319650D03*
X1495054Y1325853D03*
X1510738Y1345539D03*
Y1342432D03*
X1518538Y1345539D03*
Y1342432D03*
X1515938Y1345539D03*
Y1342432D03*
X1513338Y1345539D03*
Y1342432D03*
X1521138D03*
X1524338D03*
X1518738Y1348646D03*
X1516138D03*
X1515212Y1352295D03*
X1512732D03*
X1517692D03*
X1515212Y1357895D03*
X1512732D03*
X1517692D03*
X1527282Y1345555D03*
Y1342448D03*
X1527182Y1348651D03*
X1636412Y638451D03*
X1636417Y630007D03*
X1640061Y639497D03*
X1636412Y641051D03*
X1630198Y638651D03*
Y636051D03*
Y641251D03*
X1633305Y638651D03*
Y641251D03*
X1630198Y632851D03*
X1630214Y629907D03*
X1633321D03*
X1640061Y644457D03*
Y641977D03*
X1630198Y643851D03*
X1633305Y646451D03*
Y643851D03*
X1630198Y646451D03*
X1636412Y672451D03*
X1636417Y664007D03*
X1640061Y673497D03*
X1630198Y672651D03*
Y670051D03*
X1633305Y672651D03*
X1630198Y666851D03*
X1630214Y663907D03*
X1633321D03*
X1640061Y678457D03*
Y675977D03*
X1636412Y675051D03*
X1630198Y677851D03*
Y675251D03*
X1633305Y680451D03*
Y675251D03*
Y677851D03*
X1630198Y680451D03*
X1636417Y698007D03*
X1636412Y706451D03*
X1630214Y697907D03*
X1633321D03*
X1630198Y704051D03*
Y706651D03*
X1633305D03*
X1630198Y700851D03*
X1640061Y707497D03*
Y712457D03*
Y709977D03*
X1636412Y709051D03*
X1633305Y711851D03*
Y709251D03*
X1630198D03*
Y711851D03*
X1633305Y714451D03*
X1630198D03*
X1633103Y1417907D03*
X1630503D03*
X1635703D03*
X1633103Y1421014D03*
X1630503D03*
X1635703D03*
X1638303Y1417907D03*
Y1421014D03*
X1635903Y1424121D03*
X1638503D03*
X1632516Y1427753D03*
Y1433353D03*
X1634986Y1427753D03*
Y1433353D03*
X1637416Y1427753D03*
Y1433353D03*
X1649149Y607022D03*
X1653929Y604546D03*
X1649139Y604576D03*
X1653736Y607033D03*
X1649117Y602139D03*
X1653930Y602099D03*
X1645661Y639497D03*
Y644457D03*
Y641977D03*
Y673497D03*
Y678457D03*
Y675977D03*
Y707497D03*
Y709977D03*
Y712457D03*
X1644103Y1417907D03*
X1647047Y1417923D03*
Y1421030D03*
X1640903Y1417907D03*
X1647016Y1424153D03*
X1668646Y1417907D03*
Y1421014D03*
X1671246Y1417907D03*
Y1421014D03*
X1670659Y1427753D03*
X1673129D03*
X1670659Y1433353D03*
X1673129D03*
X1685190Y1417923D03*
X1676446Y1417907D03*
X1679046D03*
X1682246D03*
X1676446Y1421014D03*
X1685190Y1421030D03*
X1673846Y1417907D03*
Y1421014D03*
X1676646Y1424121D03*
X1685159Y1424153D03*
X1675559Y1427753D03*
Y1433353D03*
X1674046Y1424121D03*
X1699457Y1439185D03*
Y1447805D03*
X1763830Y1490782D03*
Y1487782D03*
G54D31*
G01X1921395Y582868D02*
X1925162D01*
X1925560Y582470D01*
Y-8842D01*
X1925070Y-9332D01*
X1921395D01*
G01X1931395Y582868D02*
X1927616D01*
X1927230Y582482D01*
Y-8842D01*
X1927720Y-9332D01*
X1931395D01*
G54D22*
G01X470111Y1548269D02*
X473742Y1551900D01*
X488700D01*
X493401Y1556601D01*
X657051D01*
X659670Y1553982D01*
X663410D01*
G01X979373Y1342724D02*
X974257Y1347840D01*
X914082D01*
X880713Y1381209D01*
X832218D01*
X809866Y1403561D01*
X775375D01*
G01X1271990Y1358079D02*
X1269937Y1360132D01*
X1240320D01*
X1196900Y1403552D01*
X1119812D01*
X1112010Y1411354D01*
Y1431689D01*
X1115853Y1435532D01*
G54D13*
X238780Y1681456D03*
X230906Y1677519D03*
Y1682244D03*
X238780Y1686180D03*
X254528Y1681456D03*
X246654Y1677519D03*
Y1682244D03*
X254528Y1686180D03*
X270276Y1681456D03*
X262402Y1677519D03*
Y1682244D03*
X270276Y1686180D03*
X286024Y1681456D03*
X278150Y1677519D03*
Y1682244D03*
X286024Y1686180D03*
X297835Y1677519D03*
Y1682244D03*
X305709Y1681456D03*
Y1686180D03*
X313583Y1677519D03*
Y1682244D03*
X321457Y1681456D03*
Y1686180D03*
X329331Y1677519D03*
Y1682244D03*
X337205Y1681456D03*
Y1686180D03*
X345079Y1677519D03*
Y1682244D03*
X352953Y1681456D03*
Y1686180D03*
X495079Y1691692D03*
Y1696417D03*
X510827Y1691692D03*
X502953Y1695629D03*
X510827Y1696417D03*
X502953Y1700354D03*
X526575Y1691692D03*
X518701Y1695629D03*
X526575Y1696417D03*
X534449Y1695629D03*
X518701Y1700354D03*
X534449D03*
X542323Y1691692D03*
Y1696417D03*
X550197Y1695629D03*
Y1700354D03*
X562008Y1691692D03*
Y1696417D03*
X577756Y1691692D03*
X569882Y1695629D03*
X577756Y1696417D03*
X569882Y1700354D03*
X593504Y1691692D03*
X585630Y1695629D03*
X593504Y1696417D03*
X585630Y1700354D03*
X609252Y1691692D03*
X601378Y1695629D03*
X609252Y1696417D03*
X601378Y1700354D03*
X617126Y1695629D03*
Y1700354D03*
X1238780Y1677519D03*
Y1682244D03*
X1246654Y1681456D03*
Y1686180D03*
X1254528Y1677519D03*
Y1682244D03*
X1262402Y1681456D03*
Y1686180D03*
X1270276Y1677519D03*
Y1682244D03*
X1278150Y1681456D03*
Y1686180D03*
X1286024Y1677519D03*
Y1682244D03*
X1293898Y1681456D03*
Y1686180D03*
X1305709Y1677519D03*
Y1682244D03*
X1313583Y1681456D03*
Y1686180D03*
X1321457Y1677519D03*
Y1682244D03*
X1329331Y1681456D03*
Y1686180D03*
X1337205Y1677519D03*
Y1682244D03*
X1345079Y1681456D03*
Y1686180D03*
X1352953Y1677519D03*
Y1682244D03*
X1360827Y1681456D03*
Y1686180D03*
X1502953Y1691692D03*
Y1696417D03*
X1510827Y1695629D03*
Y1700354D03*
X1518701Y1691692D03*
Y1696417D03*
X1526575Y1695629D03*
Y1700354D03*
X1534449Y1691692D03*
Y1696417D03*
X1542323Y1695629D03*
Y1700354D03*
X1550197Y1691692D03*
Y1696417D03*
X1558071Y1695629D03*
Y1700354D03*
X1569882Y1691692D03*
Y1696417D03*
X1585630Y1691692D03*
X1577756Y1695629D03*
X1585630Y1696417D03*
X1577756Y1700354D03*
X1601378Y1691692D03*
X1593504Y1695629D03*
X1601378Y1696417D03*
X1593504Y1700354D03*
X1617126Y1691692D03*
X1609252Y1695629D03*
X1617126Y1696417D03*
X1609252Y1700354D03*
X1625000Y1695629D03*
Y1700354D03*
G54D32*
G01X555175Y71436D02*
X556335Y72596D01*
Y81287D01*
X553650Y83972D01*
X546320D01*
X539644Y77296D01*
X532415D01*
X531845Y76726D01*
X530395D01*
X529825Y77296D01*
X526745D01*
X526175Y76726D01*
X524725D01*
X524155Y77296D01*
X522145D01*
X521575Y76726D01*
X520125D01*
X519555Y77296D01*
X515435D01*
X512307Y74168D01*
X499955Y69052D01*
X453902D01*
X430872Y92082D01*
X406532D01*
X389546Y109068D01*
X364887Y119282D01*
X359732D01*
X345332Y133682D01*
X318330D01*
X315254Y136758D01*
X214035D01*
X153476Y161842D01*
X63495D01*
X49149Y176188D01*
Y180618D01*
X43214Y186553D01*
X16141D01*
X7640Y195054D01*
Y290931D01*
X35260Y357610D01*
X45650Y368000D01*
X56292D01*
X58080Y369788D01*
Y373412D01*
X70740Y386072D01*
Y402041D01*
X70170Y402611D01*
Y404061D01*
X70740Y404631D01*
Y406081D01*
X70170Y406651D01*
Y408101D01*
X70740Y408671D01*
Y410121D01*
X67174Y413687D01*
X66844Y413688D01*
X63792D01*
X62812Y412708D01*
G01X62813Y415750D02*
X63795Y414768D01*
X66845D01*
X67622Y414767D01*
X71820Y410569D01*
Y385624D01*
X59160Y372964D01*
Y369340D01*
X56740Y366920D01*
X46098D01*
X36176Y356998D01*
X8720Y290716D01*
Y285015D01*
X9210Y284525D01*
Y282795D01*
X8720Y282305D01*
Y195502D01*
X16589Y187633D01*
X43662D01*
X50229Y181066D01*
Y176636D01*
X63943Y162922D01*
X153691D01*
X214250Y137838D01*
X315702D01*
X318778Y134762D01*
X345780D01*
X360180Y120362D01*
X365102D01*
X390158Y109984D01*
X406980Y93162D01*
X431320D01*
X454350Y70132D01*
X499740D01*
X511695Y75084D01*
X514987Y78376D01*
X539196D01*
X545872Y85052D01*
X554098D01*
X557415Y81735D01*
Y72596D01*
X558575Y71436D01*
G01X1403693Y1152959D02*
Y1154081D01*
X1403692Y1154082D01*
Y1177620D01*
X1361597Y1219715D01*
X1344611Y1226751D01*
X1274953Y1296409D01*
X1270166Y1307966D01*
X1225624Y1352508D01*
X1129845D01*
X1125046Y1354496D01*
X1105208Y1374334D01*
Y1467554D01*
X1061394Y1511376D01*
X636743Y1547238D01*
X499466D01*
X363046Y1527001D01*
X274190Y1490199D01*
X246361Y1462370D01*
X222207Y1404054D01*
Y1326209D01*
X219931Y1320745D01*
X213068Y1312907D01*
X199761Y1299600D01*
X197208Y1293436D01*
Y1278443D01*
X197209Y1261381D01*
X197962Y1257110D01*
X199764Y1254543D01*
X204529Y1251207D01*
X205715Y1250998D01*
X207331Y1250042D01*
X207610Y1249695D01*
X207866Y1249077D01*
Y1246195D01*
X209264Y1242819D01*
X212544Y1239538D01*
X219602Y1235765D01*
X229319Y1229272D01*
X231590Y1228332D01*
X234965Y1227659D01*
X241912Y1223017D01*
X245718Y1221440D01*
X258597Y1212831D01*
X261210Y1211748D01*
X274694Y1202736D01*
X315744Y1161688D01*
X320764Y1149569D01*
X328781Y1141552D01*
X328785D01*
X329901Y1140436D01*
G01X1402613Y1152959D02*
Y1153633D01*
X1402612Y1153634D01*
Y1156517D01*
X1402042Y1157087D01*
Y1158537D01*
X1402612Y1159107D01*
Y1165157D01*
X1402042Y1165727D01*
Y1167177D01*
X1402612Y1167747D01*
Y1172717D01*
X1402042Y1173287D01*
Y1174737D01*
X1402612Y1175307D01*
Y1177172D01*
X1399557Y1180227D01*
X1398751D01*
X1397725Y1181253D01*
Y1182059D01*
X1367149Y1212635D01*
X1366470D01*
X1365253Y1213852D01*
Y1214531D01*
X1360985Y1218799D01*
X1343999Y1225835D01*
X1274037Y1295797D01*
X1269250Y1307354D01*
X1225176Y1351428D01*
X1129630D01*
X1124434Y1353580D01*
X1104128Y1373886D01*
Y1467106D01*
X1060909Y1510332D01*
X636697Y1546158D01*
X499546D01*
X363336Y1525952D01*
X328580Y1511555D01*
X328577Y1511557D01*
X328268Y1510811D01*
X326928Y1510256D01*
X326183Y1510564D01*
X324742Y1509967D01*
X324434Y1509222D01*
X323093Y1508667D01*
X322349Y1508975D01*
X282268Y1492375D01*
X281960Y1491630D01*
X280619Y1491075D01*
X279874Y1491383D01*
X278535Y1490829D01*
X278227Y1490084D01*
X276886Y1489529D01*
X276141Y1489837D01*
X274802Y1489283D01*
X247277Y1461758D01*
X235283Y1432801D01*
Y1432800D01*
X235281Y1432798D01*
X235282D01*
X223287Y1403839D01*
Y1325993D01*
X220861Y1320166D01*
X213858Y1312168D01*
X200677Y1298988D01*
X199484Y1296106D01*
X199483D01*
X199185Y1295386D01*
X199184Y1295385D01*
X198288Y1293221D01*
Y1278444D01*
X198289Y1261476D01*
X198984Y1257534D01*
X200539Y1255319D01*
X204953Y1252230D01*
X205901Y1252062D01*
Y1252063D01*
X206096Y1252028D01*
X208107Y1250840D01*
X208137Y1250837D01*
X208488Y1250400D01*
X208864Y1249490D01*
Y1249491D01*
X208946Y1249292D01*
Y1246410D01*
X210180Y1243431D01*
X213195Y1240416D01*
X220158Y1236693D01*
X229831Y1230230D01*
X231905Y1229371D01*
X235387Y1228677D01*
X242424Y1223974D01*
X246230Y1222397D01*
X259109Y1213788D01*
X261722Y1212705D01*
X275383Y1203576D01*
X316660Y1162300D01*
X321680Y1150181D01*
X329789Y1142072D01*
X329793D01*
X330665Y1141200D01*
G01X1392323Y1160589D02*
Y1160632D01*
X1392322Y1160633D01*
Y1177497D01*
X1391349Y1179845D01*
X1390604Y1180154D01*
X1390049Y1181494D01*
X1390357Y1182239D01*
X1389170Y1185105D01*
X1358001Y1216502D01*
X1342133Y1223075D01*
X1271205Y1294003D01*
X1266429Y1305533D01*
X1224122Y1347840D01*
X1129472D01*
X1121980Y1350943D01*
X1100868Y1372055D01*
Y1464792D01*
X1058466Y1507194D01*
X1058464D01*
X637006Y1542785D01*
X499080D01*
X366569Y1523128D01*
X289452Y1491190D01*
X289192Y1490562D01*
X287602Y1489904D01*
X286975Y1490164D01*
X275945Y1485596D01*
X249898Y1459549D01*
X226547Y1403174D01*
Y1325069D01*
X223737Y1318293D01*
X219851Y1313727D01*
X219850Y1313726D01*
X217962Y1311508D01*
X217961Y1311507D01*
X216044Y1309255D01*
X203300Y1296512D01*
Y1295062D01*
X203870Y1294492D01*
Y1293042D01*
X203300Y1292472D01*
Y1281401D01*
X203870Y1280831D01*
Y1279381D01*
X203300Y1278811D01*
Y1277361D01*
X205614Y1275047D01*
X207563Y1274240D01*
X209971Y1271833D01*
X211833Y1268354D01*
X212274Y1266129D01*
Y1248350D01*
X212745Y1247213D01*
X213436Y1246522D01*
X220299Y1243679D01*
X231256Y1236357D01*
X235042Y1232571D01*
X251052Y1225939D01*
X254073Y1222918D01*
X267369Y1217411D01*
X303019Y1181761D01*
X303698D01*
X304915Y1180544D01*
Y1179865D01*
X306131Y1178649D01*
X306810D01*
X308027Y1177432D01*
Y1176753D01*
X318619Y1166161D01*
X324493Y1151980D01*
X332724Y1143749D01*
G01X1393403Y1160589D02*
Y1161080D01*
X1393402Y1161081D01*
Y1177712D01*
X1390087Y1185715D01*
X1358615Y1217417D01*
X1342745Y1223991D01*
X1272121Y1294615D01*
X1267345Y1306145D01*
X1224570Y1348920D01*
X1129687D01*
X1122592Y1351859D01*
X1101948Y1372503D01*
Y1465240D01*
X1058951Y1508237D01*
X1058555Y1508270D01*
X1058554Y1508271D01*
X637052Y1543865D01*
X499000D01*
X366279Y1524177D01*
X275333Y1486512D01*
X248982Y1460161D01*
X225467Y1403389D01*
Y1325285D01*
X222804Y1318864D01*
X215249Y1309989D01*
X202220Y1296960D01*
Y1276913D01*
X205002Y1274131D01*
X206951Y1273324D01*
X209094Y1271182D01*
X210804Y1267986D01*
X211194Y1266022D01*
Y1248134D01*
X211747Y1246800D01*
X211746D01*
X211829Y1246601D01*
X212824Y1245606D01*
X219787Y1242722D01*
X230567Y1235517D01*
X234430Y1231655D01*
X250440Y1225023D01*
X253461Y1222002D01*
X266757Y1216495D01*
X317703Y1165549D01*
X323577Y1151368D01*
X331960Y1142985D01*
G01X1390066Y1162099D02*
Y1162590D01*
X1390065Y1162591D01*
Y1175191D01*
X1385876Y1185304D01*
X1356372Y1214808D01*
X1340891Y1221219D01*
X1269347Y1292763D01*
X1264570Y1304298D01*
X1223208Y1345660D01*
X1128883D01*
X1124867Y1347324D01*
Y1347325D01*
X1120853Y1348987D01*
X1098688Y1371152D01*
Y1463755D01*
X1057450Y1504993D01*
X635731Y1540605D01*
X499296D01*
X369297Y1521320D01*
X276298Y1482799D01*
X251735Y1458236D01*
X228747Y1402739D01*
Y1324591D01*
X225511Y1316780D01*
X221685Y1312210D01*
X221684Y1312209D01*
X217857Y1307638D01*
X217856Y1307639D01*
X217852Y1307634D01*
X217849Y1307630D01*
X217788Y1307557D01*
X206440Y1296208D01*
Y1278804D01*
X214312Y1270932D01*
X217814Y1253331D01*
X219468Y1250235D01*
X220422Y1249281D01*
X225752Y1244906D01*
X238076Y1236672D01*
X242425Y1232322D01*
X266096Y1222517D01*
X320119Y1168494D01*
X321680Y1164728D01*
X323240Y1160962D01*
Y1160961D01*
X326524Y1153033D01*
X332911Y1146646D01*
G01X1388986Y1162099D02*
Y1162142D01*
X1388985Y1162143D01*
Y1174976D01*
X1387347Y1178930D01*
X1386602Y1179238D01*
X1386047Y1180578D01*
X1386355Y1181323D01*
X1384960Y1184692D01*
X1355760Y1213892D01*
X1340279Y1220303D01*
X1268431Y1292151D01*
X1263654Y1303686D01*
X1222760Y1344580D01*
X1128668D01*
X1120241Y1348071D01*
X1097608Y1370704D01*
Y1463307D01*
X1056966Y1503949D01*
X1056964D01*
X635685Y1539525D01*
X499376D01*
X369587Y1520271D01*
X298681Y1490901D01*
X298373Y1490157D01*
X297032Y1489602D01*
X296288Y1489910D01*
X287974Y1486464D01*
X287971Y1486466D01*
X287662Y1485720D01*
X286322Y1485165D01*
X285576Y1485473D01*
X283436Y1484586D01*
X283128Y1483841D01*
X281787Y1483286D01*
X281042Y1483594D01*
X276910Y1481883D01*
X252651Y1457624D01*
X229827Y1402524D01*
Y1324376D01*
X226446Y1316213D01*
X218685Y1306944D01*
X218677Y1306934D01*
X218586Y1306826D01*
X213053Y1301293D01*
X213052D01*
X207520Y1295760D01*
Y1279252D01*
X215308Y1271464D01*
X215731Y1269336D01*
X216402Y1268888D01*
X216685Y1267465D01*
X216237Y1266794D01*
X216586Y1265037D01*
X217257Y1264589D01*
X217540Y1263166D01*
X217093Y1262495D01*
X218842Y1253699D01*
X220346Y1250886D01*
X221149Y1250083D01*
X226397Y1245775D01*
X238765Y1237511D01*
X243037Y1233238D01*
X266708Y1223433D01*
X300193Y1189948D01*
X300999D01*
X302026Y1188921D01*
Y1188115D01*
X303478Y1186663D01*
X304284D01*
X305311Y1185636D01*
Y1184830D01*
X321035Y1169106D01*
X327440Y1153645D01*
X333675Y1147410D01*
G01X230906Y1682244D02*
Y1681003D01*
X230325Y1680422D01*
X228347D01*
X226025Y1678098D01*
X195357Y1618524D01*
Y1615452D01*
X194197Y1614292D01*
G01X230906Y1677519D02*
Y1678419D01*
X229983Y1679342D01*
X228795D01*
X226909Y1677453D01*
X212852Y1650146D01*
X213064Y1649485D01*
X212277Y1647955D01*
X211616Y1647744D01*
X210829Y1646215D01*
X211041Y1645555D01*
X210254Y1644025D01*
X209593Y1643814D01*
X208806Y1642285D01*
X209018Y1641625D01*
X208231Y1640095D01*
X207570Y1639884D01*
X206783Y1638355D01*
X206994Y1637695D01*
X206207Y1636165D01*
X205546Y1635954D01*
X204759Y1634425D01*
X204970Y1633765D01*
X204183Y1632235D01*
X203522Y1632024D01*
X202735Y1630495D01*
X202946Y1629835D01*
X202159Y1628305D01*
X201498Y1628093D01*
X196437Y1618262D01*
Y1615452D01*
X197597Y1614292D01*
G01X238780Y1686180D02*
Y1684939D01*
X238199Y1684358D01*
X236220D01*
X235008Y1683146D01*
Y1644062D01*
X234279Y1642467D01*
X234007Y1641603D01*
X208699Y1619297D01*
X207417Y1617510D01*
Y1615452D01*
X206257Y1614292D01*
G01X1382356Y1155809D02*
Y1156701D01*
X1382355Y1156702D01*
Y1178208D01*
X1378139Y1188388D01*
X1354476Y1212051D01*
X1339041Y1218443D01*
X1266511Y1290973D01*
X1261728Y1302518D01*
X1222156Y1342090D01*
X1128979D01*
X1118259Y1346531D01*
X1095428Y1369362D01*
Y1462316D01*
X1056073Y1501671D01*
X634199Y1537295D01*
X499226D01*
X372693Y1518526D01*
X277089Y1478924D01*
X254477Y1456312D01*
X232007Y1402064D01*
Y1323628D01*
X228440Y1315016D01*
X209940Y1292010D01*
Y1280154D01*
X212275Y1277819D01*
Y1277817D01*
X214984Y1275109D01*
X216698Y1273964D01*
X216855Y1273172D01*
X218062Y1272367D01*
X218852Y1272524D01*
X220861Y1271182D01*
X225766Y1266278D01*
Y1258497D01*
X225196Y1257927D01*
Y1256477D01*
X225766Y1255907D01*
Y1253762D01*
X228655Y1250873D01*
X231380D01*
X232760Y1249493D01*
Y1246612D01*
X234177Y1245195D01*
X245013Y1237953D01*
X245012D01*
X245101Y1237894D01*
X249434Y1236099D01*
X253479Y1232054D01*
X268317Y1225908D01*
X322235Y1171990D01*
X328973Y1155722D01*
X328974D01*
X329346Y1154822D01*
X340226Y1143942D01*
Y1138809D01*
G01X1381276Y1155809D02*
Y1156701D01*
X1381275Y1156702D01*
Y1177993D01*
X1377223Y1187776D01*
X1353864Y1211135D01*
X1338429Y1217527D01*
X1265595Y1290361D01*
X1260812Y1301906D01*
X1221708Y1341010D01*
X1128764D01*
X1117647Y1345615D01*
X1094348Y1368914D01*
Y1461868D01*
X1055589Y1500627D01*
X634153Y1536215D01*
X499306D01*
X372983Y1517477D01*
X277701Y1478008D01*
X255393Y1455700D01*
X244802Y1430128D01*
X245110Y1429384D01*
X244555Y1428043D01*
X243810Y1427734D01*
X242774Y1425233D01*
X243083Y1424488D01*
X242528Y1423148D01*
X241782Y1422839D01*
X241228Y1421500D01*
X241536Y1420756D01*
X240982Y1419415D01*
X240236Y1419106D01*
X239068Y1416286D01*
X239376Y1415541D01*
X238821Y1414200D01*
X238075Y1413892D01*
X236844Y1410918D01*
X237152Y1410173D01*
X236597Y1408832D01*
X235852Y1408524D01*
X234968Y1406390D01*
X235277Y1405645D01*
X234722Y1404305D01*
X233976Y1403996D01*
X233087Y1401849D01*
Y1323413D01*
X229379Y1314460D01*
X222499Y1305904D01*
X222586Y1305103D01*
X221676Y1303972D01*
X220876Y1303885D01*
X219097Y1301673D01*
X219184Y1300872D01*
X218275Y1299741D01*
X217473Y1299654D01*
X211020Y1291629D01*
Y1280602D01*
X215676Y1275946D01*
X221550Y1272022D01*
X226846Y1266726D01*
Y1254210D01*
X229103Y1251953D01*
X231828D01*
X233840Y1249941D01*
Y1247060D01*
X234866Y1246034D01*
X245613Y1238851D01*
X249847Y1237097D01*
Y1237098D01*
X250046Y1237015D01*
X254091Y1232970D01*
X256452Y1231992D01*
X257197Y1232301D01*
X258537Y1231746D01*
X258846Y1231000D01*
X264529Y1228647D01*
X265274Y1228955D01*
X266614Y1228400D01*
X266923Y1227655D01*
X268929Y1226824D01*
X323151Y1172602D01*
X330262Y1155434D01*
X341306Y1144390D01*
Y1138809D01*
G01X238780Y1681456D02*
Y1682355D01*
X237857Y1683278D01*
X236668D01*
X236088Y1682698D01*
Y1643826D01*
X235289Y1642078D01*
X234948Y1640991D01*
X225857Y1632979D01*
X225813Y1632287D01*
X224521Y1631149D01*
X223830Y1631193D01*
X222540Y1630056D01*
X222497Y1629364D01*
X221205Y1628226D01*
X220514Y1628270D01*
X219224Y1627133D01*
X219181Y1626441D01*
X217889Y1625303D01*
X217198Y1625347D01*
X215908Y1624210D01*
X215865Y1623518D01*
X214573Y1622380D01*
X213882Y1622424D01*
X209506Y1618567D01*
X208497Y1617162D01*
Y1615452D01*
X209657Y1614292D01*
G01X246654Y1682244D02*
Y1681103D01*
X246073Y1680522D01*
X244194D01*
X242882Y1679210D01*
Y1642360D01*
X219477Y1617705D01*
Y1615452D01*
X218317Y1614292D01*
G01X246654Y1677519D02*
Y1678862D01*
X246074Y1679442D01*
X244642D01*
X243962Y1678762D01*
Y1641929D01*
X236227Y1633780D01*
X236245Y1633087D01*
X235059Y1631839D01*
X234367Y1631821D01*
X233183Y1630574D01*
X233201Y1629881D01*
X232015Y1628633D01*
X231323Y1628615D01*
X230139Y1627368D01*
X230157Y1626675D01*
X228971Y1625427D01*
X228279Y1625409D01*
X227095Y1624162D01*
X227113Y1623469D01*
X225928Y1622220D01*
X225236Y1622202D01*
X220557Y1617274D01*
Y1615452D01*
X221717Y1614292D01*
G01X1378706Y1153619D02*
Y1172486D01*
X1374855Y1185181D01*
X1371169Y1190699D01*
X1352993Y1208875D01*
X1341355Y1213697D01*
X1341354D01*
X1337609Y1215249D01*
X1263585Y1289273D01*
X1259079Y1300153D01*
X1220402Y1338830D01*
X1128329D01*
X1114919Y1344384D01*
X1092168Y1367135D01*
Y1460876D01*
X1054652Y1498392D01*
X633228Y1533975D01*
X499431D01*
X373513Y1515296D01*
X278896Y1476105D01*
X258292Y1455501D01*
X235277Y1399938D01*
Y1322221D01*
X226140Y1300148D01*
Y1277664D01*
X230306Y1273498D01*
X231300Y1271099D01*
Y1257381D01*
X232241Y1255973D01*
X241290Y1246922D01*
Y1246923D01*
X252352Y1241010D01*
X256906Y1236457D01*
X266476Y1232494D01*
X325855Y1173115D01*
X329372Y1164623D01*
X333053Y1155735D01*
X341817Y1146971D01*
G01X1377626Y1153619D02*
Y1172325D01*
X1373868Y1184714D01*
X1370329Y1190010D01*
X1352380Y1207959D01*
X1352381D01*
X1336997Y1214333D01*
X1262669Y1288661D01*
X1258163Y1299541D01*
X1219954Y1337750D01*
X1128114D01*
X1114307Y1343468D01*
X1091088Y1366687D01*
Y1460428D01*
X1054168Y1497348D01*
X1054165D01*
X633182Y1532895D01*
X571440D01*
X570950Y1532405D01*
X569230D01*
X568740Y1532895D01*
X567020D01*
X566530Y1532405D01*
X564810D01*
X564320Y1532895D01*
X562600D01*
X562110Y1532405D01*
X560390D01*
X559900Y1532895D01*
X499511D01*
X373803Y1514247D01*
X279508Y1475189D01*
X259208Y1454889D01*
X236357Y1399723D01*
Y1322006D01*
X231706Y1310770D01*
X227220Y1299933D01*
Y1278112D01*
X231222Y1274110D01*
X232380Y1271314D01*
Y1257709D01*
X233080Y1256662D01*
X235029Y1254713D01*
X235835D01*
X236861Y1253687D01*
Y1252881D01*
X237886Y1251856D01*
X238692D01*
X239718Y1250830D01*
Y1250024D01*
X241941Y1247800D01*
X253003Y1241888D01*
X257518Y1237373D01*
X267088Y1233410D01*
X318678Y1181820D01*
X319357D01*
X320574Y1180603D01*
Y1179924D01*
X321790Y1178708D01*
X322469D01*
X323686Y1177491D01*
Y1176812D01*
X326771Y1173727D01*
X333969Y1156347D01*
X342581Y1147735D01*
G01X1371216Y1172299D02*
Y1177845D01*
X1366505Y1189216D01*
X1350525Y1205196D01*
X1339079Y1209938D01*
X1339078D01*
X1335131Y1211573D01*
X1259836Y1286868D01*
X1255323Y1297763D01*
X1218596Y1334490D01*
X1127216D01*
X1112571Y1340555D01*
X1087828Y1365298D01*
Y1449362D01*
X1087348Y1449842D01*
Y1451562D01*
X1087828Y1452042D01*
Y1453762D01*
X1087348Y1454242D01*
Y1455962D01*
X1087828Y1456442D01*
Y1458986D01*
X1052667Y1494147D01*
X638529Y1529115D01*
X496392D01*
X374992Y1511106D01*
X281220Y1472266D01*
X269999Y1461045D01*
Y1460239D01*
X268973Y1459213D01*
X268167D01*
X266314Y1457360D01*
Y1456554D01*
X265288Y1455528D01*
X264482D01*
X262064Y1453110D01*
X239680Y1399068D01*
Y1321112D01*
X237984Y1316714D01*
X238311Y1315977D01*
X237789Y1314623D01*
X237051Y1314296D01*
X234002Y1306391D01*
X234328Y1305654D01*
X233806Y1304300D01*
X233068Y1303973D01*
X232547Y1302621D01*
X232873Y1301884D01*
X232351Y1300530D01*
X231613Y1300204D01*
X230800Y1298095D01*
Y1282458D01*
X232558Y1278214D01*
X240488Y1270285D01*
X242330Y1265842D01*
Y1261379D01*
X243398Y1258801D01*
X243399D01*
X244465Y1256226D01*
X245679Y1255012D01*
X246358D01*
X247575Y1253795D01*
Y1253116D01*
X250718Y1249973D01*
X251545Y1249630D01*
X257574Y1243601D01*
X261357Y1242033D01*
X261358D01*
X265538Y1240302D01*
X329101Y1176739D01*
X336800Y1158149D01*
X344947Y1150002D01*
G01X1372296Y1172299D02*
Y1178060D01*
X1367421Y1189828D01*
X1351137Y1206112D01*
X1339492Y1210936D01*
X1339491D01*
X1335743Y1212489D01*
X1260752Y1287480D01*
X1256239Y1298375D01*
X1219044Y1335570D01*
X1127431D01*
X1113183Y1341471D01*
X1088908Y1365746D01*
Y1459434D01*
X1053152Y1495191D01*
X638575Y1530195D01*
X496312D01*
X374702Y1512155D01*
X280608Y1473182D01*
X261148Y1453722D01*
X238600Y1399283D01*
Y1321314D01*
X229720Y1298297D01*
Y1282243D01*
X231642Y1277602D01*
X239572Y1269672D01*
X241250Y1265626D01*
Y1261164D01*
X243508Y1255711D01*
X243624Y1255538D01*
X250105Y1249057D01*
X250932Y1248714D01*
X256962Y1242685D01*
X264926Y1239386D01*
X328185Y1176127D01*
X335884Y1157537D01*
X344183Y1149238D01*
G01X1367847Y1158439D02*
Y1159183D01*
X1367846Y1159184D01*
Y1177112D01*
X1363500Y1187605D01*
X1348909Y1202195D01*
X1333500Y1208578D01*
X1257006Y1285072D01*
X1252619Y1295663D01*
X1217272Y1331010D01*
X1126979D01*
X1110766Y1337725D01*
X1084078Y1364413D01*
Y1447582D01*
X1083598Y1448062D01*
Y1449782D01*
X1084078Y1450262D01*
Y1451982D01*
X1083598Y1452462D01*
Y1454182D01*
X1084078Y1454662D01*
Y1457936D01*
X1051179Y1490835D01*
X636809Y1525822D01*
X496541D01*
X376075Y1507952D01*
X284370Y1469967D01*
X264405Y1450002D01*
X242987Y1398295D01*
Y1320799D01*
X241209Y1313701D01*
X240015Y1310605D01*
X240342Y1309868D01*
X239820Y1308514D01*
X239082Y1308188D01*
X238170Y1305822D01*
X238497Y1305085D01*
X237975Y1303731D01*
X237237Y1303404D01*
X236716Y1302052D01*
X237042Y1301315D01*
X236520Y1299962D01*
X235782Y1299635D01*
X234200Y1295532D01*
Y1282969D01*
X234863Y1281369D01*
X237703Y1278529D01*
X242313Y1276619D01*
X243961Y1274971D01*
X245931Y1270215D01*
X246036Y1269962D01*
X247045Y1264888D01*
X248196Y1263737D01*
X252791Y1261834D01*
X253600Y1259883D01*
X263876Y1249603D01*
Y1247297D01*
X306970Y1204195D01*
X307649D01*
X308866Y1202978D01*
Y1202299D01*
X310082Y1201083D01*
X310760D01*
X311977Y1199866D01*
Y1199187D01*
X313193Y1197971D01*
X313872D01*
X315089Y1196754D01*
Y1196075D01*
X316573Y1194591D01*
X317252D01*
X318469Y1193373D01*
Y1192695D01*
X319736Y1191427D01*
X320414D01*
X321631Y1190210D01*
Y1189531D01*
X322847Y1188315D01*
X323526D01*
X324743Y1187097D01*
Y1186419D01*
X326341Y1184820D01*
X327020Y1184819D01*
X328237Y1183602D01*
Y1182923D01*
X331387Y1179773D01*
X339472Y1160251D01*
X350625Y1149098D01*
Y1144870D01*
G01X1365634Y1159379D02*
Y1160721D01*
X1365633Y1160722D01*
Y1174932D01*
X1365029Y1177888D01*
X1361212Y1186791D01*
X1347659Y1200344D01*
X1332252Y1206728D01*
X1254896Y1284084D01*
X1250517Y1294657D01*
X1216354Y1328820D01*
X1126562D01*
X1109510Y1335883D01*
X1081408Y1363985D01*
Y1457243D01*
X1050274Y1488377D01*
X634732Y1523642D01*
X496712D01*
X376692Y1505838D01*
X285610Y1468111D01*
X266276Y1448777D01*
X245177Y1397836D01*
Y1319876D01*
X241147Y1303797D01*
X236420Y1294950D01*
Y1284303D01*
X237352Y1282052D01*
X238896Y1280508D01*
X244222Y1278302D01*
X246875Y1275649D01*
X248820Y1270952D01*
X251375Y1268397D01*
X253225Y1267630D01*
X255618Y1265237D01*
X257987Y1259519D01*
X259867Y1256705D01*
X266674Y1249898D01*
Y1248269D01*
X332822Y1182121D01*
X337027Y1171967D01*
X341396Y1161417D01*
X352805Y1150008D01*
Y1146485D01*
X355199Y1144091D01*
G01X1368927Y1158439D02*
Y1159631D01*
X1368926Y1159632D01*
Y1177327D01*
X1364416Y1188217D01*
X1349521Y1203111D01*
X1334112Y1209494D01*
X1257922Y1285684D01*
X1253535Y1296275D01*
X1217720Y1332090D01*
X1127194D01*
X1111378Y1338641D01*
X1085158Y1364861D01*
Y1458386D01*
X1068394Y1475150D01*
X1068392D01*
X1051664Y1491879D01*
X636855Y1526902D01*
X496461D01*
X375785Y1509001D01*
X283758Y1470883D01*
X263489Y1450614D01*
X241907Y1398510D01*
Y1320933D01*
X240177Y1314028D01*
X233120Y1295734D01*
Y1282753D01*
X233865Y1280956D01*
X233864D01*
X233947Y1280757D01*
X237091Y1277613D01*
X241701Y1275703D01*
X243045Y1274359D01*
X244762Y1270215D01*
X244997Y1269647D01*
X246049Y1264356D01*
X247584Y1262821D01*
X251964Y1261007D01*
X252684Y1259271D01*
X262796Y1249155D01*
Y1246849D01*
X330471Y1179161D01*
X338474Y1159838D01*
X338473D01*
X338556Y1159639D01*
X349545Y1148650D01*
Y1144870D01*
G01X1364554Y1159379D02*
Y1160273D01*
X1364553Y1160274D01*
Y1174822D01*
X1363992Y1177563D01*
X1363098Y1179650D01*
X1362348Y1179949D01*
X1361777Y1181283D01*
X1362076Y1182032D01*
X1360301Y1186174D01*
X1347047Y1199428D01*
X1331640Y1205812D01*
X1253980Y1283472D01*
X1249601Y1294045D01*
X1215906Y1327740D01*
X1126347D01*
X1108898Y1334967D01*
X1080328Y1363537D01*
Y1456795D01*
X1049789Y1487334D01*
X634686Y1522562D01*
X496792D01*
X376982Y1504789D01*
X286222Y1467195D01*
X277090Y1458063D01*
Y1457257D01*
X276064Y1456231D01*
X275258D01*
X274233Y1455206D01*
Y1454400D01*
X273207Y1453374D01*
X272401D01*
X271376Y1452349D01*
Y1451543D01*
X270349Y1450516D01*
X269543D01*
X267192Y1448165D01*
X246257Y1397621D01*
Y1319742D01*
X242163Y1303405D01*
X240333Y1299979D01*
X240567Y1299208D01*
X239883Y1297928D01*
X239111Y1297694D01*
X237500Y1294679D01*
Y1293229D01*
X238070Y1292659D01*
Y1291209D01*
X237500Y1290639D01*
Y1284518D01*
X238268Y1282664D01*
X239508Y1281424D01*
X244834Y1279218D01*
X247791Y1276261D01*
X249736Y1271564D01*
X251987Y1269313D01*
X253837Y1268546D01*
X256534Y1265849D01*
X258944Y1260031D01*
X260707Y1257394D01*
X267754Y1250346D01*
Y1248717D01*
X315007Y1201464D01*
X315686D01*
X316903Y1200247D01*
Y1199568D01*
X318119Y1198352D01*
X318798D01*
X320015Y1197135D01*
Y1196456D01*
X321231Y1195240D01*
X321910D01*
X323128Y1194022D01*
Y1193343D01*
X324359Y1192112D01*
X325038D01*
X326255Y1190895D01*
Y1190216D01*
X327471Y1189000D01*
X328150D01*
X329368Y1187782D01*
Y1187103D01*
X333738Y1182733D01*
X342312Y1162029D01*
X353885Y1150456D01*
Y1146933D01*
X355963Y1144855D01*
G01X1362360Y1159379D02*
Y1174020D01*
X1357418Y1185953D01*
X1345785Y1197586D01*
X1330391Y1203963D01*
X1252112Y1282242D01*
X1247727Y1292833D01*
X1215000Y1325560D01*
X1125900D01*
X1107671Y1333111D01*
X1078148Y1362634D01*
Y1455892D01*
X1048811Y1485229D01*
X635128Y1520335D01*
X496751D01*
X377775Y1502686D01*
X289034Y1465927D01*
X268352Y1445245D01*
X248437Y1397165D01*
Y1319153D01*
X242038Y1293624D01*
X239720Y1289288D01*
Y1285021D01*
X240141Y1284005D01*
X240873Y1283273D01*
X246606Y1280898D01*
X249682Y1277822D01*
X251818Y1272666D01*
X253372Y1271119D01*
X255831Y1270108D01*
X255830D01*
X256091Y1270002D01*
X257621Y1268476D01*
X259635Y1264818D01*
X260082Y1263409D01*
X262901Y1258290D01*
X271119Y1250075D01*
Y1249215D01*
X328391Y1191959D01*
X328392D01*
X335138Y1185214D01*
X344193Y1163351D01*
X344192D01*
X344275Y1163152D01*
X356075Y1151352D01*
Y1149271D01*
X360928Y1144418D01*
X360932D01*
X362358Y1142992D01*
G01X254528Y1686180D02*
Y1684939D01*
X253947Y1684358D01*
X251968D01*
X250756Y1683146D01*
Y1643913D01*
X249960Y1642819D01*
X249956Y1642814D01*
X231537Y1617514D01*
Y1615452D01*
X230377Y1614292D01*
G01X254528Y1681456D02*
Y1682355D01*
X253605Y1683278D01*
X252416D01*
X251836Y1682698D01*
Y1643562D01*
X250836Y1642182D01*
Y1642181D01*
X250832Y1642176D01*
X245265Y1634531D01*
X245372Y1633847D01*
X244359Y1632456D01*
X243674Y1632348D01*
X242662Y1630958D01*
X242770Y1630273D01*
X241757Y1628882D01*
X241072Y1628774D01*
X240060Y1627384D01*
X240168Y1626699D01*
X239155Y1625308D01*
X238470Y1625200D01*
X237458Y1623810D01*
X237566Y1623125D01*
X236552Y1621734D01*
X235868Y1621626D01*
X232617Y1617162D01*
Y1615452D01*
X233777Y1614292D01*
G01X1361280Y1159379D02*
Y1173805D01*
X1356502Y1185341D01*
X1349162Y1192681D01*
X1348356D01*
X1347329Y1193708D01*
Y1194514D01*
X1345173Y1196670D01*
X1341984Y1197991D01*
X1341240Y1197682D01*
X1339899Y1198237D01*
X1339590Y1198982D01*
X1337596Y1199808D01*
X1336852Y1199500D01*
X1335511Y1200054D01*
X1335202Y1200800D01*
X1333811Y1201376D01*
X1333067Y1201068D01*
X1331726Y1201623D01*
X1331417Y1202369D01*
X1329779Y1203047D01*
X1251196Y1281630D01*
X1246811Y1292221D01*
X1214552Y1324480D01*
X1125685D01*
X1107059Y1332195D01*
X1077068Y1362186D01*
Y1455444D01*
X1048326Y1484186D01*
X635082Y1519255D01*
X496831D01*
X378065Y1501637D01*
X289646Y1465011D01*
X269268Y1444633D01*
X249517Y1396950D01*
Y1319019D01*
X248983Y1316886D01*
X249398Y1316195D01*
X249045Y1314787D01*
X248353Y1314373D01*
X248001Y1312967D01*
X248415Y1312276D01*
X248062Y1310868D01*
X247370Y1310454D01*
X247018Y1309048D01*
X247432Y1308357D01*
X247080Y1306949D01*
X246387Y1306535D01*
X246388Y1306534D01*
X245991Y1304947D01*
X246404Y1304256D01*
X246052Y1302849D01*
X245359Y1302434D01*
X245360Y1302433D01*
X244891Y1300559D01*
X245304Y1299869D01*
X244952Y1298461D01*
X244260Y1298047D01*
X243054Y1293232D01*
X240800Y1289017D01*
Y1285237D01*
X241101Y1284511D01*
X241379Y1284233D01*
X247218Y1281814D01*
X250598Y1278434D01*
X252734Y1273279D01*
X253982Y1272036D01*
X256701Y1270919D01*
X258493Y1269132D01*
X260633Y1265246D01*
X261080Y1263837D01*
X263774Y1258946D01*
X272199Y1250523D01*
Y1249663D01*
X314550Y1207324D01*
X315294D01*
X316382Y1206236D01*
Y1205492D01*
X317407Y1204467D01*
X318151D01*
X319240Y1203379D01*
Y1202635D01*
X320265Y1201610D01*
X321007D01*
X322098Y1200520D01*
Y1199778D01*
X323123Y1198753D01*
X323865D01*
X324956Y1197663D01*
Y1196921D01*
X325981Y1195896D01*
X326723D01*
X327813Y1194806D01*
X327814Y1194064D01*
X328839Y1193039D01*
X328840D01*
X336054Y1185826D01*
X345191Y1163764D01*
X357155Y1151800D01*
Y1149719D01*
X361692Y1145182D01*
X361696D01*
X363122Y1143756D01*
G01X1359088Y1159899D02*
Y1160671D01*
X1359087Y1160672D01*
Y1173243D01*
X1355336Y1182303D01*
X1344324Y1193315D01*
X1330820Y1198908D01*
X1249220Y1280508D01*
X1244825Y1291121D01*
X1213646Y1322300D01*
X1125068D01*
X1105954Y1330217D01*
X1074888Y1361283D01*
Y1454541D01*
X1047360Y1482069D01*
X635195Y1517045D01*
X496932D01*
X378810Y1499524D01*
X290803Y1463070D01*
X271162Y1443429D01*
X251697Y1396435D01*
Y1314877D01*
X249589Y1302919D01*
X250622Y1297065D01*
X254165Y1290991D01*
X258587Y1275058D01*
X265604Y1260228D01*
X337447Y1188385D01*
X347189Y1164863D01*
X360066Y1151986D01*
Y1150084D01*
X366764Y1143386D01*
G01X1358008Y1159899D02*
Y1160671D01*
X1358007Y1160672D01*
Y1173027D01*
X1354420Y1181691D01*
X1343712Y1192399D01*
X1330208Y1197992D01*
X1248304Y1279896D01*
X1243909Y1290509D01*
X1213198Y1321220D01*
X1124853D01*
X1105342Y1329301D01*
X1073808Y1360835D01*
Y1454093D01*
X1046875Y1481026D01*
X635149Y1515965D01*
X510650D01*
X510170Y1515485D01*
X508450D01*
X507970Y1515965D01*
X506250D01*
X505770Y1515485D01*
X504050D01*
X503570Y1515965D01*
X501640D01*
X501160Y1515485D01*
X499440D01*
X498960Y1515965D01*
X497012D01*
X379100Y1498475D01*
X291415Y1462154D01*
X272078Y1442817D01*
X252777Y1396220D01*
Y1314706D01*
X252761Y1314690D01*
X251450Y1307253D01*
X251840Y1306697D01*
X251541Y1305002D01*
X250984Y1304612D01*
X250686Y1302919D01*
X251652Y1297443D01*
X252482Y1296020D01*
X253263Y1295815D01*
X253993Y1294561D01*
X253788Y1293782D01*
X255169Y1291415D01*
X259603Y1275436D01*
X266501Y1260860D01*
X266502Y1260858D01*
X332318Y1195042D01*
X333124D01*
X334150Y1194016D01*
Y1193210D01*
X335175Y1192185D01*
X335981D01*
X337007Y1191159D01*
Y1190353D01*
X338363Y1188997D01*
X339606Y1185994D01*
X340352Y1185686D01*
X340906Y1184345D01*
X340598Y1183600D01*
X341152Y1182261D01*
X341898Y1181953D01*
X342453Y1180612D01*
X342144Y1179867D01*
X343454Y1176704D01*
X344200Y1176395D01*
X344755Y1175055D01*
X344446Y1174310D01*
X348105Y1165475D01*
X361146Y1152434D01*
Y1150532D01*
X367528Y1144150D01*
G01X1355778Y1159899D02*
Y1160671D01*
X1355777Y1160672D01*
Y1172675D01*
X1354498Y1175226D01*
X1352181Y1180820D01*
X1343385Y1189616D01*
X1329896Y1195206D01*
X1246439Y1278663D01*
X1242048Y1289264D01*
X1212272Y1319040D01*
X1124184D01*
X1104272Y1327288D01*
X1071628Y1359932D01*
Y1452914D01*
X1045653Y1478889D01*
X640804Y1513243D01*
X634523Y1513275D01*
X493758D01*
X379996Y1496400D01*
X292531Y1460172D01*
X273930Y1441571D01*
X254987Y1395836D01*
Y1308640D01*
X255030Y1308596D01*
X256321Y1295487D01*
X261651Y1276222D01*
X268249Y1262267D01*
X310282Y1220234D01*
X355827Y1182859D01*
X358360Y1182090D01*
X360609Y1180245D01*
X360610D01*
X362858Y1178400D01*
X364266Y1176501D01*
X366972Y1169967D01*
Y1148378D01*
X368838Y1146512D01*
G01X1354698Y1159899D02*
Y1160671D01*
X1354697Y1160672D01*
Y1172419D01*
X1353514Y1174776D01*
X1351265Y1180208D01*
X1342773Y1188700D01*
X1329284Y1194290D01*
X1245523Y1278051D01*
X1241132Y1288652D01*
X1211824Y1317960D01*
X1123969D01*
X1103660Y1326372D01*
X1070548Y1359484D01*
Y1452466D01*
X1045168Y1477846D01*
X640756Y1512163D01*
X634520Y1512195D01*
X493838D01*
X380286Y1495351D01*
X293143Y1459256D01*
X285740Y1451853D01*
Y1451174D01*
X284523Y1449957D01*
X283844D01*
X282628Y1448741D01*
Y1448062D01*
X281410Y1446844D01*
X280731D01*
X279433Y1445546D01*
Y1444867D01*
X278215Y1443649D01*
X277536D01*
X274846Y1440959D01*
X256067Y1395621D01*
Y1309088D01*
X256068Y1309087D01*
X256301Y1306711D01*
X256925Y1306200D01*
X257068Y1304756D01*
X256556Y1304133D01*
X256961Y1300014D01*
X257585Y1299502D01*
X257727Y1298058D01*
X257215Y1297435D01*
X257387Y1295685D01*
X262667Y1276600D01*
X269146Y1262899D01*
X311009Y1221036D01*
X336795Y1199876D01*
X337471Y1199942D01*
X338802Y1198850D01*
X338868Y1198175D01*
X344505Y1193549D01*
X345180Y1193616D01*
X346511Y1192524D01*
X346577Y1191848D01*
X348096Y1190602D01*
X348772Y1190668D01*
X350102Y1189576D01*
X350169Y1188901D01*
X351498Y1187810D01*
X352174Y1187877D01*
X353504Y1186785D01*
X353571Y1186109D01*
X356347Y1183831D01*
X358880Y1183062D01*
X363647Y1179151D01*
X365214Y1177038D01*
X368052Y1170182D01*
Y1162427D01*
X368622Y1161857D01*
Y1160407D01*
X368052Y1159837D01*
Y1158387D01*
X368622Y1157817D01*
Y1156367D01*
X368052Y1155797D01*
Y1154347D01*
X368622Y1153777D01*
Y1152327D01*
X368052Y1151757D01*
Y1148826D01*
X369602Y1147276D01*
G01X262402Y1682244D02*
Y1681003D01*
X261891Y1680492D01*
X259912D01*
X258632Y1679212D01*
Y1642582D01*
X243597Y1617533D01*
Y1615452D01*
X242437Y1614292D01*
G01X270276Y1686180D02*
Y1684727D01*
X269741Y1684192D01*
X267550D01*
X266504Y1683146D01*
Y1641286D01*
X255657Y1617233D01*
Y1615452D01*
X254497Y1614292D01*
G01X262402Y1677519D02*
Y1678832D01*
X261822Y1679412D01*
X260360D01*
X259712Y1678764D01*
Y1642282D01*
X257863Y1639200D01*
X258031Y1638528D01*
X257145Y1637052D01*
X256473Y1636884D01*
X255588Y1635410D01*
X255756Y1634738D01*
X254870Y1633262D01*
X254198Y1633094D01*
X253313Y1631620D01*
X253481Y1630948D01*
X252595Y1629472D01*
X251923Y1629304D01*
X251038Y1627830D01*
X251206Y1627158D01*
X250320Y1625682D01*
X249648Y1625514D01*
X248763Y1624040D01*
X248931Y1623367D01*
X248044Y1621892D01*
X247372Y1621724D01*
X244677Y1617233D01*
Y1615452D01*
X245837Y1614292D01*
G01X270276Y1681456D02*
Y1682532D01*
X269696Y1683112D01*
X267998D01*
X267584Y1682698D01*
Y1641053D01*
X265464Y1636350D01*
X265709Y1635702D01*
X265002Y1634133D01*
X264353Y1633888D01*
X263488Y1631969D01*
X263733Y1631321D01*
X263026Y1629752D01*
X262377Y1629507D01*
X261616Y1627819D01*
X261862Y1627171D01*
X261155Y1625602D01*
X260506Y1625356D01*
X259799Y1623789D01*
X260044Y1623141D01*
X259337Y1621572D01*
X258688Y1621327D01*
X256737Y1617000D01*
Y1615452D01*
X257897Y1614292D01*
G01X1352507Y1162569D02*
Y1163671D01*
X1352506Y1163672D01*
Y1171369D01*
X1349325Y1179056D01*
X1342250Y1186131D01*
Y1186132D01*
X1342098Y1186283D01*
X1328603Y1191873D01*
X1243449Y1277027D01*
X1239054Y1287638D01*
X1210912Y1315780D01*
X1123398D01*
X1102522Y1324427D01*
X1068368Y1358581D01*
Y1450975D01*
X1043669Y1475674D01*
X642531Y1509650D01*
X640719Y1509952D01*
X640686Y1509956D01*
X634970D01*
X634966Y1509960D01*
X493842D01*
X381003Y1493222D01*
X295611Y1457852D01*
X276164Y1438405D01*
X258277Y1395218D01*
Y1317761D01*
X260891Y1291206D01*
X264720Y1277377D01*
X270949Y1264203D01*
X309048Y1226104D01*
X357914Y1186001D01*
X359256Y1185594D01*
X365350Y1180593D01*
X367071Y1178271D01*
X370862Y1169118D01*
Y1151802D01*
X370863Y1151801D01*
Y1151189D01*
G01X1349218Y1159399D02*
Y1169371D01*
X1345567Y1178188D01*
X1340227Y1183528D01*
X1326741Y1189111D01*
X1240625Y1275227D01*
X1236571Y1285011D01*
X1209062Y1312520D01*
X1122747D01*
X1100676Y1321662D01*
X1064768Y1357570D01*
Y1449846D01*
X1042375Y1472239D01*
X637854Y1506692D01*
X494038D01*
X382068Y1490083D01*
X297611Y1455102D01*
X278838Y1436329D01*
X261557Y1394607D01*
Y1318044D01*
X264154Y1291667D01*
X267785Y1278551D01*
X273664Y1266116D01*
X307442Y1232337D01*
X367877Y1182743D01*
X369893Y1180025D01*
X374138Y1169776D01*
Y1150161D01*
X381308Y1142991D01*
G01X1351427Y1162569D02*
Y1163223D01*
X1351426Y1163224D01*
Y1171154D01*
X1348409Y1178444D01*
X1341486Y1185367D01*
X1327991Y1190957D01*
X1242533Y1276415D01*
X1238138Y1287026D01*
X1210464Y1314700D01*
X1123183D01*
X1101910Y1323511D01*
X1067288Y1358133D01*
Y1450527D01*
X1043184Y1474631D01*
X642396Y1508577D01*
X640605Y1508876D01*
X634522D01*
X634518Y1508880D01*
X493922D01*
X381293Y1492173D01*
X296223Y1456936D01*
X277080Y1437793D01*
X259357Y1395003D01*
Y1317815D01*
X261957Y1291404D01*
X265736Y1277755D01*
X271846Y1264835D01*
X309775Y1226906D01*
X311104Y1225815D01*
X311780Y1225882D01*
X313110Y1224790D01*
X313177Y1224114D01*
X315237Y1222424D01*
X315912Y1222490D01*
X317243Y1221398D01*
X317309Y1220723D01*
X349501Y1194304D01*
X349500Y1194303D01*
X349503D01*
X350178Y1194370D01*
X351509Y1193278D01*
X351576Y1192602D01*
X353105Y1191347D01*
X353780Y1191413D01*
X355111Y1190321D01*
X355177Y1189646D01*
X358434Y1186973D01*
X359776Y1186566D01*
X366139Y1181344D01*
X368019Y1178808D01*
X371942Y1169333D01*
Y1151802D01*
X371943Y1151801D01*
Y1151189D01*
G01X1348138Y1159399D02*
Y1169156D01*
X1344651Y1177576D01*
X1339615Y1182612D01*
X1326129Y1188195D01*
X1239709Y1274615D01*
X1235655Y1284399D01*
X1208614Y1311440D01*
X1122532D01*
X1100064Y1320746D01*
X1063688Y1357122D01*
Y1449398D01*
X1041890Y1471196D01*
X637808Y1505612D01*
X494118D01*
X382358Y1489034D01*
X298223Y1454186D01*
X289377Y1445340D01*
Y1444661D01*
X288160Y1443444D01*
X287481D01*
X286265Y1442228D01*
Y1441549D01*
X285048Y1440332D01*
X284369D01*
X283153Y1439116D01*
Y1438437D01*
X281935Y1437219D01*
X281256D01*
X279754Y1435717D01*
X262637Y1394392D01*
Y1318098D01*
X265220Y1291865D01*
X268801Y1278929D01*
X269536Y1277375D01*
X270176Y1277146D01*
X270911Y1275590D01*
X270682Y1274951D01*
X271417Y1273397D01*
X272057Y1273168D01*
X272792Y1271612D01*
X272563Y1270973D01*
X274561Y1266748D01*
X308169Y1233139D01*
X368666Y1183494D01*
X370841Y1180562D01*
X371850Y1178123D01*
X372479Y1177863D01*
X373136Y1176273D01*
X372877Y1175646D01*
X373534Y1174057D01*
X374162Y1173797D01*
X374820Y1172207D01*
X374560Y1171580D01*
X375218Y1169991D01*
Y1164447D01*
X375788Y1163877D01*
Y1162427D01*
X375218Y1161857D01*
Y1159227D01*
X375788Y1158657D01*
Y1157207D01*
X375218Y1156637D01*
Y1155187D01*
X375788Y1154617D01*
Y1153167D01*
X375218Y1152597D01*
Y1150609D01*
X382072Y1143755D01*
G01X1345338Y1161759D02*
Y1168382D01*
X1344044Y1172614D01*
X1343138Y1174125D01*
X1341808Y1177334D01*
X1338412Y1180730D01*
X1324903Y1186323D01*
X1237615Y1273611D01*
X1233912Y1278901D01*
X1232672Y1279770D01*
X1225352Y1282076D01*
X1224026D01*
X1220511Y1283532D01*
X1218905Y1284606D01*
X1217251Y1286259D01*
X1215343Y1288986D01*
X1213656Y1298555D01*
X1211132Y1302157D01*
X1204033Y1309260D01*
X1121935D01*
X1098713Y1318878D01*
X1060108Y1357483D01*
Y1447915D01*
X1039892Y1468131D01*
X838287Y1485778D01*
X785288Y1480072D01*
X638538Y1503262D01*
X636668Y1503425D01*
X494241D01*
X383382Y1486979D01*
X300442Y1452627D01*
X281135Y1433320D01*
X264837Y1393971D01*
Y1318118D01*
X267387Y1292239D01*
X270068Y1282550D01*
X277435Y1266972D01*
X308439Y1235968D01*
Y1235967D01*
X309710Y1234696D01*
X309751Y1234662D01*
X309752Y1234663D01*
X370255Y1185012D01*
X373986Y1179982D01*
X378372Y1169394D01*
Y1150578D01*
X382118Y1146832D01*
G01X1335818Y1152372D02*
X1334868Y1153322D01*
X1334864D01*
Y1153326D01*
X1332280Y1155910D01*
X1332276D01*
X1327447Y1160739D01*
X1323251Y1167006D01*
X1323250Y1167009D01*
X1320559Y1175874D01*
X1320946Y1176596D01*
X1324157Y1177571D01*
X1324964Y1179082D01*
X1324287Y1181313D01*
X1322776Y1182120D01*
X1319564Y1181145D01*
X1318842Y1181531D01*
X1316129Y1190472D01*
X1240054Y1266547D01*
X1232378Y1271676D01*
X1224565Y1277170D01*
Y1277171D01*
X1221968Y1278998D01*
X1220782Y1279208D01*
X1213825Y1284079D01*
X1211573Y1287297D01*
X1210286Y1294591D01*
X1205454Y1301491D01*
X1200944Y1306000D01*
X1121240D01*
X1096898Y1316082D01*
X1056358Y1356622D01*
Y1444785D01*
X1036578Y1464567D01*
X836988Y1482231D01*
X781491Y1473655D01*
X629208Y1500145D01*
X494445D01*
X384491Y1483835D01*
X303629Y1450342D01*
X283375Y1430088D01*
X268117Y1393291D01*
Y1318328D01*
X270639Y1292713D01*
X272872Y1284646D01*
X280419Y1268684D01*
X312325Y1236778D01*
X372674Y1187251D01*
X376839Y1181636D01*
X382072Y1169001D01*
Y1151510D01*
X389471Y1144111D01*
Y1142843D01*
G01X1344258Y1161759D02*
Y1168220D01*
X1343049Y1172171D01*
X1342170Y1173637D01*
X1341531Y1175180D01*
X1340892Y1176722D01*
X1337800Y1179814D01*
X1324291Y1185407D01*
X1236784Y1272914D01*
X1233136Y1278125D01*
X1232188Y1278789D01*
X1229747Y1279558D01*
X1229032Y1279186D01*
X1227648Y1279622D01*
X1227276Y1280338D01*
Y1280337D01*
X1227275Y1280338D01*
Y1280337D01*
X1227274Y1280338D01*
X1225185Y1280996D01*
X1223811D01*
X1219999Y1282575D01*
X1218216Y1283766D01*
X1216420Y1285561D01*
X1214320Y1288562D01*
X1212633Y1298131D01*
X1210301Y1301460D01*
X1207676Y1304086D01*
X1206870D01*
X1205844Y1305113D01*
X1205845Y1305919D01*
X1203585Y1308180D01*
X1121720D01*
X1098101Y1317962D01*
X1059028Y1357035D01*
Y1447467D01*
X1039406Y1467089D01*
X838298Y1484692D01*
X785261Y1478982D01*
X638407Y1502189D01*
X636621Y1502345D01*
X494321D01*
X383672Y1485930D01*
X301054Y1451711D01*
X293738Y1444395D01*
Y1443589D01*
X292712Y1442563D01*
X291906D01*
X290881Y1441538D01*
Y1440732D01*
X289855Y1439706D01*
X289049D01*
X288024Y1438681D01*
Y1437875D01*
X286997Y1436848D01*
X286191D01*
X284908Y1435565D01*
Y1434759D01*
X283882Y1433733D01*
X283076D01*
X282051Y1432708D01*
X265917Y1393756D01*
Y1318172D01*
X268453Y1292437D01*
X271084Y1282928D01*
X278332Y1267604D01*
X310437Y1235498D01*
X371044Y1185763D01*
X374934Y1180519D01*
X374933Y1180518D01*
X379452Y1169609D01*
Y1151026D01*
X382882Y1147596D01*
G01X1335054Y1151608D02*
X1331832Y1154830D01*
X1331828D01*
X1326608Y1160050D01*
X1322264Y1166539D01*
X1319395Y1175989D01*
X1320203Y1177500D01*
X1323415Y1178475D01*
X1323800Y1179196D01*
X1323383Y1180571D01*
X1322662Y1180956D01*
X1319449Y1179981D01*
X1317938Y1180789D01*
X1315173Y1189899D01*
X1239362Y1265709D01*
X1231767Y1270785D01*
X1223485Y1276608D01*
Y1276610D01*
X1221543Y1277976D01*
X1220358Y1278185D01*
X1213049Y1283303D01*
X1210550Y1286873D01*
X1209263Y1294167D01*
X1207931Y1296069D01*
X1207136Y1296209D01*
X1206304Y1297398D01*
X1206444Y1298192D01*
X1204623Y1300793D01*
X1200496Y1304920D01*
X1121025D01*
X1096286Y1315166D01*
X1055278Y1356174D01*
Y1429127D01*
X1054708Y1429697D01*
Y1431147D01*
X1055278Y1431717D01*
Y1433167D01*
X1054708Y1433737D01*
Y1435187D01*
X1055278Y1435757D01*
Y1437207D01*
X1054708Y1437777D01*
Y1439227D01*
X1055278Y1439797D01*
Y1444337D01*
X1036091Y1463525D01*
X837023Y1481143D01*
X781655Y1472587D01*
Y1472586D01*
X781481Y1472560D01*
X629114Y1499065D01*
X494525D01*
X384781Y1482786D01*
X304241Y1449426D01*
X284291Y1429476D01*
X275392Y1408011D01*
X275700Y1407267D01*
X275145Y1405926D01*
X274399Y1405618D01*
X273844Y1404279D01*
X274152Y1403535D01*
X273597Y1402194D01*
X272851Y1401886D01*
X272296Y1400547D01*
X272604Y1399803D01*
X272049Y1398462D01*
X271303Y1398154D01*
X270748Y1396815D01*
X271056Y1396070D01*
X270501Y1394730D01*
X269755Y1394422D01*
X269197Y1393075D01*
Y1318382D01*
X271705Y1292911D01*
X273888Y1285024D01*
X281316Y1269316D01*
X313052Y1237580D01*
X373463Y1188002D01*
X377787Y1182173D01*
X383152Y1169216D01*
Y1165437D01*
X383722Y1164867D01*
Y1163417D01*
X383152Y1162847D01*
Y1161397D01*
X383722Y1160827D01*
Y1159377D01*
X383152Y1158807D01*
Y1155998D01*
X383722Y1155428D01*
Y1153978D01*
X383152Y1153408D01*
Y1151958D01*
X390551Y1144559D01*
Y1142843D01*
G01X1335304Y1147926D02*
X1325735Y1157491D01*
X1325734D01*
X1323442Y1160753D01*
X1320294Y1165464D01*
X1313231Y1188744D01*
X1238004Y1263970D01*
X1218070Y1276036D01*
X1214664Y1279458D01*
X1209420Y1283133D01*
X1207843Y1285386D01*
X1206729Y1291705D01*
X1204441Y1294971D01*
X1196672Y1302740D01*
X1120328D01*
X1095237Y1313132D01*
X1052095Y1356274D01*
Y1440796D01*
X1037266Y1455625D01*
X978653Y1465961D01*
X943212Y1459713D01*
X940378Y1460215D01*
X939907Y1460886D01*
X940441Y1463907D01*
X939459Y1465311D01*
X936288Y1465872D01*
X934885Y1464890D01*
X934350Y1461869D01*
X933679Y1461398D01*
X931394Y1461803D01*
X930923Y1462475D01*
X931457Y1465496D01*
X930475Y1466900D01*
X927304Y1467461D01*
X925901Y1466479D01*
X925366Y1463458D01*
X924695Y1462987D01*
X922410Y1463392D01*
X921939Y1464064D01*
X922473Y1467085D01*
X921491Y1468489D01*
X918320Y1469050D01*
X916917Y1468068D01*
X916382Y1465047D01*
X915711Y1464576D01*
X836085Y1478653D01*
X783612Y1469400D01*
X627699Y1496885D01*
X494921D01*
X385854Y1480705D01*
X305270Y1447328D01*
X287146Y1429203D01*
X271437Y1391276D01*
Y1318593D01*
X273962Y1292947D01*
X275860Y1286085D01*
X283235Y1270491D01*
X314524Y1239201D01*
X375107Y1189483D01*
X379679Y1183319D01*
X386478Y1166906D01*
Y1151922D01*
X393170Y1145230D01*
Y1144312D01*
X393171Y1144311D01*
Y1143423D01*
G01X1334540Y1147162D02*
X1324904Y1156793D01*
X1322341Y1160440D01*
X1322344Y1160451D01*
X1319307Y1164997D01*
X1312275Y1188171D01*
X1237332Y1263113D01*
X1236052Y1263888D01*
X1235269Y1263695D01*
X1234028Y1264446D01*
X1233835Y1265230D01*
X1221547Y1272668D01*
X1220764Y1272476D01*
X1219523Y1273227D01*
X1219330Y1274010D01*
X1217398Y1275180D01*
X1213966Y1278628D01*
X1208644Y1282358D01*
X1206820Y1284962D01*
X1205706Y1291281D01*
X1204658Y1292777D01*
Y1292778D01*
X1203610Y1294273D01*
X1200237Y1297647D01*
X1199431D01*
X1198405Y1298673D01*
Y1299479D01*
X1196224Y1301660D01*
X1120113D01*
X1094625Y1312216D01*
X1051015Y1355826D01*
Y1434657D01*
X1050445Y1435227D01*
Y1436677D01*
X1051015Y1437247D01*
Y1440348D01*
X1036743Y1454620D01*
X978653Y1464864D01*
X943213Y1458616D01*
X939750Y1459229D01*
X938765Y1460632D01*
X939299Y1463654D01*
X938830Y1464325D01*
X936541Y1464730D01*
X935871Y1464261D01*
X935336Y1461241D01*
X933932Y1460256D01*
X930766Y1460817D01*
X929781Y1462222D01*
X930315Y1465243D01*
X929846Y1465914D01*
X927557Y1466319D01*
X926887Y1465850D01*
X926352Y1462830D01*
X924948Y1461845D01*
X921782Y1462406D01*
X920797Y1463811D01*
X921331Y1466832D01*
X920862Y1467503D01*
X918573Y1467908D01*
X917903Y1467439D01*
X917368Y1464419D01*
X915965Y1463434D01*
X836085Y1477556D01*
X783612Y1468303D01*
X627604Y1495805D01*
X495001D01*
X386144Y1479656D01*
X305882Y1446412D01*
X304569Y1445099D01*
Y1444293D01*
X303543Y1443267D01*
X302737D01*
X301712Y1442242D01*
X301713Y1441436D01*
X300686Y1440409D01*
X299880D01*
X298708Y1439237D01*
Y1438431D01*
X297681Y1437404D01*
X296875D01*
X295758Y1436287D01*
Y1435481D01*
X294731Y1434454D01*
X293925D01*
X292263Y1432792D01*
Y1431986D01*
X291236Y1430959D01*
X290430D01*
X288062Y1428591D01*
X272517Y1391061D01*
Y1318647D01*
X275028Y1293145D01*
X276877Y1286463D01*
X284132Y1271123D01*
X315251Y1240003D01*
X375896Y1190234D01*
X380627Y1183856D01*
X387558Y1167121D01*
Y1164447D01*
X388128Y1163877D01*
Y1162427D01*
X387558Y1161857D01*
Y1160097D01*
X388128Y1159527D01*
Y1158077D01*
X387558Y1157507D01*
Y1152370D01*
X394250Y1145678D01*
Y1144312D01*
X394251Y1144311D01*
Y1143423D01*
G01X278150Y1682244D02*
Y1681103D01*
X277569Y1680522D01*
X275690D01*
X274378Y1679210D01*
Y1642710D01*
X267717Y1618018D01*
Y1615452D01*
X266557Y1614292D01*
G01X278150Y1677519D02*
Y1678862D01*
X277570Y1679442D01*
X276138D01*
X275458Y1678762D01*
Y1642566D01*
X273423Y1635020D01*
X273769Y1634419D01*
X273321Y1632758D01*
X272719Y1632412D01*
X272272Y1630752D01*
X272617Y1630151D01*
X272169Y1628490D01*
X271567Y1628144D01*
X271120Y1626484D01*
X271466Y1625883D01*
X271018Y1624221D01*
X270416Y1623876D01*
X269949Y1622142D01*
X270294Y1621541D01*
X269846Y1619880D01*
X269244Y1619534D01*
X268797Y1617874D01*
Y1615452D01*
X269957Y1614292D01*
G01X1331710Y1144740D02*
X1323203Y1153247D01*
Y1153265D01*
X1316330Y1163546D01*
X1309383Y1186437D01*
X1240712Y1255109D01*
X1223611Y1262192D01*
X1218965Y1266108D01*
X1216049Y1270733D01*
X1210272Y1276801D01*
X1205544Y1280111D01*
X1202665Y1284223D01*
X1202194Y1286889D01*
Y1286891D01*
X1201724Y1289556D01*
X1200066Y1291621D01*
X1193288Y1298400D01*
X1118923D01*
X1093160Y1309070D01*
X1046705Y1355525D01*
Y1437157D01*
X1032435Y1451427D01*
X1007375Y1455845D01*
X1006704Y1455374D01*
X1005981Y1451279D01*
X1004578Y1450296D01*
X1001406Y1450856D01*
X1000423Y1452259D01*
X1001146Y1456354D01*
X1000675Y1457025D01*
X998389Y1457430D01*
X997718Y1456959D01*
X996995Y1452864D01*
X995592Y1451881D01*
X992420Y1452441D01*
X991437Y1453844D01*
X992160Y1457939D01*
X991689Y1458610D01*
X989403Y1459015D01*
X988732Y1458544D01*
X988009Y1454449D01*
X986606Y1453466D01*
X983434Y1454026D01*
X982451Y1455429D01*
X983174Y1459524D01*
X982703Y1460195D01*
X977767Y1461066D01*
X944094Y1455130D01*
X835875Y1474205D01*
X783612Y1464989D01*
X627318Y1492542D01*
X495388D01*
X387229Y1476485D01*
X309504Y1444290D01*
X303664Y1438450D01*
Y1437644D01*
X302638Y1436618D01*
X301832D01*
X300518Y1435304D01*
Y1434498D01*
X299492Y1433472D01*
X298686D01*
X297661Y1432447D01*
Y1431641D01*
X296635Y1430615D01*
X295829D01*
X294804Y1429590D01*
Y1428784D01*
X293778Y1427758D01*
X292972D01*
X290130Y1424916D01*
X275777Y1390267D01*
Y1318952D01*
X278260Y1293729D01*
X279962Y1287578D01*
X286845Y1273027D01*
X317422Y1242450D01*
X378395Y1192410D01*
X383562Y1185443D01*
X392339Y1164252D01*
Y1154369D01*
G01X1329307Y1143756D02*
X1327401Y1145662D01*
X1327397D01*
X1320690Y1152369D01*
X1314675Y1161361D01*
X1307405Y1185318D01*
X1243346Y1249376D01*
X1241673Y1250068D01*
X1241672Y1250071D01*
X1234314Y1253113D01*
X1222045Y1256525D01*
X1217862Y1260387D01*
X1215836Y1266518D01*
X1212735Y1270703D01*
X1210312Y1273125D01*
Y1273126D01*
X1207881Y1275557D01*
X1190207Y1282876D01*
X1187320Y1285763D01*
Y1288653D01*
X1179786Y1296187D01*
X1118497D01*
X1091792Y1307248D01*
X1043473Y1355567D01*
Y1436637D01*
X1032168Y1447942D01*
X991065D01*
X989853Y1446730D01*
Y1433022D01*
X989273Y1432442D01*
X986953D01*
X986373Y1433022D01*
Y1446730D01*
X985161Y1447942D01*
X981945D01*
X980733Y1446730D01*
Y1433022D01*
X980153Y1432442D01*
X977833D01*
X977253Y1433022D01*
Y1446730D01*
X976041Y1447942D01*
X972136D01*
X835875Y1471963D01*
X783614Y1462747D01*
X783612D01*
X627124Y1490335D01*
X495729D01*
X387926Y1474343D01*
X312779Y1443216D01*
X291126Y1421563D01*
X277967Y1389793D01*
Y1319540D01*
X280475Y1294078D01*
X282045Y1288397D01*
X288757Y1274207D01*
X318840Y1244123D01*
X349443Y1219009D01*
X349442D01*
X380002Y1193929D01*
X385695Y1186255D01*
X394704Y1164509D01*
Y1162689D01*
G01X1332474Y1145504D02*
X1324033Y1153945D01*
X1324042Y1153954D01*
X1317317Y1164013D01*
X1310339Y1187010D01*
X1241324Y1256025D01*
X1224179Y1263126D01*
X1219790Y1266826D01*
X1216906Y1271400D01*
X1210980Y1277624D01*
X1206320Y1280887D01*
X1205004Y1282767D01*
X1205003Y1282768D01*
X1203688Y1284647D01*
X1202740Y1290017D01*
X1200872Y1292344D01*
X1193736Y1299480D01*
X1119138D01*
X1093772Y1309986D01*
X1047785Y1355973D01*
Y1437605D01*
X1032958Y1452432D01*
X1007121Y1456987D01*
X1005717Y1456002D01*
X1004995Y1451907D01*
X1004325Y1451438D01*
X1002034Y1451842D01*
X1001565Y1452512D01*
X1002288Y1456608D01*
X1001303Y1458011D01*
X998136Y1458572D01*
X996731Y1457587D01*
X996009Y1453492D01*
X995339Y1453023D01*
X993048Y1453427D01*
X992579Y1454097D01*
X993302Y1458193D01*
X992317Y1459596D01*
X989150Y1460157D01*
X987745Y1459172D01*
X987023Y1455077D01*
X986353Y1454608D01*
X984062Y1455012D01*
X983593Y1455682D01*
X984316Y1459778D01*
X983331Y1461182D01*
X977767Y1462163D01*
X944094Y1456227D01*
X835875Y1475302D01*
X783612Y1466086D01*
X627413Y1493622D01*
X495308D01*
X386939Y1477534D01*
X308892Y1445206D01*
X289214Y1425528D01*
X274697Y1390482D01*
Y1318898D01*
X277194Y1293531D01*
X278946Y1287200D01*
X285948Y1272395D01*
X316695Y1241648D01*
X377606Y1191659D01*
X382614Y1184906D01*
X391259Y1164037D01*
Y1154369D01*
G01X1323580Y1142992D02*
X1321060Y1145512D01*
X1321056D01*
X1317273Y1149295D01*
X1310909Y1158808D01*
X1303569Y1182999D01*
X1244700Y1241868D01*
X1236351D01*
X1234440Y1242660D01*
X1231309Y1245792D01*
Y1245842D01*
X1230083Y1247068D01*
X1218877Y1251709D01*
X1210581Y1259436D01*
X1208591Y1260219D01*
X1207266Y1261452D01*
X1203802Y1268383D01*
X1191774Y1276803D01*
X1187578Y1278542D01*
X1179773Y1286347D01*
Y1288112D01*
X1176038Y1291847D01*
X1117549D01*
X1089323Y1303539D01*
X1027077Y1365785D01*
Y1367501D01*
X1037655Y1378079D01*
Y1378897D01*
X1036010Y1380542D01*
X1035192D01*
X1024614Y1369964D01*
X1022898D01*
X1020625Y1372237D01*
Y1373953D01*
X1033954Y1387282D01*
Y1388100D01*
X1032309Y1389745D01*
X1031491D01*
X1018162Y1376416D01*
X1016446D01*
X1014173Y1378689D01*
Y1380405D01*
X1024751Y1390983D01*
Y1391801D01*
X1023106Y1393446D01*
X1022288D01*
X1011710Y1382868D01*
X1009994D01*
X1005919Y1386941D01*
X1005918Y1386942D01*
X979726Y1424353D01*
X945772Y1448127D01*
X835874Y1467500D01*
X783623Y1458286D01*
X626738Y1485945D01*
X496056D01*
X388954Y1470057D01*
X315426Y1439602D01*
X295810Y1419979D01*
X294028Y1415683D01*
X294287Y1415055D01*
X293628Y1413466D01*
X293000Y1413206D01*
X292248Y1411391D01*
X292507Y1410764D01*
X291848Y1409174D01*
X291220Y1408915D01*
X290561Y1407327D01*
X290821Y1406699D01*
X290162Y1405110D01*
X289534Y1404850D01*
X288875Y1403262D01*
X289135Y1402634D01*
X288476Y1401045D01*
X287847Y1400785D01*
X287188Y1399197D01*
X287448Y1398569D01*
X286789Y1396980D01*
X286161Y1396720D01*
X282337Y1387502D01*
Y1319514D01*
X284401Y1298553D01*
X287534Y1287237D01*
X292579Y1276564D01*
X321958Y1247183D01*
X345771Y1227640D01*
X346446Y1227707D01*
X347761Y1226628D01*
X347828Y1225952D01*
X347829Y1225953D01*
X352900Y1221791D01*
X353703Y1221870D01*
X354825Y1220949D01*
X354904Y1220147D01*
X356385Y1218932D01*
X357187Y1219011D01*
X358309Y1218090D01*
X358388Y1217288D01*
X363932Y1212738D01*
X364734Y1212817D01*
X365856Y1211896D01*
X365935Y1211094D01*
X368016Y1209386D01*
X368818Y1209465D01*
X369940Y1208545D01*
X370019Y1207742D01*
X371844Y1206245D01*
X372646Y1206324D01*
X373768Y1205403D01*
X373847Y1204601D01*
X375860Y1202949D01*
X376662Y1203028D01*
X377784Y1202107D01*
X377863Y1201305D01*
X384302Y1196021D01*
X402300Y1171755D01*
X402734Y1170706D01*
Y1155549D01*
G01X1319080Y1143756D02*
X1315424Y1147412D01*
X1309264Y1156622D01*
X1301607Y1181863D01*
X1248175Y1235294D01*
Y1235295D01*
X1247859Y1235610D01*
X1236197D01*
X1229733Y1242074D01*
X1226658D01*
X1223131Y1245601D01*
X1219532D01*
X1212531Y1252602D01*
X1206499D01*
X1204965Y1254136D01*
X1204137Y1255756D01*
Y1262211D01*
X1202710Y1265655D01*
X1200810Y1267555D01*
X1194912Y1271835D01*
Y1271834D01*
X1190883Y1274759D01*
X1170617Y1283158D01*
X1153015D01*
X1152435Y1283738D01*
Y1288150D01*
X1151223Y1289362D01*
X1148007D01*
X1146795Y1288150D01*
Y1283738D01*
X1146215Y1283158D01*
X1132146D01*
X1087113Y1301812D01*
X1075316Y1313609D01*
X1073600D01*
X1071710Y1311719D01*
X1070893D01*
X1069248Y1313364D01*
Y1314183D01*
X1071137Y1316072D01*
Y1317788D01*
X1068864Y1320061D01*
X1067148D01*
X1065258Y1318171D01*
X1064441D01*
X1062796Y1319816D01*
Y1320635D01*
X1064685Y1322524D01*
Y1324240D01*
X1062412Y1326513D01*
X1060696D01*
X1058806Y1324623D01*
X1057989D01*
X1056344Y1326268D01*
Y1327087D01*
X1058233Y1328976D01*
Y1330692D01*
X1055960Y1332965D01*
X1054244D01*
X1052354Y1331075D01*
X1051537D01*
X1049892Y1332720D01*
Y1333539D01*
X1051781Y1335428D01*
Y1337144D01*
X1049508Y1339417D01*
X1047792D01*
X1045902Y1337527D01*
X1045085D01*
X1043440Y1339172D01*
Y1339991D01*
X1045329Y1341880D01*
Y1343596D01*
X1003109Y1385817D01*
X999267Y1391305D01*
X997578Y1391604D01*
X993853Y1388996D01*
X993048Y1389138D01*
X991714Y1391043D01*
X991856Y1391848D01*
X995580Y1394456D01*
X995879Y1396144D01*
X994032Y1398779D01*
X992344Y1399078D01*
X988619Y1396470D01*
X987814Y1396612D01*
X986480Y1398517D01*
X986622Y1399322D01*
X990346Y1401930D01*
X990645Y1403618D01*
X988798Y1406253D01*
X987110Y1406552D01*
X983385Y1403944D01*
X982580Y1404086D01*
X981246Y1405991D01*
X981388Y1406796D01*
X985112Y1409404D01*
X985411Y1411092D01*
X983564Y1413727D01*
X981876Y1414026D01*
X978151Y1411418D01*
X977346Y1411560D01*
X976012Y1413465D01*
X976154Y1414270D01*
X979878Y1416878D01*
X980177Y1418567D01*
X978220Y1421362D01*
X973436Y1424712D01*
X971747Y1424413D01*
X968437Y1419687D01*
X967632Y1419545D01*
X965727Y1420879D01*
X965585Y1421684D01*
X968895Y1426411D01*
X968596Y1428099D01*
X965961Y1429946D01*
X964273Y1429647D01*
X960963Y1424921D01*
X960158Y1424779D01*
X958253Y1426113D01*
X958111Y1426918D01*
X961421Y1431645D01*
X961122Y1433333D01*
X958487Y1435180D01*
X956799Y1434881D01*
X953489Y1430155D01*
X952684Y1430013D01*
X950779Y1431347D01*
X950637Y1432152D01*
X953947Y1436879D01*
X953648Y1438567D01*
X951013Y1440414D01*
X949325Y1440115D01*
X946015Y1435389D01*
X945210Y1435247D01*
X943305Y1436581D01*
X943163Y1437386D01*
X946473Y1442113D01*
X946174Y1443802D01*
X942570Y1446325D01*
X836062Y1465165D01*
Y1465166D01*
X835875Y1465198D01*
X783612Y1455982D01*
X626539Y1483675D01*
X495855D01*
X389577Y1467911D01*
X316612Y1437684D01*
X298596Y1419668D01*
X284547Y1385789D01*
Y1319516D01*
X286580Y1298858D01*
X289528Y1288212D01*
X294464Y1277772D01*
X316280Y1255956D01*
X380552Y1203211D01*
X385731Y1197772D01*
X404321Y1172708D01*
X404956Y1171177D01*
Y1152618D01*
X405471Y1151375D01*
X406642Y1150204D01*
X406646D01*
X408163Y1148687D01*
G01X1328543Y1142992D02*
X1326953Y1144582D01*
X1326949D01*
X1319851Y1151680D01*
X1313688Y1160894D01*
X1306449Y1184745D01*
X1242734Y1248460D01*
X1240887Y1249224D01*
X1240886Y1249226D01*
X1233961Y1252089D01*
X1232212Y1252575D01*
X1231510Y1252179D01*
X1230112Y1252567D01*
X1229716Y1253270D01*
X1221504Y1255554D01*
X1219978Y1256963D01*
X1219172Y1256931D01*
X1218106Y1257916D01*
X1218074Y1258721D01*
X1216924Y1259783D01*
X1214865Y1266014D01*
X1211914Y1269995D01*
X1209232Y1272677D01*
Y1272678D01*
X1207269Y1274641D01*
X1189595Y1281960D01*
X1186240Y1285315D01*
Y1288205D01*
X1184858Y1289587D01*
X1184052D01*
X1183025Y1290614D01*
Y1291420D01*
X1179338Y1295107D01*
X1118282D01*
X1091180Y1306332D01*
X1042393Y1355119D01*
Y1436189D01*
X1031720Y1446862D01*
X991513D01*
X990933Y1446282D01*
Y1432574D01*
X989721Y1431362D01*
X986505D01*
X985293Y1432574D01*
Y1446282D01*
X984713Y1446862D01*
X982393D01*
X981813Y1446282D01*
Y1432574D01*
X980601Y1431362D01*
X977385D01*
X976173Y1432574D01*
Y1446282D01*
X975593Y1446862D01*
X972041D01*
X835875Y1470866D01*
X783612Y1461650D01*
X627029Y1489255D01*
X495809D01*
X388216Y1473294D01*
X313391Y1442300D01*
X292042Y1420951D01*
X282879Y1398829D01*
X283188Y1398084D01*
X282633Y1396744D01*
X281887Y1396435D01*
X281333Y1395096D01*
X281641Y1394351D01*
X281086Y1393011D01*
X280341Y1392702D01*
X279047Y1389578D01*
Y1319594D01*
X281541Y1294276D01*
X281985Y1292669D01*
X282687Y1292272D01*
X283074Y1290873D01*
X282676Y1290172D01*
X283062Y1288775D01*
Y1288774D01*
X289654Y1274839D01*
X319567Y1244925D01*
X380791Y1194680D01*
X386643Y1186792D01*
X387557Y1184585D01*
X387583Y1184524D01*
X388137Y1183185D01*
X388883Y1182876D01*
X389438Y1181536D01*
X389129Y1180791D01*
X389683Y1179452D01*
X390429Y1179143D01*
X390984Y1177803D01*
X390676Y1177058D01*
X391426Y1175247D01*
X392171Y1174939D01*
X392726Y1173598D01*
X392418Y1172853D01*
X393582Y1170042D01*
X394328Y1169733D01*
X394882Y1168392D01*
X394574Y1167648D01*
X395702Y1164922D01*
X395784Y1164840D01*
Y1162689D01*
G01X1324344Y1143756D02*
X1321508Y1146592D01*
X1321504D01*
X1318112Y1149984D01*
X1311896Y1159275D01*
X1304525Y1183572D01*
X1245148Y1242948D01*
X1236567D01*
X1235052Y1243576D01*
X1232389Y1246240D01*
Y1246290D01*
X1230695Y1247984D01*
X1219471Y1252633D01*
X1211168Y1260367D01*
X1209177Y1261150D01*
X1208145Y1262110D01*
X1204646Y1269111D01*
X1192297Y1277756D01*
X1188190Y1279458D01*
X1180853Y1286795D01*
Y1288560D01*
X1176486Y1292927D01*
X1117764D01*
X1089935Y1304455D01*
X1028157Y1366233D01*
Y1367053D01*
X1038735Y1377631D01*
Y1379345D01*
X1036458Y1381622D01*
X1034744D01*
X1024166Y1371044D01*
X1023346D01*
X1021705Y1372685D01*
Y1373505D01*
X1035034Y1386834D01*
Y1388548D01*
X1032757Y1390825D01*
X1031043D01*
X1017714Y1377496D01*
X1016894D01*
X1015253Y1379137D01*
Y1379957D01*
X1025831Y1390535D01*
Y1392249D01*
X1023554Y1394526D01*
X1021840D01*
X1011262Y1383948D01*
X1010442D01*
X1006750Y1387639D01*
X980502Y1425129D01*
X946196Y1449150D01*
X835874Y1468597D01*
X783623Y1459383D01*
X626833Y1487025D01*
X495976D01*
X388664Y1471106D01*
X314814Y1440518D01*
X294894Y1420591D01*
X281257Y1387718D01*
Y1319460D01*
X283335Y1298355D01*
X286518Y1286859D01*
X291682Y1275932D01*
X321231Y1246381D01*
X383513Y1195270D01*
X401352Y1171218D01*
X401654Y1170491D01*
Y1155549D01*
G01X1309094Y1150710D02*
X1309093D01*
X1306392Y1154739D01*
X1298677Y1180168D01*
X1248713Y1230132D01*
X1236593D01*
X1233566Y1231386D01*
X1229687Y1235265D01*
X1225157Y1237142D01*
X1225154Y1237143D01*
X1220957Y1238882D01*
X1211800D01*
X1208875Y1241808D01*
X1205395Y1243720D01*
X1199095Y1248223D01*
X1196825Y1250289D01*
X1196173Y1251557D01*
X1195650Y1256015D01*
X1191479Y1266851D01*
X1184858Y1273472D01*
X1169477Y1279842D01*
X1131352D01*
X1122952Y1283321D01*
X1100796D01*
X1095696Y1288421D01*
Y1289241D01*
X1096526Y1290071D01*
Y1291785D01*
X1094249Y1294062D01*
X1092535D01*
X1091705Y1293232D01*
X1090885D01*
X1079405Y1304712D01*
X1072644D01*
X1035835Y1341521D01*
Y1342341D01*
X1037914Y1344420D01*
Y1346134D01*
X1035637Y1348411D01*
X1033923D01*
X1031844Y1346332D01*
X1031024D01*
X1029383Y1347973D01*
Y1348793D01*
X1031462Y1350872D01*
Y1352586D01*
X1029185Y1354863D01*
X1027471D01*
X1025392Y1352784D01*
X1024572D01*
X1022931Y1354425D01*
Y1355245D01*
X1025010Y1357324D01*
Y1359038D01*
X1022733Y1361315D01*
X1021019D01*
X1018940Y1359236D01*
X1018120D01*
X1016479Y1360877D01*
Y1361697D01*
X1018558Y1363776D01*
Y1365490D01*
X1016281Y1367767D01*
X1014567D01*
X1012488Y1365688D01*
X1011668D01*
X1010027Y1367329D01*
Y1368149D01*
X1012106Y1370228D01*
Y1371942D01*
X1009829Y1374219D01*
X1008115D01*
X1006036Y1372140D01*
X1005216D01*
X1003575Y1373781D01*
Y1374601D01*
X1005654Y1376680D01*
Y1378394D01*
X1003377Y1380671D01*
X1001663D01*
X999584Y1378592D01*
X998764D01*
X981628Y1395728D01*
Y1396548D01*
X982666Y1397586D01*
Y1399300D01*
X980389Y1401577D01*
X978675D01*
X977637Y1400539D01*
X976817D01*
X974322Y1403034D01*
Y1403854D01*
X976480Y1406012D01*
Y1407726D01*
X974203Y1410003D01*
X972489D01*
X970331Y1407845D01*
X969511D01*
X967870Y1409486D01*
Y1410306D01*
X969230Y1411666D01*
Y1413380D01*
X966953Y1415657D01*
X965239D01*
X963879Y1414297D01*
X963059D01*
X949182Y1428173D01*
X946139Y1430304D01*
X944450Y1430005D01*
X940366Y1424173D01*
X939560Y1424031D01*
X937655Y1425365D01*
X937513Y1426170D01*
X941598Y1432003D01*
X941299Y1433691D01*
X938665Y1435538D01*
X936976Y1435239D01*
X932892Y1429407D01*
X932086Y1429265D01*
X930181Y1430599D01*
X930039Y1431404D01*
X936723Y1440948D01*
X936424Y1442636D01*
X933790Y1444483D01*
X932101Y1444184D01*
X925418Y1434641D01*
X924612Y1434499D01*
X922707Y1435833D01*
X922565Y1436638D01*
X926650Y1442471D01*
X926351Y1444160D01*
X923114Y1446427D01*
X919626Y1447042D01*
X918222Y1446057D01*
X917473Y1441801D01*
X916803Y1441332D01*
X914512Y1441736D01*
X914043Y1442406D01*
X914793Y1446663D01*
X913808Y1448067D01*
X835871Y1461806D01*
X783695Y1452605D01*
X626248Y1480365D01*
X496139D01*
X390741Y1464725D01*
X318787Y1434921D01*
X301156Y1417294D01*
X287807Y1385102D01*
Y1319688D01*
X289776Y1299704D01*
X292582Y1289551D01*
X297321Y1279535D01*
X318504Y1258352D01*
X384917Y1203848D01*
X405767Y1179070D01*
X412330Y1170221D01*
Y1151432D01*
X412331Y1151431D01*
Y1150209D01*
G01X1318316Y1142992D02*
X1314585Y1146723D01*
X1308277Y1156155D01*
X1300651Y1181290D01*
X1247411Y1234530D01*
X1245335D01*
X1244765Y1233960D01*
X1243315D01*
X1242745Y1234530D01*
X1235749D01*
X1234300Y1235979D01*
X1233494D01*
X1232467Y1237006D01*
Y1237812D01*
X1229285Y1240994D01*
X1226210D01*
X1222683Y1244521D01*
X1219084D01*
X1216343Y1247262D01*
X1215537D01*
X1214510Y1248289D01*
Y1249095D01*
X1212083Y1251522D01*
X1206051D01*
X1204080Y1253492D01*
X1203057Y1255495D01*
Y1257956D01*
X1202487Y1258526D01*
Y1259976D01*
X1203057Y1260546D01*
Y1261996D01*
X1201794Y1265043D01*
X1200106Y1266730D01*
X1196375Y1269438D01*
X1195578Y1269311D01*
X1194404Y1270163D01*
X1194277Y1270960D01*
X1190351Y1273809D01*
X1170402Y1282078D01*
X1152567D01*
X1151355Y1283290D01*
Y1287702D01*
X1150775Y1288282D01*
X1148455D01*
X1147875Y1287702D01*
Y1283290D01*
X1146663Y1282078D01*
X1131931D01*
X1093019Y1298196D01*
X1092275Y1297887D01*
X1090934Y1298442D01*
X1090625Y1299188D01*
X1086501Y1300896D01*
X1079896Y1307501D01*
X1079217D01*
X1077999Y1308719D01*
Y1309398D01*
X1074868Y1312529D01*
X1074048D01*
X1072158Y1310639D01*
X1070446Y1310638D01*
X1068168Y1312916D01*
X1068167Y1314630D01*
X1070057Y1316520D01*
Y1317340D01*
X1068416Y1318981D01*
X1067596D01*
X1065706Y1317091D01*
X1063994Y1317090D01*
X1061716Y1319368D01*
X1061715Y1321082D01*
X1063605Y1322972D01*
Y1323792D01*
X1061964Y1325433D01*
X1061144D01*
X1059254Y1323543D01*
X1057542Y1323542D01*
X1055264Y1325820D01*
X1055263Y1327534D01*
X1057153Y1329424D01*
Y1330244D01*
X1055512Y1331885D01*
X1054692D01*
X1052802Y1329995D01*
X1051090Y1329994D01*
X1048812Y1332272D01*
X1048811Y1333986D01*
X1050701Y1335876D01*
Y1336696D01*
X1049060Y1338337D01*
X1048240D01*
X1046350Y1336447D01*
X1044638Y1336446D01*
X1042360Y1338724D01*
X1042359Y1340438D01*
X1044249Y1342328D01*
Y1343148D01*
X1002278Y1385120D01*
X998638Y1390319D01*
X997831Y1390462D01*
X994106Y1387854D01*
X992419Y1388151D01*
X990572Y1390790D01*
X990869Y1392477D01*
X994594Y1395085D01*
X994737Y1395891D01*
X993404Y1397793D01*
X992597Y1397936D01*
X988872Y1395328D01*
X987185Y1395625D01*
X985338Y1398264D01*
X985635Y1399951D01*
X989360Y1402559D01*
X989503Y1403365D01*
X988170Y1405267D01*
X987363Y1405410D01*
X983638Y1402802D01*
X981951Y1403099D01*
X980104Y1405738D01*
X980401Y1407425D01*
X984126Y1410033D01*
X984269Y1410839D01*
X982936Y1412741D01*
X982129Y1412884D01*
X978404Y1410276D01*
X976717Y1410573D01*
X974870Y1413212D01*
X975167Y1414899D01*
X978892Y1417507D01*
X979035Y1418314D01*
X977444Y1420586D01*
X973183Y1423570D01*
X972376Y1423427D01*
X969066Y1418700D01*
X967379Y1418403D01*
X964740Y1420250D01*
X964443Y1421937D01*
X967753Y1426664D01*
X967610Y1427471D01*
X965708Y1428804D01*
X964902Y1428661D01*
X961592Y1423934D01*
X959905Y1423637D01*
X957266Y1425484D01*
X956969Y1427171D01*
X960279Y1431898D01*
X960136Y1432705D01*
X958234Y1434038D01*
X957428Y1433895D01*
X954118Y1429168D01*
X952431Y1428871D01*
X949792Y1430718D01*
X949495Y1432405D01*
X952805Y1437132D01*
X952662Y1437939D01*
X950760Y1439272D01*
X949954Y1439129D01*
X946644Y1434402D01*
X944957Y1434105D01*
X942318Y1435952D01*
X942021Y1437639D01*
X945331Y1442366D01*
X945188Y1443173D01*
X942146Y1445303D01*
X835875Y1464101D01*
X783612Y1454885D01*
X626444Y1482595D01*
X495935D01*
X389867Y1466862D01*
X317224Y1436768D01*
X299512Y1419056D01*
X285627Y1385573D01*
Y1319570D01*
X287646Y1299056D01*
X290544Y1288590D01*
X295361Y1278404D01*
X317007Y1256758D01*
X381237Y1204046D01*
X381238Y1204047D01*
X381289Y1204005D01*
X386513Y1198517D01*
Y1198518D01*
X386559Y1198469D01*
X405268Y1173245D01*
X406036Y1171392D01*
Y1166537D01*
X406606Y1165967D01*
Y1164517D01*
X406036Y1163947D01*
Y1159787D01*
X406606Y1159217D01*
Y1157767D01*
X406036Y1157197D01*
Y1152833D01*
X406387Y1151987D01*
X407090Y1151284D01*
X407094D01*
X408332Y1150046D01*
Y1150042D01*
X408336D01*
X408927Y1149451D01*
G01X1308198Y1150105D02*
X1305404Y1154271D01*
X1297721Y1179595D01*
X1248265Y1229052D01*
X1236378D01*
X1232954Y1230470D01*
X1229075Y1234349D01*
X1224743Y1236144D01*
X1224740Y1236145D01*
X1220742Y1237802D01*
X1217455D01*
X1216885Y1237232D01*
X1215435D01*
X1214865Y1237802D01*
X1211352D01*
X1208219Y1240935D01*
X1204819Y1242804D01*
X1203105Y1244029D01*
X1202310Y1243896D01*
X1201130Y1244739D01*
X1200997Y1245535D01*
X1198415Y1247381D01*
X1195953Y1249621D01*
X1195123Y1251237D01*
X1194593Y1255754D01*
X1190553Y1266249D01*
X1184246Y1272556D01*
X1169262Y1278762D01*
X1131137D01*
X1122737Y1282241D01*
X1100348D01*
X1098035Y1284554D01*
X1097229D01*
X1096202Y1285581D01*
Y1286387D01*
X1094616Y1287973D01*
Y1289689D01*
X1095446Y1290519D01*
Y1291337D01*
X1093801Y1292982D01*
X1092983D01*
X1092153Y1292152D01*
X1090437D01*
X1078957Y1303632D01*
X1072196D01*
X1034755Y1341073D01*
Y1342789D01*
X1036834Y1344868D01*
Y1345686D01*
X1035189Y1347331D01*
X1034371D01*
X1032292Y1345252D01*
X1030576D01*
X1028303Y1347525D01*
Y1349241D01*
X1030382Y1351320D01*
Y1352138D01*
X1028737Y1353783D01*
X1027919D01*
X1025840Y1351704D01*
X1024124D01*
X1021851Y1353977D01*
Y1355693D01*
X1023930Y1357772D01*
Y1358590D01*
X1022285Y1360235D01*
X1021467D01*
X1019388Y1358156D01*
X1017672D01*
X1015399Y1360429D01*
Y1362145D01*
X1017478Y1364224D01*
Y1365042D01*
X1015833Y1366687D01*
X1015015D01*
X1012936Y1364608D01*
X1011220D01*
X1008947Y1366881D01*
Y1368597D01*
X1011026Y1370676D01*
Y1371494D01*
X1009381Y1373139D01*
X1008563D01*
X1006484Y1371060D01*
X1004768D01*
X1002495Y1373333D01*
Y1375049D01*
X1004574Y1377128D01*
Y1377946D01*
X1002929Y1379591D01*
X1002111D01*
X1000032Y1377512D01*
X998316D01*
X980548Y1395280D01*
Y1396996D01*
X981586Y1398034D01*
Y1398852D01*
X979941Y1400497D01*
X979123D01*
X978085Y1399459D01*
X976369D01*
X973242Y1402586D01*
Y1404302D01*
X975400Y1406460D01*
Y1407278D01*
X973755Y1408923D01*
X972937D01*
X970779Y1406765D01*
X969063D01*
X966790Y1409038D01*
Y1410754D01*
X968150Y1412114D01*
Y1412932D01*
X966505Y1414577D01*
X965687D01*
X964327Y1413217D01*
X962611D01*
X948484Y1427342D01*
X945886Y1429162D01*
X945079Y1429019D01*
X940994Y1423186D01*
X939307Y1422889D01*
X936668Y1424736D01*
X936371Y1426423D01*
X940456Y1432256D01*
X940313Y1433063D01*
X938412Y1434396D01*
X937605Y1434253D01*
X933520Y1428420D01*
X931833Y1428123D01*
X929195Y1429971D01*
X928897Y1431657D01*
X935581Y1441201D01*
X935438Y1442008D01*
X933537Y1443341D01*
X932729Y1443198D01*
X926046Y1433655D01*
X924799Y1433435D01*
Y1433434D01*
X924359Y1433357D01*
X921720Y1435204D01*
X921423Y1436891D01*
X925508Y1442724D01*
X925365Y1443531D01*
X922690Y1445404D01*
X919880Y1445900D01*
X919209Y1445429D01*
X918459Y1441173D01*
X917056Y1440190D01*
X913884Y1440750D01*
X912901Y1442153D01*
X913651Y1446409D01*
X913180Y1447080D01*
X835871Y1460709D01*
X783695Y1451508D01*
X626153Y1479285D01*
X496219D01*
X391031Y1463675D01*
Y1463676D01*
X319399Y1434005D01*
X302072Y1416681D01*
X288887Y1384886D01*
Y1319742D01*
X290842Y1299902D01*
X293599Y1289929D01*
X298218Y1280167D01*
X319231Y1259154D01*
X385602Y1204683D01*
Y1204684D01*
X385679Y1204620D01*
X406615Y1179740D01*
X413410Y1170578D01*
Y1151432D01*
X413411Y1151431D01*
Y1150209D01*
G01X286024Y1686180D02*
Y1684939D01*
X285443Y1684358D01*
X283464D01*
X282252Y1683146D01*
Y1642232D01*
X279777Y1617201D01*
Y1615452D01*
X278617Y1614292D01*
G01X286024Y1681456D02*
Y1682355D01*
X285101Y1683278D01*
X283912D01*
X283332Y1682698D01*
Y1642178D01*
X282767Y1636455D01*
X283207Y1635919D01*
X283037Y1634207D01*
X282501Y1633767D01*
X282332Y1632056D01*
X282772Y1631520D01*
X282602Y1629808D01*
X282066Y1629368D01*
X281897Y1627657D01*
X282337Y1627121D01*
X282167Y1625409D01*
X281631Y1624969D01*
X281462Y1623258D01*
X281901Y1622722D01*
X281732Y1621009D01*
X281195Y1620570D01*
X280857Y1617147D01*
Y1615452D01*
X282017Y1614292D01*
G01X1314555Y1136149D02*
Y1137727D01*
X1308268Y1144014D01*
X1302439Y1152736D01*
X1294811Y1177878D01*
X1248243Y1224447D01*
X1245755D01*
X1245185Y1223877D01*
X1243735D01*
X1243165Y1224447D01*
X1238191D01*
X1238169Y1224469D01*
X1236552Y1224801D01*
X1235879Y1224358D01*
X1234458Y1224650D01*
X1234014Y1225324D01*
X1232181Y1225701D01*
X1231508Y1225258D01*
X1230087Y1225551D01*
X1229644Y1226225D01*
X1224726Y1227237D01*
X1220142Y1231821D01*
X1217695D01*
X1217125Y1231251D01*
X1215675D01*
X1215105Y1231821D01*
X1210402D01*
X1206491Y1235732D01*
X1205381D01*
X1198718Y1241157D01*
X1197156Y1241944D01*
X1193562Y1245538D01*
X1189522D01*
X1187662Y1247398D01*
Y1250138D01*
X1186582Y1255847D01*
Y1259617D01*
X1186012Y1260187D01*
Y1261637D01*
X1186582Y1262207D01*
Y1265529D01*
X1182407Y1269704D01*
X1173280Y1273485D01*
X1172535Y1273177D01*
X1171195Y1273732D01*
X1170886Y1274478D01*
X1168655Y1275402D01*
X1130331D01*
X1122226Y1278759D01*
X1098654D01*
X1096830Y1280583D01*
X1071536D01*
X1066691Y1285428D01*
Y1304034D01*
X1061402Y1309323D01*
X1060582D01*
X1057513Y1306254D01*
X1055799D01*
X1053522Y1308531D01*
Y1310245D01*
X1056591Y1313314D01*
Y1314134D01*
X1054950Y1315775D01*
X1054130D01*
X1051061Y1312706D01*
X1049347D01*
X1047070Y1314983D01*
Y1316697D01*
X1050139Y1319766D01*
Y1320586D01*
X1048498Y1322227D01*
X1047678D01*
X1044609Y1319158D01*
X1042895D01*
X1040618Y1321435D01*
Y1323149D01*
X1043687Y1326218D01*
Y1327038D01*
X1042046Y1328679D01*
X1041226D01*
X1038157Y1325610D01*
X1036443D01*
X1034166Y1327887D01*
Y1329601D01*
X1037235Y1332670D01*
Y1333490D01*
X1035594Y1335131D01*
X1034774D01*
X1031705Y1332062D01*
X1029991D01*
X1027714Y1334339D01*
Y1336053D01*
X1030783Y1339122D01*
Y1339942D01*
X1029142Y1341583D01*
X1028322D01*
X1025253Y1338514D01*
X1023539D01*
X1021262Y1340791D01*
Y1342505D01*
X1024331Y1345574D01*
Y1346394D01*
X1022690Y1348035D01*
X1021870D01*
X1018801Y1344966D01*
X1017087D01*
X1014810Y1347243D01*
Y1348957D01*
X1017879Y1352026D01*
Y1352846D01*
X1016238Y1354487D01*
X1015418D01*
X1012349Y1351418D01*
X1010635D01*
X1008358Y1353695D01*
Y1355409D01*
X1011427Y1358478D01*
Y1359298D01*
X1009786Y1360939D01*
X1008966D01*
X1005897Y1357870D01*
X1004183D01*
X1001906Y1360147D01*
Y1361861D01*
X1004975Y1364930D01*
Y1365750D01*
X1003334Y1367391D01*
X1002514D01*
X999445Y1364322D01*
X997731D01*
X995454Y1366599D01*
Y1368313D01*
X998523Y1371382D01*
Y1372202D01*
X996882Y1373843D01*
X996062D01*
X992993Y1370774D01*
X991279D01*
X989002Y1373051D01*
Y1374765D01*
X992071Y1377834D01*
Y1378654D01*
X989519Y1381206D01*
X988699D01*
X987910Y1380417D01*
X986196D01*
X983919Y1382694D01*
Y1384408D01*
X984708Y1385197D01*
Y1386017D01*
X983067Y1387658D01*
X982247D01*
X981458Y1386869D01*
X979744D01*
X977467Y1389146D01*
Y1390860D01*
X978256Y1391649D01*
Y1392469D01*
X975863Y1394862D01*
X973504D01*
X963306Y1402004D01*
X963007Y1403693D01*
X964240Y1405454D01*
X964098Y1406259D01*
X962193Y1407594D01*
X961388Y1407452D01*
X960155Y1405692D01*
X958466Y1405393D01*
X953561Y1408828D01*
X953262Y1410517D01*
X955404Y1413575D01*
X955262Y1414380D01*
X953357Y1415715D01*
X952551Y1415573D01*
X950410Y1412516D01*
X948722Y1412217D01*
X946087Y1414064D01*
X945788Y1415752D01*
X947930Y1418810D01*
X947788Y1419615D01*
X945883Y1420950D01*
X945077Y1420808D01*
X942936Y1417751D01*
X941247Y1417452D01*
X900510Y1445982D01*
X837633Y1457068D01*
X785369Y1447852D01*
X625862Y1475976D01*
X496838D01*
X395948Y1461010D01*
X319389Y1429295D01*
X304822Y1414729D01*
X292177Y1384237D01*
Y1319770D01*
X294071Y1300547D01*
X296634Y1291287D01*
X301040Y1281974D01*
X321476Y1261538D01*
X388279Y1206724D01*
Y1206725D01*
X388356Y1206661D01*
X409044Y1182078D01*
X416181Y1172458D01*
X416680Y1171250D01*
Y1166652D01*
X417250Y1166082D01*
Y1164632D01*
X416680Y1164062D01*
Y1150477D01*
G01X1310751Y1135659D02*
Y1136503D01*
X1306087Y1141167D01*
X1299501Y1151018D01*
X1295679Y1163613D01*
Y1163614D01*
X1291858Y1176206D01*
X1250640Y1217424D01*
X1237212D01*
X1237207Y1217429D01*
X1234027Y1217743D01*
X1233404Y1217232D01*
X1231960Y1217375D01*
X1231449Y1217999D01*
X1226871Y1218452D01*
Y1218453D01*
X1224875Y1219427D01*
X1224112Y1219165D01*
X1222808Y1219801D01*
X1222546Y1220564D01*
X1219800Y1221904D01*
X1215987Y1225448D01*
X1211085Y1227761D01*
X1208227Y1228141D01*
X1206489Y1229006D01*
X1189525Y1238971D01*
X1187434Y1241158D01*
X1184372Y1244220D01*
Y1249641D01*
X1180393Y1253620D01*
Y1255319D01*
X1175269Y1260443D01*
X1171319Y1267226D01*
X1166457Y1272088D01*
X1133965D01*
X1132058Y1270181D01*
X1126194D01*
X1124609Y1270836D01*
X1120167Y1275278D01*
X1087704D01*
X1085837Y1277145D01*
X1068954D01*
X1064594Y1281505D01*
X1041663D01*
X1035057Y1288111D01*
Y1322384D01*
X980793Y1376648D01*
Y1381206D01*
X965648Y1396351D01*
X899219Y1442866D01*
X837620Y1453729D01*
X830960Y1452557D01*
X830489Y1451886D01*
X830697Y1450711D01*
X829714Y1449308D01*
X826542Y1448747D01*
X825139Y1449730D01*
X824931Y1450905D01*
X824260Y1451376D01*
X821974Y1450971D01*
X821503Y1450300D01*
X821711Y1449125D01*
X820728Y1447722D01*
X817556Y1447161D01*
X816153Y1448144D01*
X815945Y1449319D01*
X815274Y1449790D01*
X812988Y1449385D01*
X812517Y1448714D01*
X812725Y1447539D01*
X811742Y1446136D01*
X808570Y1445575D01*
X807167Y1446558D01*
X806959Y1447733D01*
X806288Y1448204D01*
X804002Y1447799D01*
X803531Y1447128D01*
X803739Y1445953D01*
X802756Y1444550D01*
X799584Y1443989D01*
X798181Y1444972D01*
X797973Y1446147D01*
X797302Y1446618D01*
X795016Y1446213D01*
X794545Y1445542D01*
X794753Y1444367D01*
X793770Y1442964D01*
X790598Y1442403D01*
X789195Y1443386D01*
X788987Y1444561D01*
X788316Y1445032D01*
X785379Y1444513D01*
X780049Y1445441D01*
X779377Y1444968D01*
X778978Y1442710D01*
X777575Y1441727D01*
X774403Y1442287D01*
X773420Y1443690D01*
X773819Y1445949D01*
X773348Y1446621D01*
X771063Y1447026D01*
X770391Y1446554D01*
X769992Y1444295D01*
X768589Y1443312D01*
X765417Y1443872D01*
X764434Y1445275D01*
X764833Y1447534D01*
X764362Y1448205D01*
X762075Y1448610D01*
X761405Y1448139D01*
X761006Y1445880D01*
X759603Y1444897D01*
X756431Y1445457D01*
X755448Y1446860D01*
X755847Y1449119D01*
X755377Y1449789D01*
X753088Y1450195D01*
X752419Y1449724D01*
X752020Y1447465D01*
X750617Y1446482D01*
X747445Y1447042D01*
X746462Y1448445D01*
X746861Y1450704D01*
X746386Y1451381D01*
X744110Y1451784D01*
X743433Y1451309D01*
X743034Y1449050D01*
X741631Y1448067D01*
X738459Y1448627D01*
X737476Y1450030D01*
X737875Y1452289D01*
X737404Y1452960D01*
X735118Y1453365D01*
X734447Y1452894D01*
X734048Y1450635D01*
X732645Y1449652D01*
X729473Y1450212D01*
X728490Y1451615D01*
X728889Y1453874D01*
X728418Y1454545D01*
X726132Y1454950D01*
X725461Y1454479D01*
X725062Y1452220D01*
X723659Y1451237D01*
X720487Y1451797D01*
X719504Y1453200D01*
X719903Y1455459D01*
X719432Y1456130D01*
X717146Y1456535D01*
X716475Y1456064D01*
X716076Y1453805D01*
X714673Y1452822D01*
X711501Y1453382D01*
X710518Y1454785D01*
X710917Y1457044D01*
X710446Y1457715D01*
X708160Y1458120D01*
X707489Y1457649D01*
X707090Y1455390D01*
X705687Y1454407D01*
X702515Y1454967D01*
X701532Y1456370D01*
X701931Y1458629D01*
X701460Y1459300D01*
X699174Y1459705D01*
X698503Y1459234D01*
X698104Y1456975D01*
X696701Y1455992D01*
X693529Y1456552D01*
X692546Y1457955D01*
X692945Y1460214D01*
X692474Y1460885D01*
X690188Y1461290D01*
X689517Y1460819D01*
X689118Y1458560D01*
X687715Y1457577D01*
X684543Y1458137D01*
X683560Y1459540D01*
X683959Y1461799D01*
X683488Y1462470D01*
X681202Y1462875D01*
X680531Y1462404D01*
X680132Y1460145D01*
X678729Y1459162D01*
X675557Y1459722D01*
X674574Y1461125D01*
X674973Y1463384D01*
X674502Y1464055D01*
X672216Y1464460D01*
X671545Y1463989D01*
X671146Y1461730D01*
X669743Y1460747D01*
X666571Y1461307D01*
X665588Y1462710D01*
X665987Y1464969D01*
X665516Y1465640D01*
X663230Y1466045D01*
X662559Y1465574D01*
X662160Y1463315D01*
X660757Y1462332D01*
X657585Y1462892D01*
X656602Y1464295D01*
X657001Y1466554D01*
X656530Y1467225D01*
X654244Y1467630D01*
X653573Y1467159D01*
X653174Y1464900D01*
X651771Y1463917D01*
X648599Y1464477D01*
X647616Y1465880D01*
X648015Y1468139D01*
X647544Y1468810D01*
X645258Y1469215D01*
X644587Y1468744D01*
X644188Y1466485D01*
X642785Y1465502D01*
X639613Y1466062D01*
X638630Y1467466D01*
X639029Y1469724D01*
X638558Y1470395D01*
X636272Y1470800D01*
X635600Y1470329D01*
X635202Y1468070D01*
X633799Y1467087D01*
X630627Y1467647D01*
X629644Y1469050D01*
X630043Y1471309D01*
X629572Y1471980D01*
X625568Y1472686D01*
X497549D01*
X396601Y1457711D01*
X321286Y1426515D01*
X307725Y1412954D01*
X305482Y1407538D01*
X305791Y1406793D01*
X305236Y1405453D01*
X304490Y1405144D01*
X302779Y1401011D01*
X303088Y1400266D01*
X302533Y1398925D01*
X301787Y1398617D01*
X300891Y1396452D01*
X301200Y1395707D01*
X300645Y1394367D01*
X299899Y1394058D01*
X299345Y1392719D01*
X299654Y1391974D01*
X299099Y1390634D01*
X298353Y1390325D01*
X298354D01*
X298353Y1390324D01*
X297799Y1388986D01*
X298108Y1388241D01*
X297553Y1386900D01*
X296808Y1386592D01*
X295467Y1383355D01*
Y1319845D01*
X297305Y1301168D01*
X299631Y1292760D01*
X303874Y1283792D01*
X323237Y1264427D01*
X344225Y1247204D01*
X345027Y1247283D01*
X346149Y1246362D01*
X346228Y1245560D01*
X390211Y1209465D01*
Y1209464D01*
X422933Y1175095D01*
X425310Y1171891D01*
X425846Y1170599D01*
Y1147614D01*
X427551Y1145909D01*
Y1143029D01*
G01X1307665Y1130629D02*
Y1131161D01*
X1307664Y1131162D01*
Y1132020D01*
X1306866Y1133945D01*
X1296547Y1149318D01*
Y1149319D01*
X1288857Y1174581D01*
X1252374Y1211064D01*
X1236456D01*
X1235731Y1211370D01*
X1227247D01*
X1221270Y1213847D01*
X1215741Y1217540D01*
X1212691Y1220590D01*
X1208007Y1223722D01*
X1188645Y1231743D01*
X1179490Y1240040D01*
X1179250Y1241278D01*
Y1249432D01*
X1177772Y1251222D01*
X1173551D01*
X1170122Y1247793D01*
X1167437D01*
X1164142Y1251088D01*
X1144895D01*
X1142962Y1253021D01*
Y1266451D01*
X1141921Y1267492D01*
X1135794D01*
X1134130Y1265828D01*
X1128139D01*
X1117733Y1270140D01*
X1078571D01*
X1077359Y1271352D01*
Y1273305D01*
X1076779Y1273885D01*
X1074459D01*
X1073879Y1273305D01*
Y1271352D01*
X1072667Y1270140D01*
X1063701D01*
X1062489Y1271352D01*
Y1277047D01*
X1061909Y1277627D01*
X1059589D01*
X1059009Y1277047D01*
Y1271352D01*
X1057797Y1270140D01*
X1045252D01*
X1030610Y1284782D01*
Y1312347D01*
X1023449Y1319508D01*
Y1321224D01*
X1027118Y1324893D01*
Y1325711D01*
X1025473Y1327356D01*
X1024655D01*
X1020986Y1323687D01*
X1019270D01*
X1016997Y1325960D01*
Y1327676D01*
X1020666Y1331345D01*
Y1332163D01*
X1019021Y1333808D01*
X1018203D01*
X1014534Y1330139D01*
X1012818D01*
X1010545Y1332412D01*
Y1334128D01*
X1014214Y1337797D01*
Y1338615D01*
X1012569Y1340260D01*
X1011751D01*
X1008082Y1336591D01*
X1006366D01*
X1004093Y1338864D01*
Y1340580D01*
X1007762Y1344249D01*
Y1345067D01*
X1006117Y1346712D01*
X1005299D01*
X1001630Y1343043D01*
X999914D01*
X997641Y1345316D01*
Y1347032D01*
X1001310Y1350701D01*
Y1351519D01*
X999665Y1353164D01*
X998847D01*
X995178Y1349495D01*
X993462D01*
X991189Y1351768D01*
Y1353484D01*
X994858Y1357153D01*
Y1357971D01*
X993213Y1359616D01*
X992395D01*
X988726Y1355947D01*
X987010D01*
X984737Y1358220D01*
Y1359936D01*
X988406Y1363605D01*
Y1364423D01*
X986761Y1366068D01*
X985943D01*
X982274Y1362399D01*
X980558D01*
X977533Y1365424D01*
Y1378858D01*
X960382Y1396008D01*
X897928Y1439742D01*
X847609Y1448615D01*
X783667Y1437341D01*
X601928Y1469386D01*
X497860D01*
X397425Y1454488D01*
X324124Y1424127D01*
X311223Y1411226D01*
X308299Y1404164D01*
X308608Y1403419D01*
X308053Y1402078D01*
X307307Y1401770D01*
X307308Y1401769D01*
X305812Y1398158D01*
X305811Y1398155D01*
X306120Y1397410D01*
X305565Y1396070D01*
X304820Y1395761D01*
X303447Y1392445D01*
X303756Y1391700D01*
X303201Y1390359D01*
X302456Y1390051D01*
X301482Y1387698D01*
X301790Y1386953D01*
X301236Y1385613D01*
X300490Y1385304D01*
X298782Y1381178D01*
Y1319519D01*
X300526Y1301796D01*
X302542Y1294530D01*
Y1294529D01*
X304665Y1290039D01*
X306787Y1285550D01*
X310021Y1282316D01*
X310827D01*
X311854Y1281289D01*
Y1280483D01*
X313711Y1278626D01*
X314517D01*
X315544Y1277599D01*
Y1276793D01*
X321608Y1270728D01*
X389603Y1214928D01*
X425366Y1177365D01*
X426135Y1176329D01*
Y1176328D01*
X428401Y1173274D01*
X429746Y1170024D01*
Y1152873D01*
X430520Y1151005D01*
Y1148222D01*
G01X1315635Y1136149D02*
Y1138175D01*
X1314688Y1139122D01*
X1309108Y1144703D01*
X1303426Y1153203D01*
X1295767Y1178451D01*
X1248691Y1225527D01*
X1238386D01*
X1225261Y1228230D01*
X1220590Y1232901D01*
X1210850D01*
X1206939Y1236812D01*
X1205766D01*
X1199309Y1242069D01*
X1197798Y1242831D01*
X1194010Y1246618D01*
X1189970D01*
X1188742Y1247846D01*
Y1250240D01*
X1187662Y1255949D01*
Y1265977D01*
X1183019Y1270620D01*
X1168870Y1276482D01*
X1130546D01*
X1122441Y1279839D01*
X1099102D01*
X1097278Y1281663D01*
X1071984D01*
X1067771Y1285876D01*
Y1304482D01*
X1061850Y1310403D01*
X1060134D01*
X1057065Y1307334D01*
X1056247D01*
X1054602Y1308979D01*
Y1309797D01*
X1057671Y1312866D01*
Y1314582D01*
X1055398Y1316855D01*
X1053682D01*
X1050613Y1313786D01*
X1049795D01*
X1048150Y1315431D01*
Y1316249D01*
X1051219Y1319318D01*
Y1321034D01*
X1048946Y1323307D01*
X1047230D01*
X1044161Y1320238D01*
X1043343D01*
X1041698Y1321883D01*
Y1322701D01*
X1044767Y1325770D01*
Y1327486D01*
X1042494Y1329759D01*
X1040778D01*
X1037709Y1326690D01*
X1036891D01*
X1035246Y1328335D01*
Y1329153D01*
X1038315Y1332222D01*
Y1333938D01*
X1036042Y1336211D01*
X1034326D01*
X1031257Y1333142D01*
X1030439D01*
X1028794Y1334787D01*
Y1335605D01*
X1031863Y1338674D01*
Y1340390D01*
X1029590Y1342663D01*
X1027874D01*
X1024805Y1339594D01*
X1023987D01*
X1022342Y1341239D01*
Y1342057D01*
X1025411Y1345126D01*
Y1346842D01*
X1023138Y1349115D01*
X1021422D01*
X1018353Y1346046D01*
X1017535D01*
X1015890Y1347691D01*
Y1348509D01*
X1018959Y1351578D01*
Y1353294D01*
X1016686Y1355567D01*
X1014970D01*
X1011901Y1352498D01*
X1011083D01*
X1009438Y1354143D01*
Y1354961D01*
X1012507Y1358030D01*
Y1359746D01*
X1010234Y1362019D01*
X1008518D01*
X1005449Y1358950D01*
X1004631D01*
X1002986Y1360595D01*
Y1361413D01*
X1006055Y1364482D01*
Y1366198D01*
X1003782Y1368471D01*
X1002066D01*
X998997Y1365402D01*
X998179D01*
X996534Y1367047D01*
Y1367865D01*
X999603Y1370934D01*
Y1372650D01*
X997330Y1374923D01*
X995614D01*
X992545Y1371854D01*
X991727D01*
X990082Y1373499D01*
Y1374317D01*
X993151Y1377386D01*
Y1379102D01*
X989967Y1382286D01*
X988251D01*
X987462Y1381497D01*
X986644D01*
X984999Y1383142D01*
Y1383960D01*
X985788Y1384749D01*
Y1386465D01*
X983515Y1388738D01*
X981799D01*
X981010Y1387949D01*
X980192D01*
X978547Y1389594D01*
Y1390412D01*
X979336Y1391201D01*
Y1392917D01*
X976311Y1395942D01*
X973845D01*
X964292Y1402633D01*
X964149Y1403440D01*
X965382Y1405201D01*
X965085Y1406888D01*
X962446Y1408736D01*
X960759Y1408439D01*
X959526Y1406678D01*
X958719Y1406535D01*
X954547Y1409457D01*
X954404Y1410264D01*
X956546Y1413322D01*
X956249Y1415009D01*
X953610Y1416857D01*
X951923Y1416560D01*
X949781Y1413502D01*
X948975Y1413359D01*
X947073Y1414692D01*
X946930Y1415499D01*
X949072Y1418557D01*
X948775Y1420244D01*
X946136Y1422092D01*
X944449Y1421795D01*
X942307Y1418737D01*
X941500Y1418594D01*
X900934Y1447005D01*
X837633Y1458165D01*
X785369Y1448949D01*
X625957Y1477056D01*
X496758D01*
X395658Y1462059D01*
X318777Y1430211D01*
X303906Y1415342D01*
X291097Y1384453D01*
Y1319716D01*
X293005Y1300349D01*
X295618Y1290909D01*
X300143Y1281342D01*
X320749Y1260736D01*
X387594Y1205889D01*
X408196Y1181408D01*
X415233Y1171921D01*
X415600Y1171035D01*
Y1150477D01*
G01X1311831Y1135659D02*
Y1136951D01*
X1306926Y1141856D01*
X1300488Y1151485D01*
X1292814Y1176779D01*
X1251088Y1218504D01*
X1237313D01*
X1227170Y1219509D01*
X1220418Y1222805D01*
X1216600Y1226354D01*
X1211394Y1228810D01*
X1208548Y1229189D01*
X1207004Y1229957D01*
X1190202Y1239826D01*
X1188207Y1241914D01*
X1185452Y1244668D01*
Y1250089D01*
X1181473Y1254068D01*
Y1255767D01*
X1176132Y1261108D01*
X1172182Y1267891D01*
X1166905Y1273168D01*
X1133517D01*
X1131610Y1271261D01*
X1126409D01*
X1125221Y1271753D01*
X1120615Y1276358D01*
X1088152D01*
X1086285Y1278225D01*
X1069402D01*
X1065042Y1282585D01*
X1042111D01*
X1036137Y1288559D01*
Y1322832D01*
X981873Y1377096D01*
Y1381654D01*
X966346Y1397182D01*
X899839Y1443751D01*
Y1443752D01*
X899643Y1443889D01*
X837620Y1454826D01*
X830332Y1453544D01*
X829347Y1452139D01*
X829555Y1450964D01*
X829086Y1450294D01*
X826795Y1449889D01*
X826125Y1450358D01*
X825917Y1451533D01*
X824513Y1452518D01*
X821346Y1451957D01*
X820361Y1450553D01*
X820569Y1449378D01*
X820100Y1448708D01*
X817809Y1448303D01*
X817139Y1448772D01*
X816931Y1449947D01*
X815527Y1450932D01*
X812360Y1450371D01*
X811375Y1448967D01*
X811583Y1447792D01*
X811114Y1447122D01*
X808823Y1446717D01*
X808153Y1447186D01*
X807945Y1448361D01*
X806541Y1449346D01*
X803374Y1448785D01*
X802389Y1447381D01*
X802597Y1446206D01*
X802128Y1445536D01*
X799837Y1445131D01*
X799167Y1445600D01*
X798959Y1446775D01*
X797555Y1447760D01*
X794388Y1447199D01*
X793403Y1445795D01*
X793611Y1444620D01*
X793142Y1443950D01*
X790851Y1443545D01*
X790181Y1444014D01*
X789973Y1445189D01*
X788570Y1446174D01*
X785378Y1445610D01*
X779793Y1446583D01*
X778391Y1445595D01*
X778113Y1444027D01*
X778112Y1444026D01*
X777992Y1443338D01*
X777322Y1442869D01*
X775031Y1443273D01*
X774562Y1443943D01*
X774961Y1446202D01*
X773976Y1447607D01*
X770809Y1448169D01*
X769404Y1447182D01*
X769006Y1444923D01*
X768336Y1444454D01*
X766045Y1444858D01*
X765576Y1445528D01*
X765975Y1447788D01*
X764990Y1449191D01*
X761821Y1449752D01*
X760418Y1448767D01*
X760020Y1446508D01*
X759350Y1446039D01*
X757059Y1446443D01*
X756590Y1447113D01*
X756989Y1449373D01*
X756005Y1450775D01*
X752834Y1451337D01*
X751433Y1450351D01*
X751034Y1448093D01*
X750364Y1447624D01*
X748073Y1448028D01*
X747604Y1448698D01*
X748003Y1450958D01*
X747014Y1452367D01*
X743857Y1452926D01*
X742447Y1451937D01*
X742048Y1449678D01*
X741378Y1449209D01*
X739087Y1449613D01*
X738618Y1450283D01*
X739017Y1452543D01*
X738032Y1453946D01*
X734865Y1454507D01*
X733460Y1453522D01*
X733062Y1451263D01*
X732392Y1450794D01*
X730101Y1451198D01*
X729632Y1451868D01*
X730031Y1454128D01*
X729046Y1455531D01*
X725879Y1456092D01*
X724474Y1455107D01*
X724076Y1452848D01*
X723406Y1452379D01*
X721115Y1452783D01*
X720646Y1453453D01*
X721045Y1455713D01*
X720060Y1457116D01*
X716893Y1457677D01*
X715488Y1456692D01*
X715090Y1454433D01*
X714420Y1453964D01*
X712129Y1454368D01*
X711660Y1455038D01*
X712059Y1457298D01*
X711074Y1458701D01*
X707907Y1459262D01*
X706502Y1458277D01*
X706104Y1456018D01*
X705434Y1455549D01*
X703143Y1455953D01*
X702674Y1456623D01*
X703073Y1458883D01*
X702088Y1460286D01*
X698921Y1460847D01*
X697516Y1459862D01*
X697118Y1457603D01*
X696448Y1457134D01*
X694157Y1457538D01*
X693688Y1458208D01*
X694087Y1460468D01*
X693102Y1461871D01*
X689935Y1462432D01*
X688530Y1461447D01*
X688132Y1459188D01*
X687462Y1458719D01*
X685171Y1459123D01*
X684702Y1459793D01*
X685101Y1462053D01*
X684116Y1463456D01*
X680949Y1464017D01*
X679545Y1463032D01*
X679146Y1460773D01*
X678476Y1460304D01*
X676185Y1460708D01*
X675716Y1461378D01*
X676115Y1463638D01*
X675130Y1465041D01*
X671963Y1465602D01*
X670558Y1464617D01*
X670160Y1462358D01*
X669490Y1461889D01*
X667199Y1462293D01*
X666730Y1462963D01*
X667129Y1465223D01*
X666144Y1466626D01*
X662977Y1467187D01*
X661572Y1466202D01*
X661174Y1463943D01*
X660504Y1463474D01*
X658213Y1463878D01*
X657744Y1464548D01*
X658143Y1466808D01*
X657158Y1468211D01*
X653991Y1468772D01*
X652586Y1467787D01*
X652188Y1465528D01*
X651518Y1465059D01*
X649227Y1465463D01*
X648758Y1466133D01*
X649157Y1468393D01*
X648172Y1469796D01*
X645005Y1470357D01*
X643600Y1469372D01*
X643202Y1467113D01*
X642532Y1466644D01*
X640241Y1467048D01*
X639772Y1467718D01*
X640171Y1469978D01*
X639186Y1471381D01*
X636019Y1471942D01*
X634614Y1470957D01*
X634216Y1468698D01*
X633546Y1468229D01*
X631255Y1468633D01*
X630786Y1469303D01*
X631185Y1471563D01*
X630201Y1472966D01*
X625663Y1473766D01*
X497469D01*
X396311Y1458760D01*
X320674Y1427431D01*
X306809Y1413566D01*
X294387Y1383570D01*
Y1319791D01*
X296239Y1300970D01*
X298614Y1292382D01*
X302977Y1283160D01*
X322510Y1263625D01*
X389466Y1208679D01*
X389474Y1208671D01*
X412015Y1184996D01*
X411995Y1184190D01*
X412996Y1183139D01*
X413802Y1183119D01*
X415384Y1181457D01*
X415365Y1180651D01*
X416365Y1179600D01*
X417171Y1179580D01*
X419112Y1177542D01*
X419092Y1176736D01*
X420093Y1175685D01*
X420899Y1175665D01*
X422105Y1174398D01*
X424363Y1171354D01*
X424766Y1170383D01*
Y1166827D01*
X424196Y1166257D01*
Y1164807D01*
X424766Y1164237D01*
Y1157517D01*
X424196Y1156947D01*
Y1155497D01*
X424766Y1154927D01*
Y1147166D01*
X426471Y1145461D01*
Y1143029D01*
G01X1308745Y1130629D02*
Y1131161D01*
X1308744Y1131162D01*
Y1132235D01*
X1307823Y1134458D01*
X1297534Y1149787D01*
X1289812Y1175154D01*
X1252822Y1212144D01*
X1236675D01*
X1235950Y1212450D01*
X1227462D01*
X1221782Y1214804D01*
X1216430Y1218380D01*
X1213380Y1221430D01*
X1208519Y1224679D01*
X1189232Y1232670D01*
X1180482Y1240599D01*
X1180330Y1241382D01*
Y1249821D01*
X1178281Y1252302D01*
X1173103D01*
X1169674Y1248873D01*
X1167885D01*
X1164590Y1252168D01*
X1145343D01*
X1144042Y1253469D01*
Y1266899D01*
X1142369Y1268572D01*
X1135346D01*
X1133682Y1266908D01*
X1128354D01*
X1117948Y1271220D01*
X1079019D01*
X1078439Y1271800D01*
Y1273753D01*
X1077227Y1274965D01*
X1074011D01*
X1072799Y1273753D01*
Y1271800D01*
X1072219Y1271220D01*
X1064149D01*
X1063569Y1271800D01*
Y1277495D01*
X1062357Y1278707D01*
X1059141D01*
X1057929Y1277495D01*
Y1271800D01*
X1057349Y1271220D01*
X1045700D01*
X1031690Y1285230D01*
Y1312795D01*
X1024529Y1319956D01*
Y1320776D01*
X1028198Y1324445D01*
Y1326159D01*
X1025921Y1328436D01*
X1024207D01*
X1020538Y1324767D01*
X1019718D01*
X1018077Y1326408D01*
Y1327228D01*
X1021746Y1330897D01*
Y1332611D01*
X1019469Y1334888D01*
X1017755D01*
X1014086Y1331219D01*
X1013266D01*
X1011625Y1332860D01*
Y1333680D01*
X1015294Y1337349D01*
Y1339063D01*
X1013017Y1341340D01*
X1011303D01*
X1007634Y1337671D01*
X1006814D01*
X1005173Y1339312D01*
Y1340132D01*
X1008842Y1343801D01*
Y1345515D01*
X1006565Y1347792D01*
X1004851D01*
X1001182Y1344123D01*
X1000362D01*
X998721Y1345764D01*
Y1346584D01*
X1002390Y1350253D01*
Y1351967D01*
X1000113Y1354244D01*
X998399D01*
X994730Y1350575D01*
X993910D01*
X992269Y1352216D01*
Y1353036D01*
X995938Y1356705D01*
Y1358419D01*
X993661Y1360696D01*
X991947D01*
X988278Y1357027D01*
X987458D01*
X985817Y1358668D01*
Y1359488D01*
X989486Y1363157D01*
Y1364871D01*
X987209Y1367148D01*
X985495D01*
X981826Y1363479D01*
X981006D01*
X978613Y1365872D01*
Y1379306D01*
X961080Y1396839D01*
X898352Y1440765D01*
X847609Y1449712D01*
X783667Y1438438D01*
X602023Y1470466D01*
X497780D01*
X397135Y1455537D01*
X323512Y1425043D01*
X310307Y1411838D01*
X297702Y1381393D01*
Y1319466D01*
X299460Y1301597D01*
X301526Y1294151D01*
X305890Y1284918D01*
X320881Y1269926D01*
X388866Y1214134D01*
X424538Y1176668D01*
X427453Y1172737D01*
X428666Y1169809D01*
Y1152658D01*
X429440Y1150790D01*
Y1148222D01*
G01X297835Y1682244D02*
Y1681003D01*
X297254Y1680422D01*
X295275D01*
X294107Y1679254D01*
X293565Y1673956D01*
X293134Y1660026D01*
Y1660014D01*
X291837Y1618009D01*
Y1615452D01*
X290677Y1614292D01*
G01X305709Y1686180D02*
Y1684939D01*
X305128Y1684358D01*
X303149D01*
X301937Y1683146D01*
Y1668783D01*
X303897Y1629378D01*
Y1615452D01*
X302737Y1614292D01*
G01X294077D02*
X292917Y1615452D01*
Y1617992D01*
X293132Y1624939D01*
X293131Y1624945D01*
X293699Y1625478D01*
X293744Y1626928D01*
X293211Y1627495D01*
X293255Y1628944D01*
X293823Y1629477D01*
X293868Y1630927D01*
X293335Y1631494D01*
X293379Y1632943D01*
X293947Y1633476D01*
X293992Y1634926D01*
X293459Y1635493D01*
X293503Y1636942D01*
X294071Y1637475D01*
X294116Y1638925D01*
X293583Y1639492D01*
X293627Y1640941D01*
X294195Y1641474D01*
X294239Y1642924D01*
X293707Y1643491D01*
X294215Y1659984D01*
X294214Y1659993D01*
X294644Y1673884D01*
X295143Y1678762D01*
X295723Y1679342D01*
X296912D01*
X297835Y1678419D01*
Y1677519D01*
G01X306137Y1614292D02*
X304977Y1615452D01*
Y1629405D01*
X304064Y1647794D01*
Y1647796D01*
X304529Y1648310D01*
X304444Y1650029D01*
X303929Y1650494D01*
X303844Y1652211D01*
X304366Y1652788D01*
X304294Y1654237D01*
X303716Y1654759D01*
X303645Y1656207D01*
X304167Y1656784D01*
X304095Y1658233D01*
X303518Y1658755D01*
X303446Y1660203D01*
X303968Y1660779D01*
X303896Y1662229D01*
X303318Y1662751D01*
X303017Y1668810D01*
Y1682698D01*
X303597Y1683278D01*
X304786D01*
X305709Y1682355D01*
Y1681456D01*
G01X313583Y1682244D02*
Y1681003D01*
X313002Y1680422D01*
X311023D01*
X309811Y1679210D01*
Y1668658D01*
X315957Y1621942D01*
Y1615452D01*
X314797Y1614292D01*
G01X318197D02*
X317037Y1615452D01*
Y1622013D01*
X313876Y1646047D01*
X314350Y1646664D01*
X314161Y1648102D01*
X313543Y1648576D01*
X313354Y1650013D01*
X313828Y1650630D01*
X313639Y1652068D01*
X313021Y1652542D01*
X312832Y1653979D01*
X313306Y1654596D01*
X313117Y1656034D01*
X312499Y1656508D01*
X312310Y1657945D01*
X312784Y1658562D01*
X312595Y1660000D01*
X311977Y1660474D01*
X311788Y1661911D01*
X312262Y1662528D01*
X312073Y1663967D01*
X311455Y1664441D01*
X310891Y1668729D01*
Y1678762D01*
X311471Y1679342D01*
X312660D01*
X313583Y1678419D01*
Y1677519D01*
G01X321457Y1686180D02*
Y1684939D01*
X320876Y1684358D01*
X318897D01*
X317685Y1683146D01*
Y1668317D01*
X328017Y1620199D01*
Y1615452D01*
X326857Y1614292D01*
G01X330257D02*
X329097Y1615452D01*
Y1620314D01*
X322711Y1650055D01*
X322712Y1650056D01*
X323134Y1650709D01*
X322830Y1652128D01*
X322176Y1652550D01*
X321872Y1653967D01*
X322294Y1654620D01*
X321990Y1656039D01*
X321336Y1656461D01*
X321032Y1657878D01*
X321454Y1658531D01*
X321150Y1659950D01*
X320496Y1660372D01*
X320192Y1661789D01*
X320614Y1662442D01*
X320310Y1663861D01*
X319655Y1664283D01*
X318765Y1668432D01*
Y1682698D01*
X319345Y1683278D01*
X320534D01*
X321457Y1682355D01*
Y1681456D01*
G01X349764Y832855D02*
Y832376D01*
X337390Y820002D01*
X335210Y815310D01*
X335060Y810628D01*
X336208Y804299D01*
X376647Y756243D01*
X385280Y733285D01*
X400980Y713746D01*
X483525Y636127D01*
X627955Y547288D01*
X666959Y533934D01*
X939369Y538409D01*
X1072104Y535985D01*
X1224285Y542384D01*
X1256921D01*
X1317225Y557843D01*
X1423103Y630494D01*
X1456066Y651546D01*
X1456065Y651547D01*
X1456982Y652132D01*
X1458321Y653693D01*
X1458684Y654319D01*
X1458686Y654322D01*
X1460814Y654892D01*
G01X350844Y832855D02*
Y831928D01*
X348844Y829928D01*
Y829122D01*
X347818Y828096D01*
X347012D01*
X345987Y827071D01*
Y826265D01*
X344961Y825239D01*
X344155D01*
X343130Y824214D01*
Y823408D01*
X342104Y822382D01*
X341298D01*
X338290Y819373D01*
X336283Y815055D01*
X336144Y810708D01*
X337220Y804775D01*
X377593Y756797D01*
X386231Y733827D01*
X401775Y714481D01*
X484185Y636989D01*
X628419Y548272D01*
X667130Y535018D01*
X939370Y539490D01*
X1072091Y537066D01*
X1224262Y543464D01*
X1256784D01*
X1316772Y558842D01*
X1422507Y631395D01*
X1443891Y645053D01*
X1444064Y645841D01*
X1445287Y646621D01*
X1446075Y646448D01*
X1447544Y647386D01*
X1447718Y648174D01*
X1448941Y648954D01*
X1449728Y648781D01*
X1450950Y649561D01*
X1451123Y650349D01*
X1452346Y651129D01*
X1453133Y650956D01*
X1456266Y652957D01*
X1457436Y654321D01*
X1457748Y654859D01*
X1457176Y656992D01*
G01X329331Y1682244D02*
Y1681003D01*
X328750Y1680422D01*
X326771D01*
X325559Y1679210D01*
Y1668997D01*
X340077Y1619444D01*
Y1615452D01*
X338917Y1614292D01*
G01X342317D02*
X341157Y1615452D01*
Y1619704D01*
X341114Y1619747D01*
X332877Y1647864D01*
X333250Y1648546D01*
X332843Y1649939D01*
X332159Y1650312D01*
X331752Y1651703D01*
X332125Y1652385D01*
X331718Y1653778D01*
X331034Y1654151D01*
X330627Y1655542D01*
X331000Y1656224D01*
X330593Y1657617D01*
X329909Y1657990D01*
X329502Y1659381D01*
X329875Y1660063D01*
X329468Y1661456D01*
X328784Y1661829D01*
X328377Y1663220D01*
X328750Y1663903D01*
X328343Y1665295D01*
X327660Y1665667D01*
X326639Y1669152D01*
Y1678762D01*
X327219Y1679342D01*
X328408D01*
X329331Y1678419D01*
Y1677519D01*
G01X337205Y1686180D02*
Y1684939D01*
X336624Y1684358D01*
X334645D01*
X333433Y1683146D01*
Y1669043D01*
X352137Y1619004D01*
Y1615452D01*
X350977Y1614292D01*
G01X354377D02*
X353217Y1615452D01*
Y1619200D01*
X340874Y1652222D01*
X340875Y1652224D01*
X341198Y1652931D01*
X340690Y1654291D01*
X339981Y1654613D01*
X339475Y1655968D01*
X339474Y1655971D01*
X339797Y1656678D01*
X339289Y1658038D01*
X338580Y1658360D01*
X338073Y1659718D01*
X338396Y1660425D01*
X337888Y1661785D01*
X337179Y1662107D01*
X336673Y1663462D01*
X336672Y1663465D01*
X336994Y1664173D01*
X336487Y1665532D01*
X335778Y1665854D01*
X334513Y1669239D01*
Y1682698D01*
X335093Y1683278D01*
X336282D01*
X337205Y1682355D01*
Y1681456D01*
G01X354538Y833625D02*
Y830070D01*
X352235Y827767D01*
Y826961D01*
X351209Y825935D01*
X350403D01*
X349378Y824910D01*
Y824104D01*
X348352Y823078D01*
X347546D01*
X346521Y822053D01*
Y821247D01*
X345495Y820221D01*
X344689D01*
X341080Y816612D01*
X339952Y814185D01*
X339850Y810982D01*
X340680Y806402D01*
X380094Y759563D01*
X389205Y735334D01*
X403722Y717267D01*
X486454Y639472D01*
X629968Y551199D01*
X667604Y538314D01*
X939380Y542778D01*
X1068284Y540425D01*
X1228444Y547157D01*
X1228490Y547158D01*
X1257870D01*
X1314541Y561689D01*
X1317591Y563782D01*
X1317739Y564575D01*
X1318935Y565395D01*
X1319728Y565248D01*
X1321025Y566137D01*
X1321172Y566931D01*
X1322369Y567751D01*
X1323161Y567604D01*
X1324356Y568424D01*
X1324504Y569217D01*
X1325700Y570038D01*
X1326493Y569890D01*
X1327688Y570710D01*
X1327836Y571503D01*
X1329032Y572324D01*
X1329825Y572176D01*
X1332112Y573745D01*
Y573744D01*
X1417369Y632233D01*
X1451855Y660735D01*
X1454623Y661900D01*
X1455804Y661806D01*
X1455805Y661805D01*
X1456984Y661712D01*
X1465000Y656740D01*
X1465783Y656924D01*
X1467017Y656160D01*
X1467201Y655375D01*
X1470220Y653502D01*
X1473400D01*
X1474620Y654722D01*
Y656108D01*
X1474618Y656110D01*
X1474208Y656820D01*
X1472076Y657392D01*
G01X353458Y833625D02*
Y830518D01*
X340181Y817241D01*
X338879Y814440D01*
X338766Y810902D01*
X339668Y805926D01*
X379148Y759009D01*
X388254Y734792D01*
X402927Y716532D01*
X485794Y638610D01*
X629504Y550215D01*
X667433Y537231D01*
X939379Y541697D01*
X1068297Y539344D01*
X1228489Y546077D01*
X1228490Y546078D01*
X1258007D01*
X1314994Y560690D01*
X1418020Y631369D01*
X1452421Y659801D01*
X1454800Y660802D01*
X1456637Y660656D01*
X1469912Y652422D01*
X1473848D01*
X1475700Y654274D01*
Y656556D01*
X1475483Y656774D01*
X1475144Y657361D01*
X1475142Y657364D01*
X1475714Y659492D01*
G01X345079Y1682244D02*
Y1681003D01*
X344398Y1680322D01*
X342419D01*
X341307Y1679210D01*
Y1670107D01*
X364197Y1618724D01*
Y1615452D01*
X363037Y1614292D01*
G01X366437D02*
X365277Y1615452D01*
Y1619070D01*
X365184Y1619163D01*
X351815Y1649175D01*
X352094Y1649902D01*
X351504Y1651227D01*
X350777Y1651506D01*
X350187Y1652830D01*
X350466Y1653556D01*
X349876Y1654881D01*
X349149Y1655160D01*
X348559Y1656484D01*
X348838Y1657210D01*
X348248Y1658535D01*
X347521Y1658814D01*
X346931Y1660138D01*
X347209Y1660864D01*
X346619Y1662189D01*
X345892Y1662468D01*
X345184Y1664058D01*
X345463Y1664784D01*
X344873Y1666110D01*
X344147Y1666388D01*
X342387Y1670337D01*
Y1678762D01*
X342867Y1679242D01*
X344256D01*
X345079Y1678419D01*
Y1677519D01*
G01X352953Y1686180D02*
Y1684939D01*
X352372Y1684358D01*
X350393D01*
X349136Y1683101D01*
Y1669171D01*
X376257Y1618594D01*
Y1615452D01*
X375097Y1614292D01*
G01X378497D02*
X377337Y1615452D01*
Y1618976D01*
X377209Y1619104D01*
X367822Y1636610D01*
X358437Y1654114D01*
X358662Y1654859D01*
X357976Y1656138D01*
X357231Y1656363D01*
X356546Y1657640D01*
X356771Y1658385D01*
X356085Y1659664D01*
X355340Y1659889D01*
X354655Y1661166D01*
X354880Y1661911D01*
X354194Y1663190D01*
X353449Y1663415D01*
X352764Y1664692D01*
X352989Y1665436D01*
X352304Y1666715D01*
X351558Y1666940D01*
X350216Y1669443D01*
Y1682653D01*
X350841Y1683278D01*
X352030D01*
X352953Y1682355D01*
Y1681456D01*
G01X1460814Y666892D02*
X1458686Y666322D01*
X1458684Y666319D01*
X1458103Y665314D01*
X1456663Y664637D01*
X1454565Y664286D01*
X1450853Y662800D01*
X1420694Y637875D01*
X1312379Y563566D01*
X1257080Y549388D01*
X1229288D01*
X1068834Y542663D01*
X939438Y544977D01*
X939409D01*
X667973Y540562D01*
X630329Y553592D01*
X487742Y641332D01*
X406348Y717903D01*
X391074Y736950D01*
X376847Y775334D01*
X360861Y818460D01*
X360858Y818469D01*
X357589Y827288D01*
Y833745D01*
G01X1457176Y668992D02*
X1457748Y666860D01*
X1457337Y666148D01*
X1456338Y665678D01*
X1454272Y665333D01*
X1450295Y663740D01*
X1448817Y662519D01*
X1448015Y662596D01*
X1446897Y661671D01*
X1446821Y660868D01*
X1446820Y660869D01*
X1445378Y659678D01*
X1445379Y659677D01*
X1444576Y659753D01*
X1443458Y658828D01*
X1443381Y658026D01*
X1442118Y656982D01*
X1441315Y657058D01*
X1440196Y656134D01*
X1440120Y655331D01*
X1439003Y654408D01*
X1438200Y654484D01*
X1437082Y653559D01*
X1437005Y652757D01*
X1420043Y638739D01*
X1311926Y564565D01*
X1256943Y550468D01*
X1229265D01*
X1068821Y543744D01*
X939448Y546057D01*
X939400D01*
X668146Y541645D01*
X630794Y554574D01*
X488402Y642194D01*
X407143Y718638D01*
X392027Y737490D01*
X377860Y775710D01*
Y775711D01*
X377857Y775720D01*
X377856Y775722D01*
X361874Y818835D01*
X361872Y818843D01*
X362208Y819576D01*
X361704Y820937D01*
X360971Y821272D01*
X360467Y822632D01*
X360804Y823365D01*
X360300Y824725D01*
X359567Y825060D01*
X358669Y827482D01*
Y833745D01*
G01X361290D02*
Y828425D01*
X394801Y737646D01*
X408308Y720711D01*
X489252Y644523D01*
X632753Y556225D01*
X668259Y543967D01*
X939314Y548349D01*
X939331D01*
X1068377Y546029D01*
X1068378Y546028D01*
X1068409D01*
X1228903Y552717D01*
X1256745D01*
X1311031Y566638D01*
X1418336Y640253D01*
X1452258Y671337D01*
X1454012Y672213D01*
X1455370Y672100D01*
Y672101D01*
X1472069Y666255D01*
X1473983Y666737D01*
X1475800Y668554D01*
Y670725D01*
X1475144Y671861D01*
X1475142Y671864D01*
X1475714Y673992D01*
G01X362370Y833745D02*
Y828618D01*
X362965Y827005D01*
X363583Y826721D01*
X364178Y825106D01*
X363894Y824490D01*
X364489Y822877D01*
X365107Y822593D01*
X365702Y820978D01*
X365418Y820362D01*
X366013Y818749D01*
X366631Y818465D01*
X367226Y816850D01*
X366942Y816234D01*
X395755Y738184D01*
X409105Y721445D01*
X489912Y645385D01*
X633218Y557208D01*
X668432Y545050D01*
X939305Y549429D01*
X939341D01*
X1068396Y547109D01*
X1228880Y553797D01*
X1256608D01*
X1310578Y567637D01*
X1313492Y569637D01*
X1313640Y570429D01*
X1314836Y571250D01*
X1315628Y571102D01*
X1316824Y571923D01*
X1316972Y572715D01*
X1318168Y573536D01*
X1318961Y573388D01*
X1320156Y574208D01*
X1320304Y575001D01*
X1321500Y575822D01*
X1322292Y575674D01*
X1324526Y577207D01*
X1324527Y577206D01*
X1324675Y578000D01*
X1325871Y578820D01*
X1326663Y578673D01*
X1328193Y579723D01*
X1328194Y579722D01*
X1328341Y580516D01*
X1329538Y581336D01*
X1330331Y581189D01*
X1417662Y641101D01*
X1451640Y672236D01*
X1453800Y673315D01*
X1455597Y673166D01*
X1460090Y671594D01*
X1460816Y671943D01*
X1462186Y671464D01*
X1462535Y670738D01*
X1472120Y667382D01*
X1473430Y667712D01*
X1474720Y669002D01*
Y670435D01*
X1474209Y671320D01*
X1472076Y671892D01*
G01X364989Y832995D02*
Y829380D01*
X398702Y738060D01*
X410704Y723011D01*
X491389Y647069D01*
X633990Y559324D01*
X667769Y547661D01*
X939317Y552052D01*
X939334D01*
X1075401Y549606D01*
X1238895Y556418D01*
X1257300D01*
X1307821Y569374D01*
X1418253Y645136D01*
X1450161Y673955D01*
X1453141Y675455D01*
X1456913Y676455D01*
X1458154Y677405D01*
X1458682Y678320D01*
X1460814Y678892D01*
G01X366069Y832995D02*
Y829573D01*
X366664Y827960D01*
X367282Y827676D01*
X367877Y826061D01*
X367593Y825445D01*
X368188Y823832D01*
X368806Y823548D01*
X369401Y821933D01*
X369117Y821317D01*
X399656Y738598D01*
X411501Y723745D01*
X492049Y647931D01*
X634455Y560307D01*
X667942Y548744D01*
X939308Y553132D01*
X939344D01*
X1075388Y550687D01*
X1238872Y557498D01*
X1257163D01*
X1307368Y570373D01*
X1417582Y645987D01*
X1434504Y661271D01*
X1434545Y662076D01*
X1435622Y663049D01*
X1436427Y663008D01*
X1437503Y663979D01*
X1437544Y664784D01*
X1438621Y665757D01*
X1439426Y665716D01*
X1440502Y666687D01*
X1440543Y667492D01*
X1441620Y668465D01*
X1442425Y668424D01*
X1443904Y669760D01*
X1443945Y670565D01*
X1445022Y671538D01*
X1445827Y671497D01*
X1449545Y674855D01*
X1452755Y676471D01*
X1456428Y677444D01*
X1457326Y678132D01*
X1457746Y678861D01*
X1457748Y678864D01*
X1457176Y680992D01*
G01X1472076Y686392D02*
X1474209Y685820D01*
X1474660Y685039D01*
Y683522D01*
X1473650Y682512D01*
X1472340Y682042D01*
X1464584Y683638D01*
X1464140Y684312D01*
X1462719Y684605D01*
X1462046Y684161D01*
X1460626Y684453D01*
X1460183Y685128D01*
X1458761Y685420D01*
X1458088Y684977D01*
X1455000Y685612D01*
X1453524Y685580D01*
X1451241Y684208D01*
X1413231Y647048D01*
X1320246Y583255D01*
X1319454Y583403D01*
X1318257Y582582D01*
X1318109Y581789D01*
X1316691Y580816D01*
X1315898Y580964D01*
X1314702Y580143D01*
X1314554Y579350D01*
X1313359Y578530D01*
X1312567Y578678D01*
X1311370Y577857D01*
X1311223Y577064D01*
X1309800Y576088D01*
X1309007Y576235D01*
X1307810Y575415D01*
X1307663Y574621D01*
X1305824Y573360D01*
X1258406Y561197D01*
X1249082D01*
X1082532Y554259D01*
X939329Y556833D01*
X667293Y552434D01*
X636131Y563193D01*
X494112Y650579D01*
X413959Y726023D01*
X403488Y739153D01*
X374718Y817080D01*
X375055Y817812D01*
X374553Y819173D01*
X373820Y819510D01*
X372631Y822731D01*
X372968Y823463D01*
X372466Y824824D01*
X371733Y825161D01*
X371732Y825166D01*
X371232Y826522D01*
X371569Y827254D01*
X371067Y828615D01*
X370333Y828952D01*
X370335Y828953D01*
X370333Y828959D01*
X369770Y830480D01*
Y833585D01*
G01X1475714Y688492D02*
X1475142Y686364D01*
X1475144Y686361D01*
X1475740Y685329D01*
Y683074D01*
X1474243Y681577D01*
X1474014Y681494D01*
Y681495D01*
X1472419Y680922D01*
X1464367Y682580D01*
X1464366D01*
X1454901Y684529D01*
X1453835Y684506D01*
X1451904Y683344D01*
X1413919Y646210D01*
X1308274Y573730D01*
X1306277Y572361D01*
X1258543Y560117D01*
X1249105D01*
X1082545Y553178D01*
X939328Y555752D01*
X667120Y551351D01*
X635666Y562210D01*
X493452Y649717D01*
X413162Y725289D01*
X402534Y738615D01*
X370720Y824788D01*
X370719Y824791D01*
X369319Y828583D01*
X368690Y830286D01*
Y833585D01*
G01X1460814Y690892D02*
X1458686Y690322D01*
X1458684Y690319D01*
X1458137Y689372D01*
X1456659Y688459D01*
X1452758Y687704D01*
X1449850Y686023D01*
X1413957Y651215D01*
X1302681Y574871D01*
X1259675Y563839D01*
X1089589Y556753D01*
X939331Y559455D01*
X666669Y555047D01*
X636961Y565303D01*
X495697Y652224D01*
X415869Y727364D01*
X406874Y738643D01*
X372389Y832046D01*
Y835047D01*
G01X1457176Y692992D02*
X1457748Y690860D01*
X1457337Y690148D01*
X1456260Y689482D01*
X1452375Y688730D01*
X1449193Y686892D01*
X1448108Y685839D01*
X1447302Y685852D01*
X1446260Y684841D01*
X1446247Y684035D01*
X1445186Y683006D01*
X1444380Y683018D01*
X1443338Y682008D01*
X1443326Y681202D01*
X1441907Y679826D01*
X1441101Y679839D01*
X1440059Y678828D01*
X1440047Y678022D01*
X1438738Y676753D01*
X1437932Y676766D01*
X1436890Y675755D01*
X1436878Y674949D01*
X1413270Y652055D01*
X1302228Y575870D01*
X1259516Y564914D01*
X1089576Y557834D01*
X939332Y560536D01*
X666842Y556130D01*
X637426Y566286D01*
X496357Y653086D01*
X416665Y728098D01*
X412866Y732863D01*
X412957Y733664D01*
X412052Y734799D01*
X411251Y734889D01*
X410347Y736022D01*
X410438Y736823D01*
X409533Y737958D01*
X408732Y738048D01*
X407828Y739181D01*
X373469Y832240D01*
Y835047D01*
G01X376090Y833745D02*
Y831654D01*
X409229Y741899D01*
X419357Y729200D01*
X499429Y653833D01*
X637818Y568683D01*
X666588Y558746D01*
X939334Y563156D01*
X1088318Y560477D01*
X1259079Y567121D01*
X1301391Y577972D01*
X1304500Y580104D01*
X1409751Y652320D01*
X1453315Y695758D01*
X1454679Y696330D01*
X1473399Y695988D01*
X1474764Y696538D01*
X1475850Y697624D01*
Y699639D01*
X1475144Y700861D01*
X1475142Y700864D01*
X1475714Y702992D01*
G01X377170Y833745D02*
Y831848D01*
X410183Y742437D01*
X411255Y741093D01*
X411929Y741017D01*
X413003Y739671D01*
X412927Y738996D01*
X413999Y737652D01*
X414673Y737576D01*
X415747Y736230D01*
X415671Y735555D01*
X416743Y734211D01*
X417418Y734135D01*
X418491Y732789D01*
X418415Y732115D01*
X420154Y729934D01*
X500089Y654695D01*
X638283Y569665D01*
X666761Y559829D01*
X939335Y564237D01*
X1088307Y561558D01*
X1258922Y568196D01*
X1300938Y578971D01*
X1303889Y580995D01*
X1304036Y581789D01*
X1305233Y582609D01*
X1306025Y582462D01*
X1307220Y583282D01*
X1307368Y584075D01*
X1308564Y584896D01*
X1309357Y584748D01*
X1310822Y585753D01*
X1310970Y586547D01*
X1312166Y587367D01*
X1312959Y587219D01*
X1314154Y588039D01*
X1314302Y588832D01*
X1315498Y589653D01*
X1316291Y589505D01*
X1409058Y653155D01*
X1452702Y696673D01*
X1454471Y697414D01*
X1461432Y697287D01*
X1462013Y697847D01*
X1463463Y697820D01*
X1464022Y697240D01*
X1465473Y697214D01*
X1466053Y697773D01*
X1467503Y697746D01*
X1468062Y697166D01*
X1473199Y697072D01*
X1474156Y697458D01*
X1474770Y698072D01*
Y699349D01*
X1474209Y700320D01*
X1472076Y700892D01*
G01X1457176Y704992D02*
X1457748Y702860D01*
X1457337Y702148D01*
X1455132Y701229D01*
X1454386Y701536D01*
X1453047Y700978D01*
X1452740Y700231D01*
X1450801Y699423D01*
X1449480Y698121D01*
X1448674Y698127D01*
X1447641Y697108D01*
X1447635Y696302D01*
X1446603Y695284D01*
X1445797Y695290D01*
X1444764Y694271D01*
X1444758Y693465D01*
X1443726Y692447D01*
X1442920Y692453D01*
X1441887Y691434D01*
X1441881Y690628D01*
X1408517Y657729D01*
X1297348Y581452D01*
X1258882Y571585D01*
X1172919Y568241D01*
Y568242D01*
X1086955Y564897D01*
X939344Y567552D01*
X667571Y563156D01*
X639285Y572924D01*
X572155Y614229D01*
Y614230D01*
X505024Y655535D01*
X422052Y733634D01*
X418295Y738346D01*
X418385Y739146D01*
X417481Y740280D01*
X416679Y740371D01*
X415776Y741504D01*
X415866Y742305D01*
X414961Y743439D01*
X414160Y743530D01*
X412766Y745278D01*
X380869Y831657D01*
Y833745D01*
G01X1460814Y702892D02*
X1458686Y702322D01*
X1458684Y702319D01*
X1458090Y701291D01*
X1451411Y698506D01*
X1409208Y656892D01*
X1297801Y580453D01*
X1259039Y570510D01*
X1086966Y563816D01*
X939343Y566471D01*
X667398Y562073D01*
X638820Y571941D01*
X504364Y654673D01*
X421255Y732900D01*
X411812Y744740D01*
X379789Y831463D01*
Y833745D01*
G01X384570D02*
Y832098D01*
X415656Y747915D01*
X416728Y746571D01*
X417402Y746495D01*
X418476Y745149D01*
X418400Y744474D01*
X419472Y743130D01*
X420146Y743054D01*
X421220Y741708D01*
X421144Y741033D01*
X422216Y739689D01*
X422890Y739613D01*
X423964Y738267D01*
X423888Y737592D01*
X427560Y732987D01*
X507095Y658121D01*
X640388Y576107D01*
X668317Y566458D01*
X939354Y570843D01*
X1086557Y568193D01*
X1258367Y574878D01*
X1296064Y584544D01*
X1299498Y586901D01*
X1299646Y587694D01*
X1300842Y588514D01*
X1301634Y588366D01*
X1303139Y589399D01*
X1303287Y590191D01*
X1304483Y591012D01*
X1305275Y590864D01*
X1396913Y653740D01*
X1397061Y654533D01*
X1398257Y655354D01*
X1399050Y655206D01*
X1400277Y656048D01*
X1400424Y656841D01*
X1401621Y657662D01*
X1402413Y657514D01*
X1404330Y658829D01*
X1452844Y708645D01*
X1454229Y709393D01*
X1462334Y710408D01*
X1462829Y711045D01*
X1464269Y711225D01*
X1464905Y710730D01*
X1466841Y710972D01*
X1467336Y711609D01*
X1468775Y711789D01*
X1469412Y711294D01*
X1473835Y711847D01*
X1474670Y712682D01*
Y714022D01*
X1474209Y714820D01*
X1472076Y715392D01*
G01X383490Y833745D02*
Y831904D01*
X414702Y747377D01*
X426763Y732253D01*
X506435Y657259D01*
X639923Y575125D01*
X668144Y565375D01*
X939353Y569762D01*
X1086568Y567112D01*
X1258524Y573803D01*
X1296517Y583545D01*
X1305887Y589974D01*
X1405030Y657998D01*
X1453504Y707774D01*
X1454564Y708346D01*
X1462913Y709391D01*
Y709390D01*
X1474337Y710821D01*
X1475750Y712234D01*
Y714312D01*
X1475144Y715361D01*
X1475142Y715364D01*
X1475714Y717492D01*
G01X387189Y833745D02*
Y831613D01*
X417175Y750411D01*
X431818Y732049D01*
X470051Y696060D01*
X470052D01*
X508311Y660048D01*
X641414Y578148D01*
X668779Y568700D01*
X939362Y573078D01*
X1087103Y570419D01*
X1256927Y577024D01*
X1293598Y586435D01*
X1403911Y662126D01*
X1451492Y710546D01*
X1453353Y711473D01*
X1456758Y712041D01*
X1458203Y713486D01*
X1458684Y714319D01*
X1458686Y714322D01*
X1460814Y714892D01*
G01X388269Y833745D02*
Y831807D01*
X418129Y750949D01*
X419279Y749506D01*
X419954Y749430D01*
X421027Y748084D01*
X420951Y747410D01*
X422023Y746066D01*
X422697Y745990D01*
X423771Y744644D01*
X423695Y743969D01*
X424767Y742625D01*
X425441Y742549D01*
X426515Y741203D01*
X426439Y740528D01*
X427511Y739184D01*
X428185Y739108D01*
X429259Y737762D01*
X429183Y737087D01*
X432615Y732783D01*
X508971Y660910D01*
X641879Y579131D01*
X668952Y569783D01*
X939363Y574159D01*
X1087092Y571500D01*
X1256770Y578099D01*
X1293144Y587434D01*
X1403213Y662958D01*
X1444282Y704751D01*
X1444275Y705557D01*
X1445292Y706593D01*
X1446098Y706600D01*
X1447127Y707647D01*
X1447120Y708453D01*
X1448138Y709488D01*
X1448944Y709495D01*
X1450848Y711433D01*
X1453016Y712512D01*
X1456238Y713050D01*
X1457338Y714150D01*
X1457748Y714860D01*
X1457176Y716992D01*
G01X391970Y833745D02*
Y831789D01*
X420872Y753530D01*
X421944Y752186D01*
X422618Y752110D01*
X423692Y750764D01*
X423616Y750089D01*
X424688Y748745D01*
X425362Y748669D01*
X426436Y747323D01*
X426360Y746648D01*
X427432Y745304D01*
X428106Y745228D01*
X429180Y743882D01*
X429104Y743207D01*
X430176Y741863D01*
X430850Y741787D01*
X431924Y740441D01*
X431848Y739766D01*
X437112Y733164D01*
X510898Y663708D01*
X643673Y582011D01*
X669577Y573065D01*
X939373Y577431D01*
X1086913Y574775D01*
X1256072Y581354D01*
X1291882Y590538D01*
X1399752Y664555D01*
X1448330Y716591D01*
X1448302Y717396D01*
X1449293Y718457D01*
X1450098Y718485D01*
X1451484Y719969D01*
X1453546Y721413D01*
X1456313Y722109D01*
X1456726Y722802D01*
X1458133Y723156D01*
X1458825Y722742D01*
X1460231Y723095D01*
X1460644Y723788D01*
X1462052Y724142D01*
X1462743Y723728D01*
X1464149Y724081D01*
X1464562Y724774D01*
X1465970Y725128D01*
X1466661Y724714D01*
X1466662Y724713D01*
X1468066Y725067D01*
X1468068Y725069D01*
X1468547Y725189D01*
X1468549Y725190D01*
X1470879Y725775D01*
X1471320Y726343D01*
X1471502Y726972D01*
X1471008Y727820D01*
X1468876Y728392D01*
G01X390890Y833745D02*
Y831595D01*
X419918Y752992D01*
X436315Y732430D01*
X510238Y662846D01*
X643208Y581028D01*
X669404Y571982D01*
X939372Y576350D01*
X1086924Y573694D01*
X1256229Y580279D01*
X1292335Y589539D01*
X1400461Y663731D01*
X1452196Y719149D01*
X1454003Y720413D01*
X1468811Y724140D01*
X1468812Y724142D01*
X1471503Y724818D01*
X1472301Y725843D01*
X1472668Y727116D01*
X1471942Y728364D01*
X1472514Y730492D01*
G01X1374668Y659708D02*
X1375240Y657577D01*
X1374630Y656521D01*
X1374629Y656519D01*
X1289879Y593518D01*
X1254209Y584570D01*
X1085787Y578070D01*
X939383Y580706D01*
X670410Y576391D01*
X644726Y585250D01*
X513103Y666242D01*
X441991Y733181D01*
X440162Y735476D01*
X440252Y736277D01*
X439347Y737411D01*
X438546Y737502D01*
X437581Y738713D01*
X437671Y739514D01*
X436766Y740648D01*
X435965Y740739D01*
X435062Y741872D01*
X435152Y742673D01*
X434247Y743808D01*
X433446Y743898D01*
X432198Y745464D01*
X432288Y746265D01*
X431383Y747399D01*
X430582Y747490D01*
X428962Y749522D01*
X429052Y750323D01*
X428147Y751457D01*
X427346Y751548D01*
X426443Y752681D01*
X426533Y753482D01*
X425628Y754617D01*
X424827Y754707D01*
X423531Y756333D01*
X395669Y831773D01*
Y833745D01*
G01X1378306Y657608D02*
X1376178Y657038D01*
X1376158Y657007D01*
X1375455Y655787D01*
X1290351Y592522D01*
X1254363Y583495D01*
X1085798Y576989D01*
X939382Y579625D01*
X670237Y575308D01*
X644261Y584267D01*
X512443Y665380D01*
X441194Y732447D01*
X422577Y755795D01*
X394589Y831579D01*
Y833745D01*
G01X1389568Y662608D02*
X1390140Y664740D01*
X1389730Y665450D01*
X1388918Y666262D01*
X1386342D01*
X1378443Y664493D01*
X1376989Y664743D01*
X1371611Y663794D01*
X1363935Y657494D01*
X1361537Y655396D01*
X1353481Y645301D01*
X1338547Y632485D01*
X1288399Y595558D01*
X1275629Y592352D01*
X1268530D01*
X1098793Y627912D01*
X1090992D01*
X937791Y588562D01*
X920892D01*
X811015Y607937D01*
X797508D01*
X789056Y599485D01*
Y593799D01*
X775728Y580471D01*
X753803D01*
X739572Y590435D01*
X726563Y592729D01*
X718889Y591375D01*
X712181Y586678D01*
X669286Y579115D01*
X646091Y587194D01*
X514036Y668573D01*
X446362Y732200D01*
X425117Y758940D01*
X398290Y832594D01*
Y833465D01*
G01X1393206Y664708D02*
X1391078Y665278D01*
X1391076Y665281D01*
X1390595Y666114D01*
X1390494Y666215D01*
Y666214D01*
X1389366Y667342D01*
X1386222D01*
X1378415Y665594D01*
X1376987Y665840D01*
X1371144Y664809D01*
X1363236Y658319D01*
X1360752Y656146D01*
X1352700Y646054D01*
X1337874Y633331D01*
X1312903Y614944D01*
Y614943D01*
X1287930Y596554D01*
X1275495Y593432D01*
X1268642D01*
X1098905Y628992D01*
X1090855D01*
X937654Y589642D01*
X920987D01*
X811110Y609017D01*
X797060D01*
X792389Y604346D01*
X791583D01*
X790556Y603319D01*
Y602513D01*
X787976Y599933D01*
Y594247D01*
X775280Y581551D01*
X754144D01*
X739996Y591458D01*
X726563Y593826D01*
X718465Y592398D01*
X711757Y587701D01*
X669376Y580228D01*
X646558Y588176D01*
X514696Y669435D01*
X447160Y732934D01*
X431345Y752839D01*
Y752838D01*
X426073Y759475D01*
X399370Y832785D01*
Y833465D01*
G01X401989Y833745D02*
Y832024D01*
X427456Y762103D01*
X451316Y732069D01*
X515992Y671258D01*
X647607Y590151D01*
X656101Y587184D01*
X671845Y587600D01*
X686806Y595009D01*
X755575Y630992D01*
X765543D01*
X773894Y629937D01*
X920694Y592092D01*
X938390D01*
X1090540Y631172D01*
X1099138D01*
X1267586Y595882D01*
X1274674D01*
X1287064Y598994D01*
X1337499Y636082D01*
X1347829Y644947D01*
X1358499Y658323D01*
X1360893Y660418D01*
X1368397Y666722D01*
X1375304Y668142D01*
X1376183Y669021D01*
X1376189Y669041D01*
X1378306Y669608D01*
G01X403069Y833745D02*
Y832215D01*
X428411Y762638D01*
X428947Y761965D01*
X430016Y760619D01*
X430691Y760541D01*
X431762Y759194D01*
X431684Y758519D01*
X432753Y757173D01*
X433428Y757096D01*
X434499Y755748D01*
X434421Y755073D01*
X435490Y753727D01*
X436165Y753650D01*
X437236Y752302D01*
X437159Y751627D01*
X438228Y750281D01*
X438903Y750204D01*
X439974Y748856D01*
X439897Y748181D01*
X440966Y746835D01*
X441641Y746758D01*
X442712Y745410D01*
X442634Y744735D01*
X443703Y743389D01*
X444378Y743312D01*
X445449Y741964D01*
X445372Y741289D01*
X446441Y739943D01*
X447116Y739866D01*
X448187Y738518D01*
X448110Y737843D01*
X452114Y732803D01*
X516652Y672120D01*
X648074Y591132D01*
X656270Y588269D01*
X671579Y588674D01*
X686315Y595972D01*
X755309Y632072D01*
X765611D01*
X774097Y631000D01*
X920831Y593172D01*
X938253D01*
X1090403Y632252D01*
X1099250D01*
X1267698Y596962D01*
X1274540D01*
X1286595Y599990D01*
X1336826Y636928D01*
X1347048Y645700D01*
X1357714Y659073D01*
X1360190Y661238D01*
X1367911Y667726D01*
X1374769Y669135D01*
X1375221Y669587D01*
X1375229Y669615D01*
X1374668Y671708D01*
G01X406770Y833745D02*
Y832105D01*
X419212Y797950D01*
X419211D01*
X431075Y765379D01*
X431076D01*
X432145Y764033D01*
X432820Y763955D01*
X433891Y762608D01*
X433813Y761933D01*
X457110Y732608D01*
X518501Y674882D01*
X649150Y594371D01*
X656041Y591964D01*
X670666Y592351D01*
X684635Y599270D01*
X753828Y635472D01*
X765825D01*
X774737Y634347D01*
X921269Y596572D01*
X937822D01*
X1089427Y635512D01*
X1100271D01*
X1268051Y600362D01*
X1274118D01*
X1285277Y603167D01*
X1294498Y610218D01*
X1328585Y639591D01*
X1330294Y639463D01*
X1330970Y638679D01*
X1331787Y638619D01*
X1333548Y640136D01*
X1333608Y640952D01*
X1332932Y641737D01*
X1333060Y643446D01*
X1335497Y645547D01*
X1337206Y645419D01*
X1337882Y644635D01*
X1338699Y644575D01*
X1340460Y646092D01*
X1340520Y646908D01*
X1339844Y647693D01*
X1339971Y649403D01*
X1370559Y675758D01*
X1382447Y678639D01*
X1385844Y680835D01*
X1387528Y681452D01*
X1389756D01*
X1390595Y680614D01*
X1391076Y679781D01*
X1391078Y679778D01*
X1393206Y679208D01*
G01X405690Y833745D02*
Y831914D01*
X430120Y764844D01*
X456312Y731874D01*
X517841Y674020D01*
X648683Y593390D01*
X655872Y590879D01*
X670933Y591277D01*
X678131Y594842D01*
Y594843D01*
X685126Y598307D01*
X754094Y634392D01*
X765757D01*
X774534Y633284D01*
X921132Y595492D01*
X937959D01*
X1089564Y634432D01*
X1100159D01*
X1267939Y599282D01*
X1274252D01*
X1285757Y602173D01*
X1295179Y609379D01*
X1328951Y638480D01*
X1329768Y638419D01*
X1330444Y637635D01*
X1332153Y637508D01*
X1334592Y639610D01*
X1334719Y641319D01*
X1334043Y642103D01*
X1334104Y642920D01*
X1335863Y644436D01*
X1336680Y644375D01*
X1337356Y643591D01*
X1339065Y643464D01*
X1341504Y645566D01*
X1341631Y647275D01*
X1340955Y648059D01*
X1341016Y648876D01*
X1371067Y674769D01*
X1382880Y677632D01*
X1386329Y679862D01*
X1387720Y680372D01*
X1389308D01*
X1389730Y679950D01*
X1390140Y679240D01*
X1389568Y677108D01*
G01X410469Y833745D02*
Y832308D01*
X422512Y799247D01*
X422511D01*
X433946Y767853D01*
X433947D01*
X435244Y766220D01*
X435919Y766143D01*
X436989Y764795D01*
X436912Y764120D01*
X437981Y762774D01*
X438656Y762696D01*
X439727Y761349D01*
X439649Y760674D01*
X440718Y759328D01*
X441393Y759250D01*
X442464Y757903D01*
X442386Y757228D01*
X443455Y755882D01*
X444130Y755804D01*
X445201Y754457D01*
X445123Y753782D01*
X446192Y752436D01*
X446867Y752359D01*
X447938Y751011D01*
X447860Y750337D01*
X448930Y748990D01*
X448929D01*
X449604Y748913D01*
X450675Y747565D01*
X450598Y746890D01*
X451667Y745544D01*
X452342Y745467D01*
X453413Y744119D01*
X453336Y743444D01*
X461935Y732620D01*
X520530Y677525D01*
X650582Y597380D01*
X655531Y595652D01*
X669240Y596015D01*
X682859Y602761D01*
X751669Y638762D01*
X766032D01*
X775356Y637586D01*
X921690Y599862D01*
X937405D01*
X1089010Y638802D01*
X1100613D01*
X1268393Y603652D01*
X1273710D01*
X1283816Y606194D01*
X1292474Y612813D01*
X1350109Y662632D01*
X1350168Y663449D01*
X1346893Y667239D01*
X1347017Y668947D01*
X1349455Y671054D01*
X1351163Y670930D01*
X1354438Y667140D01*
X1355255Y667081D01*
X1357012Y668599D01*
X1357071Y669416D01*
X1353796Y673206D01*
X1353920Y674914D01*
X1356358Y677021D01*
X1358066Y676897D01*
X1361341Y673107D01*
X1362158Y673048D01*
X1368763Y678757D01*
X1373400Y679872D01*
X1374829Y680864D01*
X1375240Y681576D01*
X1374668Y683708D01*
G01X1393206Y693708D02*
X1391078Y694278D01*
X1391076Y694281D01*
X1390595Y695114D01*
X1389486Y696222D01*
X1387529D01*
X1385331Y695058D01*
X1381989Y690612D01*
X1381495Y690293D01*
X1368507Y687769D01*
X1367546Y686348D01*
X1367655Y685793D01*
X1367198Y685115D01*
X1364914Y684671D01*
X1364237Y685129D01*
X1364128Y685683D01*
X1362708Y686643D01*
X1357286Y685588D01*
X1355464Y684583D01*
X1337070Y665057D01*
X1337121Y663343D01*
X1339107Y661471D01*
X1339132Y660653D01*
X1337537Y658961D01*
X1336719Y658936D01*
X1334733Y660809D01*
X1333019Y660757D01*
X1330812Y658415D01*
X1330864Y656701D01*
X1332850Y654829D01*
X1332875Y654011D01*
X1331280Y652319D01*
X1330462Y652294D01*
X1328476Y654167D01*
X1326762Y654115D01*
X1324555Y651773D01*
X1324607Y650059D01*
X1326593Y648187D01*
X1326618Y647369D01*
X1325023Y645677D01*
X1324205Y645652D01*
X1322219Y647525D01*
X1320505Y647472D01*
X1316489Y643210D01*
X1316542Y641496D01*
X1317472Y640619D01*
X1317497Y639801D01*
X1315902Y638109D01*
X1315084Y638084D01*
X1314153Y638962D01*
X1312439Y638909D01*
X1290366Y615481D01*
X1282306Y609322D01*
X1273288Y607052D01*
X1268746D01*
X1100966Y642202D01*
X1088579D01*
X937013Y603272D01*
X922084D01*
X775996Y640933D01*
X766246Y642162D01*
X750652D01*
X681277Y605866D01*
X668839Y599707D01*
X656111Y599369D01*
X650579Y601301D01*
X522329Y680334D01*
X466903Y732455D01*
X439975Y766354D01*
X440067Y767155D01*
X439164Y768291D01*
X438365Y768383D01*
X436765Y770397D01*
X414170Y832425D01*
Y833745D01*
G01X409389D02*
Y832117D01*
X432991Y767318D01*
X461137Y731886D01*
X519870Y676663D01*
X650115Y596399D01*
X655362Y594567D01*
X669507Y594941D01*
X683350Y601798D01*
X751935Y637682D01*
X765964D01*
X775153Y636522D01*
Y636523D01*
X921553Y598782D01*
X937542D01*
X1089147Y637722D01*
X1100501D01*
X1268281Y602572D01*
X1273844D01*
X1284296Y605200D01*
X1293156Y611974D01*
X1351155Y662107D01*
X1351278Y663817D01*
X1348003Y667607D01*
X1348062Y668422D01*
X1349823Y669944D01*
X1350638Y669885D01*
X1353913Y666094D01*
X1355623Y665971D01*
X1358058Y668074D01*
X1358181Y669784D01*
X1354906Y673574D01*
X1354965Y674389D01*
X1356726Y675911D01*
X1357541Y675852D01*
X1360816Y672061D01*
X1362526Y671938D01*
X1369271Y677768D01*
X1373850Y678868D01*
X1375643Y680114D01*
X1376176Y681035D01*
X1376178Y681038D01*
X1378306Y681608D01*
G01X1389568Y691608D02*
X1390140Y693740D01*
X1389729Y694452D01*
X1389038Y695142D01*
X1387798D01*
X1386050Y694216D01*
X1382737Y689809D01*
X1381906Y689272D01*
X1369152Y686794D01*
X1368693Y686115D01*
X1368802Y685560D01*
X1367843Y684140D01*
X1364681Y683525D01*
X1363261Y684483D01*
X1363153Y685038D01*
X1362474Y685497D01*
X1357659Y684560D01*
X1356134Y683719D01*
X1338163Y664642D01*
X1338188Y663823D01*
X1340174Y661951D01*
X1340225Y660238D01*
X1338017Y657894D01*
X1336304Y657843D01*
X1334318Y659715D01*
X1333499Y659690D01*
X1331906Y658000D01*
X1331931Y657181D01*
X1333917Y655309D01*
X1333968Y653596D01*
X1331760Y651252D01*
X1330047Y651201D01*
X1328061Y653073D01*
X1327242Y653048D01*
X1325649Y651358D01*
X1325674Y650539D01*
X1327660Y648667D01*
X1327711Y646954D01*
X1325503Y644610D01*
X1323790Y644559D01*
X1321804Y646431D01*
X1320985Y646406D01*
X1317583Y642795D01*
X1317608Y641976D01*
X1318539Y641099D01*
X1318590Y639386D01*
X1316382Y637042D01*
X1314669Y636991D01*
X1313738Y637868D01*
X1312919Y637843D01*
X1291092Y614676D01*
X1282786Y608328D01*
X1273422Y605972D01*
X1268634D01*
X1100854Y641122D01*
X1088716D01*
X937150Y602192D01*
X921947D01*
X775793Y639870D01*
X766178Y641082D01*
X750918D01*
X681767Y604903D01*
X669106Y598633D01*
X655942Y598284D01*
X650112Y600320D01*
X521669Y679472D01*
X466105Y731721D01*
X435809Y769862D01*
X413090Y832234D01*
Y833745D01*
G01X417869D02*
Y831829D01*
X438916Y774055D01*
X440029Y772654D01*
X440703Y772577D01*
X441774Y771229D01*
X441697Y770555D01*
X442766Y769209D01*
X443441Y769131D01*
X444512Y767784D01*
X444434Y767109D01*
X445592Y765651D01*
X446267Y765574D01*
X447338Y764226D01*
X447260Y763551D01*
X448329Y762205D01*
X449004Y762127D01*
X450075Y760780D01*
X449997Y760105D01*
X451066Y758759D01*
X451741Y758682D01*
X452812Y757334D01*
X452734Y756659D01*
X472649Y731592D01*
X524160Y683149D01*
X650665Y605192D01*
X656691Y603087D01*
X667926Y603386D01*
X679598Y609165D01*
X749108Y645532D01*
X766458D01*
X776630Y644250D01*
X922551Y606632D01*
X936547D01*
X1088152Y645572D01*
X1101316D01*
X1269096Y610422D01*
X1272870D01*
X1280810Y612422D01*
X1288390Y618212D01*
X1303373Y634146D01*
X1303348Y634965D01*
X1300829Y637333D01*
X1300776Y639045D01*
X1302982Y641392D01*
X1304695Y641445D01*
X1307214Y639077D01*
X1308033Y639102D01*
X1309623Y640794D01*
X1309598Y641613D01*
X1307079Y643981D01*
X1307026Y645693D01*
X1309232Y648040D01*
X1310945Y648093D01*
X1313464Y645725D01*
X1314283Y645750D01*
X1315873Y647442D01*
X1315848Y648261D01*
X1313329Y650629D01*
X1313276Y652341D01*
X1315482Y654688D01*
X1317195Y654741D01*
X1319714Y652373D01*
X1320533Y652398D01*
X1322123Y654090D01*
X1322098Y654909D01*
X1319579Y657277D01*
X1319526Y658989D01*
X1321732Y661336D01*
X1323445Y661389D01*
X1325964Y659021D01*
X1326783Y659046D01*
X1328373Y660738D01*
X1328348Y661557D01*
X1325829Y663925D01*
X1325776Y665637D01*
X1327982Y667984D01*
X1329695Y668037D01*
X1332214Y665669D01*
X1333033Y665694D01*
X1334623Y667386D01*
X1334598Y668205D01*
X1332079Y670573D01*
X1332026Y672285D01*
X1334232Y674632D01*
X1335945Y674685D01*
X1338464Y672317D01*
X1339283Y672342D01*
X1353312Y687255D01*
X1356322Y688917D01*
X1367624Y691125D01*
X1368074Y691794D01*
X1369498Y692072D01*
X1370167Y691622D01*
X1373679Y692308D01*
X1374954Y693080D01*
X1375240Y693576D01*
X1374668Y695708D01*
G01X416789Y833745D02*
Y831638D01*
X437960Y773520D01*
X471851Y730858D01*
X523500Y682287D01*
X650198Y604211D01*
X656522Y602002D01*
X668192Y602312D01*
X680088Y608202D01*
X749374Y644452D01*
X766390D01*
X776427Y643187D01*
X922414Y605552D01*
X936684D01*
X1088289Y644492D01*
X1101204D01*
X1268984Y609342D01*
X1273004D01*
X1281290Y611428D01*
X1289117Y617407D01*
X1304467Y633732D01*
X1304415Y635446D01*
X1301895Y637814D01*
X1301870Y638631D01*
X1303463Y640326D01*
X1304281Y640351D01*
X1306800Y637983D01*
X1308514Y638035D01*
X1310717Y640380D01*
X1310665Y642094D01*
X1308145Y644462D01*
X1308120Y645279D01*
X1309713Y646974D01*
X1310531Y646999D01*
X1313050Y644631D01*
X1314764Y644683D01*
X1316967Y647028D01*
X1316915Y648742D01*
X1314395Y651110D01*
X1314370Y651927D01*
X1315963Y653622D01*
X1316781Y653647D01*
X1319300Y651279D01*
X1321014Y651331D01*
X1323217Y653676D01*
X1323165Y655390D01*
X1320645Y657758D01*
X1320620Y658575D01*
X1322213Y660270D01*
X1323031Y660295D01*
X1325550Y657927D01*
X1327264Y657979D01*
X1329467Y660324D01*
X1329415Y662038D01*
X1326895Y664406D01*
X1326870Y665223D01*
X1328463Y666918D01*
X1329281Y666943D01*
X1331800Y664575D01*
X1333514Y664627D01*
X1335717Y666972D01*
X1335665Y668686D01*
X1333145Y671054D01*
X1333120Y671871D01*
X1334713Y673566D01*
X1335531Y673591D01*
X1338050Y671223D01*
X1339763Y671276D01*
X1353983Y686391D01*
X1356696Y687889D01*
X1374075Y691284D01*
X1375751Y692299D01*
X1376169Y693024D01*
X1376176Y693035D01*
X1376178Y693038D01*
X1378306Y693608D01*
G01X1389568Y706108D02*
X1390140Y708240D01*
X1389730Y708950D01*
X1389268Y709412D01*
X1387640D01*
X1386140Y708292D01*
X1383092Y702319D01*
X1381386Y701016D01*
X1377153Y700095D01*
X1374190Y699808D01*
X1354440Y693917D01*
X1295716Y663102D01*
X1239579Y647256D01*
X1235728Y647176D01*
X1235160Y646586D01*
X1235316Y638987D01*
X1234129Y637752D01*
X1230909Y637685D01*
X1229674Y638871D01*
X1229518Y646470D01*
X1228928Y647038D01*
X1226607Y646989D01*
X1226038Y646397D01*
X1226194Y638799D01*
X1225007Y637564D01*
X1221787Y637497D01*
X1220552Y638683D01*
X1220396Y646282D01*
X1219806Y646850D01*
X1217485Y646801D01*
X1216916Y646209D01*
X1217072Y638611D01*
X1215885Y637376D01*
X1212665Y637309D01*
X1211430Y638495D01*
X1211274Y646094D01*
X1210684Y646662D01*
X1208363Y646613D01*
X1207794Y646021D01*
X1207950Y638423D01*
X1206763Y637188D01*
X1203543Y637121D01*
X1202308Y638307D01*
X1202152Y645906D01*
X1201562Y646474D01*
X1199241Y646425D01*
X1198672Y645833D01*
X1198828Y638235D01*
X1197641Y637000D01*
X1194421Y636933D01*
X1193186Y638119D01*
X1193030Y645716D01*
X1192438Y646289D01*
X1191290Y646270D01*
X1191250D01*
X1105676Y647752D01*
X1087756D01*
X936267Y608842D01*
X922832D01*
X777046Y646426D01*
X766597Y647742D01*
X747682D01*
X678409Y611500D01*
X667280Y605989D01*
X657101Y605718D01*
X650048Y608181D01*
X525463Y684957D01*
X476649Y730863D01*
X440414Y776472D01*
X420490Y831167D01*
Y833745D01*
G01X1393206Y708208D02*
X1391078Y708778D01*
X1391076Y708781D01*
X1390595Y709614D01*
X1389716Y710492D01*
X1387281D01*
X1385292Y709007D01*
X1385177Y708783D01*
X1385178D01*
X1382241Y703029D01*
X1380921Y702021D01*
X1376985Y701164D01*
X1373982Y700873D01*
X1354031Y694923D01*
X1295314Y664111D01*
X1239419Y648334D01*
X1235259Y648247D01*
X1234070Y647012D01*
X1234227Y639413D01*
X1233660Y638823D01*
X1231335Y638775D01*
X1230745Y639340D01*
X1230590Y646939D01*
X1229354Y648128D01*
X1226137Y648060D01*
X1224949Y646823D01*
X1225105Y639225D01*
X1224538Y638635D01*
X1222213Y638587D01*
X1221623Y639152D01*
X1221468Y646751D01*
X1220232Y647940D01*
X1217015Y647872D01*
X1215827Y646635D01*
X1215983Y639037D01*
X1215416Y638447D01*
X1213091Y638399D01*
X1212501Y638964D01*
X1212346Y646563D01*
X1211110Y647752D01*
X1207893Y647684D01*
X1206705Y646447D01*
X1206861Y638849D01*
X1206294Y638259D01*
X1203969Y638211D01*
X1203379Y638776D01*
X1203224Y646375D01*
X1201988Y647564D01*
X1198771Y647496D01*
X1197583Y646259D01*
X1197739Y638661D01*
X1197172Y638071D01*
X1194847Y638023D01*
X1194257Y638588D01*
X1194101Y646183D01*
X1192868Y647377D01*
X1191272Y647351D01*
X1191269Y647352D01*
Y647351D01*
X1105686Y648832D01*
X1087619D01*
X936130Y609922D01*
X922969D01*
X777249Y647489D01*
X766665Y648822D01*
X747416D01*
X677919Y612463D01*
X667013Y607063D01*
X657270Y606803D01*
X650515Y609162D01*
X526123Y685819D01*
X477447Y731597D01*
X441370Y777007D01*
X423279Y826668D01*
X423620Y827398D01*
X423123Y828762D01*
X422392Y829102D01*
X421570Y831358D01*
Y833745D01*
G01X1378306Y705608D02*
X1376178Y705038D01*
X1376176Y705035D01*
X1375592Y704025D01*
X1373702Y703158D01*
X1325681Y688801D01*
X1322236Y686993D01*
X1321992Y686211D01*
X1323748Y682864D01*
X1323238Y681228D01*
X1320387Y679732D01*
X1318751Y680242D01*
X1316995Y683589D01*
X1316213Y683833D01*
X1314157Y682754D01*
X1313913Y681972D01*
X1315669Y678625D01*
X1315159Y676989D01*
X1312308Y675493D01*
X1310672Y676003D01*
X1308916Y679350D01*
X1308134Y679594D01*
X1306078Y678515D01*
X1305834Y677733D01*
X1307590Y674386D01*
X1307080Y672750D01*
X1304229Y671254D01*
X1302593Y671764D01*
X1300837Y675111D01*
X1300055Y675355D01*
X1297999Y674276D01*
X1297755Y673494D01*
X1299511Y670147D01*
X1299001Y668511D01*
X1296150Y667015D01*
X1294514Y667525D01*
X1292758Y670872D01*
X1291976Y671116D01*
X1268626Y658864D01*
X1239092Y650528D01*
X1190920Y649545D01*
X1103013Y651062D01*
X1087456D01*
X935851Y612122D01*
X923249D01*
X777663Y649655D01*
X766803Y651022D01*
X745966D01*
X692489Y623043D01*
X690854Y623556D01*
X688795Y627490D01*
X688015Y627734D01*
X685953Y626655D01*
X685709Y625875D01*
X687768Y621941D01*
X687255Y620306D01*
X676730Y614799D01*
X666367Y609668D01*
X657681Y609437D01*
X650023Y612111D01*
X632965Y622621D01*
X632861Y623057D01*
X632862D01*
X632569Y624289D01*
X636653Y630916D01*
X636464Y631711D01*
X634483Y632932D01*
X633688Y632743D01*
X629604Y626116D01*
X627936Y625720D01*
X625388Y627290D01*
X625197Y627408D01*
X625093Y627844D01*
X625094D01*
X624801Y629076D01*
X629515Y636726D01*
X629326Y637521D01*
X627345Y638742D01*
X626550Y638553D01*
X621836Y630903D01*
X620168Y630507D01*
X617429Y632195D01*
X617033Y633863D01*
X620521Y639523D01*
X620332Y640318D01*
X618351Y641539D01*
X617556Y641350D01*
X614068Y635690D01*
X612400Y635294D01*
X527261Y687763D01*
X479336Y732834D01*
X444412Y776797D01*
X424189Y832305D01*
Y833745D01*
G01X1374668Y707708D02*
X1375240Y705576D01*
X1374829Y704864D01*
X1373320Y704172D01*
X1325271Y689807D01*
X1321338Y687742D01*
X1320827Y686105D01*
X1322583Y682758D01*
X1322339Y681977D01*
X1320281Y680897D01*
X1319500Y681140D01*
X1317744Y684487D01*
X1316107Y684998D01*
X1313259Y683503D01*
X1312748Y681866D01*
X1314504Y678519D01*
X1314260Y677738D01*
X1312202Y676658D01*
X1311421Y676901D01*
X1309665Y680248D01*
X1308028Y680759D01*
X1305180Y679264D01*
X1304669Y677627D01*
X1306425Y674280D01*
X1306181Y673499D01*
X1304123Y672419D01*
X1303342Y672662D01*
X1301586Y676009D01*
X1299949Y676520D01*
X1297101Y675025D01*
X1296590Y673388D01*
X1298346Y670041D01*
X1298102Y669260D01*
X1296044Y668180D01*
X1295263Y668423D01*
X1293507Y671770D01*
X1291870Y672281D01*
X1268224Y659873D01*
X1238932Y651606D01*
X1190918Y650626D01*
X1103023Y652142D01*
X1087319D01*
X935714Y613202D01*
X923386D01*
X777866Y650718D01*
X766871Y652102D01*
X745700D01*
X692385Y624208D01*
X691604Y624453D01*
X689545Y628387D01*
X687911Y628899D01*
X685056Y627405D01*
X684544Y625771D01*
X686603Y621837D01*
X686358Y621056D01*
X676240Y615762D01*
X666100Y610742D01*
X657850Y610522D01*
X650490Y613092D01*
X633913Y623306D01*
X633724Y624103D01*
X637808Y630730D01*
X637412Y632396D01*
X634669Y634087D01*
X633003Y633691D01*
X628919Y627064D01*
X628122Y626875D01*
X626145Y628093D01*
X625956Y628890D01*
X630670Y636540D01*
X630274Y638206D01*
X627531Y639897D01*
X625865Y639501D01*
X621151Y631851D01*
X620354Y631662D01*
X618377Y632880D01*
X618188Y633677D01*
X621676Y639337D01*
X621280Y641003D01*
X618537Y642694D01*
X616871Y642298D01*
X613383Y636638D01*
X612586Y636449D01*
X527921Y688625D01*
X480134Y733568D01*
X445368Y777332D01*
X434703Y806605D01*
X435043Y807336D01*
X434547Y808699D01*
X433815Y809040D01*
X432967Y811369D01*
X433308Y812100D01*
X432812Y813463D01*
X432080Y813803D01*
X430972Y816845D01*
X431313Y817575D01*
X430817Y818939D01*
X430085Y819279D01*
X429589Y820641D01*
X429930Y821371D01*
X429434Y822735D01*
X428702Y823075D01*
X428206Y824437D01*
X428547Y825167D01*
X428051Y826531D01*
X427319Y826871D01*
X426823Y828233D01*
X427163Y828963D01*
X426667Y830327D01*
X425936Y830666D01*
X425269Y832497D01*
Y833745D01*
G01X430132D02*
Y833029D01*
X431412Y829412D01*
X431411D01*
X432024Y829120D01*
X432598Y827497D01*
X432305Y826885D01*
X432878Y825264D01*
X433492Y824971D01*
X434065Y823349D01*
X433773Y822736D01*
X450046Y776724D01*
X483106Y735687D01*
X530700Y690761D01*
X539891Y685121D01*
X540688Y685312D01*
X541225Y686187D01*
X542891Y686585D01*
X545636Y684899D01*
X546034Y683233D01*
X545497Y682358D01*
X545688Y681561D01*
X547666Y680345D01*
X548463Y680536D01*
X549000Y681411D01*
X550666Y681809D01*
X553411Y680123D01*
X553809Y678457D01*
X553272Y677582D01*
X553463Y676785D01*
X555441Y675569D01*
X556238Y675760D01*
X557406Y677663D01*
X559072Y678061D01*
X561817Y676375D01*
X562215Y674709D01*
X561047Y672806D01*
X561238Y672009D01*
X563216Y670793D01*
X564013Y670984D01*
X565048Y672670D01*
X566713Y673068D01*
X569458Y671382D01*
X569856Y669715D01*
X568822Y668030D01*
X569013Y667233D01*
X599291Y648638D01*
X604559Y647104D01*
X608799Y647032D01*
X609387Y647602D01*
X609451Y651400D01*
X610682Y652591D01*
X613903Y652536D01*
X615094Y651304D01*
X615030Y647507D01*
X615600Y646919D01*
X620566Y646835D01*
X621154Y647405D01*
X621173Y648507D01*
X622404Y649698D01*
X625625Y649644D01*
X626816Y648413D01*
X626797Y647311D01*
X627367Y646723D01*
X636809Y646566D01*
X656230Y653937D01*
X656578Y654008D01*
X663502Y654237D01*
X668657Y652885D01*
X674083Y650788D01*
Y650789D01*
X674084Y650788D01*
X684491Y650529D01*
X685673Y649288D01*
X685560Y644747D01*
X684319Y643565D01*
X682954Y643598D01*
X682361Y643035D01*
X682303Y640710D01*
X682867Y640118D01*
X684232Y640083D01*
X685414Y638842D01*
X685281Y633473D01*
X685846Y632880D01*
X688171Y632822D01*
X688763Y633386D01*
X689155Y649201D01*
X690396Y650383D01*
X693612Y650303D01*
X694794Y649062D01*
X694402Y633247D01*
X694967Y632654D01*
X697292Y632596D01*
X697884Y633160D01*
X697969Y636543D01*
X699210Y637725D01*
X704418Y637597D01*
X705011Y638160D01*
X705069Y640485D01*
X704505Y641077D01*
X699297Y641207D01*
X698115Y642448D01*
X698276Y648975D01*
X699517Y650157D01*
X714429Y649791D01*
X728122Y652206D01*
X732170Y651492D01*
X733720D01*
X744757Y655413D01*
X767212D01*
X778081Y654045D01*
X923802Y616477D01*
X935299D01*
X1086904Y655417D01*
X1103052D01*
X1190912Y653903D01*
X1238446Y654873D01*
X1267005Y662933D01*
X1325128Y693428D01*
X1342454Y700380D01*
X1344508Y699501D01*
X1346863Y700446D01*
X1347741Y702499D01*
X1352665Y704475D01*
X1354240Y703799D01*
X1354587Y702936D01*
X1355339Y702614D01*
X1357498Y703481D01*
X1357819Y704232D01*
X1357472Y705096D01*
X1358148Y706673D01*
X1361133Y707872D01*
X1362708Y707196D01*
X1363055Y706333D01*
X1363807Y706011D01*
X1365966Y706878D01*
X1366287Y707629D01*
X1365940Y708494D01*
X1366616Y710069D01*
X1371780Y712142D01*
X1380794Y714006D01*
X1382002Y714759D01*
X1382674Y715621D01*
X1383730Y722008D01*
X1384666Y723893D01*
X1386538Y724982D01*
X1389719D01*
X1390588Y724114D01*
X1391069Y723281D01*
X1391071Y723278D01*
X1393199Y722708D01*
G01X429052Y833745D02*
Y832843D01*
X449089Y776190D01*
X482311Y734952D01*
X530039Y689898D01*
X539708Y683966D01*
X541375Y684366D01*
X541912Y685240D01*
X542707Y685430D01*
X544689Y684212D01*
X544879Y683417D01*
X544342Y682541D01*
X544741Y680874D01*
X547482Y679190D01*
X549150Y679590D01*
X549687Y680464D01*
X550482Y680654D01*
X552464Y679436D01*
X552654Y678641D01*
X552117Y677765D01*
X552516Y676098D01*
X555257Y674414D01*
X556925Y674814D01*
X558093Y676716D01*
X558888Y676906D01*
X560870Y675688D01*
X561060Y674893D01*
X559892Y672989D01*
X560291Y671322D01*
X563032Y669638D01*
X564700Y670037D01*
X565735Y671723D01*
X566529Y671913D01*
X568511Y670696D01*
X568701Y669899D01*
X567667Y668213D01*
X568066Y666546D01*
X598849Y647641D01*
X604396Y646026D01*
X609229Y645944D01*
X610460Y647137D01*
X610524Y650934D01*
X611112Y651503D01*
X613437Y651463D01*
X614006Y650875D01*
X613942Y647077D01*
X615135Y645846D01*
X620996Y645747D01*
X622227Y646940D01*
X622246Y648041D01*
X622834Y648610D01*
X625159Y648571D01*
X625728Y647984D01*
X625709Y646881D01*
X626902Y645650D01*
X636999Y645482D01*
X656533Y652896D01*
X656706Y652931D01*
X663380Y653152D01*
X668324Y651855D01*
X673869Y649712D01*
X684017Y649460D01*
X684582Y648867D01*
X684491Y645221D01*
X683898Y644656D01*
X682533Y644690D01*
X681292Y643509D01*
X681212Y640289D01*
X682393Y639049D01*
X683758Y639014D01*
X684323Y638421D01*
X684190Y633052D01*
X685372Y631811D01*
X688592Y631731D01*
X689832Y632912D01*
X690224Y648727D01*
X690817Y649292D01*
X693138Y649234D01*
X693703Y648641D01*
X693311Y632826D01*
X694493Y631585D01*
X697713Y631505D01*
X698953Y632686D01*
X699038Y636069D01*
X699631Y636634D01*
X704839Y636505D01*
X706080Y637686D01*
X706160Y640906D01*
X704979Y642146D01*
X699771Y642276D01*
X699206Y642869D01*
X699345Y648501D01*
X699938Y649066D01*
X714402Y648710D01*
X714599D01*
X714616Y648727D01*
X728122Y651109D01*
X732075Y650412D01*
X733907D01*
X744944Y654333D01*
X767144D01*
X777878Y652982D01*
X923665Y615397D01*
X935436D01*
X1087041Y654337D01*
X1103042D01*
X1190914Y652822D01*
X1238606Y653795D01*
X1267407Y661924D01*
X1325581Y692446D01*
X1342441Y699210D01*
X1344495Y698331D01*
X1347681Y699609D01*
X1348559Y701663D01*
X1352651Y703305D01*
X1353404Y702982D01*
X1353751Y702118D01*
X1355326Y701445D01*
X1358316Y702644D01*
X1358989Y704219D01*
X1358642Y705083D01*
X1358965Y705837D01*
X1361119Y706702D01*
X1361872Y706379D01*
X1362219Y705515D01*
X1363794Y704842D01*
X1366784Y706041D01*
X1367457Y707616D01*
X1367110Y708480D01*
X1367433Y709233D01*
X1372093Y711103D01*
X1381202Y712987D01*
X1382737Y713943D01*
X1383695Y715174D01*
X1384770Y721672D01*
X1385490Y723122D01*
X1386830Y723902D01*
X1389271D01*
X1389723Y723450D01*
X1390133Y722740D01*
X1389561Y720608D01*
G01X434517Y833245D02*
Y831884D01*
X435090Y830263D01*
X435704Y829970D01*
X436277Y828348D01*
X435985Y827735D01*
X436558Y826114D01*
X437172Y825821D01*
X437745Y824199D01*
X437453Y823586D01*
X438026Y821965D01*
X438640Y821672D01*
X439213Y820050D01*
X438921Y819437D01*
X439494Y817816D01*
X440108Y817523D01*
X440681Y815901D01*
X440389Y815288D01*
X440962Y813667D01*
X441576Y813374D01*
X442149Y811752D01*
X441856Y811139D01*
X442429Y809518D01*
X443043Y809225D01*
X443616Y807603D01*
X443323Y806990D01*
X453861Y777192D01*
X485373Y738081D01*
X526593Y699174D01*
X578244Y672798D01*
X578778Y671150D01*
X576746Y667172D01*
X576998Y666394D01*
X579069Y665336D01*
X579847Y665588D01*
X581879Y669566D01*
X583509Y670095D01*
X586815Y668407D01*
X591278Y667281D01*
X592159Y665809D01*
X590456Y659065D01*
X590876Y658362D01*
X593131Y657792D01*
X593833Y658212D01*
X595534Y664956D01*
X597006Y665837D01*
X600125Y665048D01*
X601005Y663576D01*
X599303Y656832D01*
X599723Y656129D01*
X601978Y655559D01*
X602680Y655979D01*
X604381Y662723D01*
X605852Y663604D01*
X612816Y661847D01*
X618429Y661714D01*
X619614Y660475D01*
X619455Y653854D01*
X620020Y653262D01*
X622345Y653206D01*
X622937Y653771D01*
X623095Y660391D01*
X624335Y661575D01*
X627552Y661497D01*
X628736Y660258D01*
X628577Y653637D01*
X629142Y653045D01*
X631467Y652989D01*
X632059Y653554D01*
X632217Y660174D01*
X633457Y661358D01*
X636674Y661280D01*
X637858Y660041D01*
X637699Y653420D01*
X638264Y652828D01*
X640589Y652772D01*
X641181Y653337D01*
X641339Y659957D01*
X642578Y661141D01*
X676908Y660325D01*
X678093Y659086D01*
X678001Y655222D01*
X678566Y654630D01*
X680891Y654574D01*
X681482Y655139D01*
X681574Y659001D01*
X682814Y660186D01*
X686030Y660108D01*
X687215Y658868D01*
X687123Y655005D01*
X687688Y654413D01*
X690013Y654357D01*
X690604Y654922D01*
X690696Y658784D01*
X691936Y659969D01*
X695152Y659891D01*
X696337Y658651D01*
X696245Y654788D01*
X696810Y654196D01*
X699135Y654140D01*
X699726Y654705D01*
X699818Y658567D01*
X701058Y659752D01*
X704274Y659674D01*
X705459Y658434D01*
X705367Y654571D01*
X705932Y653979D01*
X708257Y653923D01*
X708848Y654488D01*
X708940Y658350D01*
X710180Y659535D01*
X713396Y659457D01*
X714581Y658217D01*
X714489Y654354D01*
X715054Y653762D01*
X717379Y653706D01*
X717970Y654271D01*
X718062Y658133D01*
X719301Y659318D01*
X745352Y658701D01*
X772160D01*
X774464Y658411D01*
X924224Y619801D01*
X934878D01*
X1086483Y658741D01*
X1103082D01*
X1190906Y657229D01*
X1237953Y658189D01*
X1265768Y666039D01*
X1333041Y701337D01*
X1356074Y709859D01*
X1356416Y710603D01*
X1354737Y715140D01*
X1355453Y716696D01*
X1358474Y717815D01*
X1360030Y717099D01*
X1361709Y712562D01*
X1362453Y712220D01*
X1364631Y713026D01*
X1364973Y713770D01*
X1363294Y718307D01*
X1364010Y719863D01*
X1367031Y720982D01*
X1368587Y720266D01*
X1370266Y715729D01*
X1371010Y715387D01*
X1374655Y716736D01*
X1374890Y716972D01*
X1375240Y717576D01*
X1374668Y719708D01*
G01X433437Y833245D02*
Y831698D01*
X452904Y776658D01*
X484578Y737346D01*
X525964Y698282D01*
X577354Y672039D01*
X577612Y671243D01*
X575580Y667265D01*
X576108Y665635D01*
X578976Y664170D01*
X580606Y664698D01*
X582638Y668676D01*
X583417Y668929D01*
X586432Y667389D01*
X590580Y666342D01*
X591001Y665639D01*
X589299Y658895D01*
X590178Y657424D01*
X593301Y656635D01*
X594771Y657514D01*
X596473Y664258D01*
X597176Y664679D01*
X599427Y664110D01*
X599848Y663406D01*
X598146Y656662D01*
X599025Y655191D01*
X602148Y654402D01*
X603618Y655281D01*
X605320Y662025D01*
X606023Y662446D01*
X612669Y660770D01*
X617957Y660644D01*
X618523Y660052D01*
X618364Y653432D01*
X619547Y652193D01*
X622767Y652115D01*
X624006Y653298D01*
X624165Y659918D01*
X624757Y660484D01*
X627079Y660427D01*
X627645Y659835D01*
X627486Y653215D01*
X628669Y651976D01*
X631889Y651898D01*
X633128Y653081D01*
X633287Y659701D01*
X633879Y660267D01*
X636201Y660210D01*
X636767Y659618D01*
X636608Y652998D01*
X637791Y651759D01*
X641011Y651681D01*
X642250Y652864D01*
X642409Y659484D01*
X643001Y660050D01*
X676436Y659255D01*
X677002Y658663D01*
X676910Y654800D01*
X678093Y653561D01*
X681313Y653483D01*
X682552Y654666D01*
X682644Y658529D01*
X683236Y659095D01*
X685557Y659038D01*
X686124Y658445D01*
X686032Y654583D01*
X687215Y653344D01*
X690435Y653266D01*
X691674Y654449D01*
X691766Y658312D01*
X692358Y658878D01*
X694679Y658821D01*
X695246Y658228D01*
X695154Y654366D01*
X696337Y653127D01*
X699557Y653049D01*
X700796Y654232D01*
X700888Y658095D01*
X701480Y658661D01*
X703801Y658604D01*
X704368Y658011D01*
X704276Y654149D01*
X705459Y652910D01*
X708679Y652832D01*
X709918Y654015D01*
X710010Y657878D01*
X710602Y658444D01*
X712923Y658387D01*
X713490Y657794D01*
X713398Y653932D01*
X714581Y652693D01*
X717801Y652615D01*
X719040Y653798D01*
X719132Y657661D01*
X719724Y658227D01*
X745339Y657621D01*
X772092D01*
X774261Y657348D01*
X924087Y618721D01*
X935015D01*
X1086620Y657661D01*
X1103072D01*
X1190908Y656148D01*
X1238113Y657111D01*
X1266170Y665030D01*
X1333481Y700348D01*
X1356869Y709001D01*
X1357585Y710558D01*
X1355906Y715095D01*
X1356248Y715838D01*
X1358429Y716646D01*
X1359172Y716304D01*
X1360851Y711767D01*
X1362408Y711051D01*
X1365426Y712168D01*
X1366142Y713725D01*
X1364463Y718262D01*
X1364805Y719005D01*
X1366986Y719813D01*
X1367729Y719471D01*
X1369408Y714934D01*
X1370965Y714218D01*
X1375252Y715804D01*
Y715805D01*
X1375754Y716307D01*
X1376176Y717035D01*
X1376178Y717038D01*
X1378306Y717608D01*
G01X1385338Y735098D02*
X1385910Y737230D01*
X1385903Y737243D01*
X1384676Y739367D01*
X1382700Y742084D01*
X1380472Y744312D01*
X1378942D01*
X1349607Y716172D01*
X1332823Y704113D01*
X1264051Y668029D01*
X1237600Y660564D01*
X1190902Y659611D01*
X1103472Y661100D01*
X1080731D01*
X929212Y622182D01*
X895914Y630766D01*
X895042Y632242D01*
X897434Y641519D01*
X897018Y642224D01*
X894766Y642805D01*
X894062Y642389D01*
X891670Y633112D01*
X890194Y632240D01*
X887079Y633044D01*
X886207Y634520D01*
X888599Y643797D01*
X888183Y644502D01*
X885931Y645083D01*
X885227Y644667D01*
X882835Y635390D01*
X881359Y634518D01*
X878244Y635322D01*
X877372Y636798D01*
X879764Y646075D01*
X879348Y646780D01*
X877096Y647361D01*
X876392Y646945D01*
X874000Y637668D01*
X872524Y636796D01*
X869409Y637600D01*
X868537Y639076D01*
X870929Y648353D01*
X870513Y649058D01*
X868261Y649639D01*
X867557Y649223D01*
X865165Y639946D01*
X863689Y639074D01*
X860574Y639878D01*
X859702Y641354D01*
X862094Y650631D01*
X861678Y651336D01*
X859426Y651917D01*
X858722Y651501D01*
X856330Y642224D01*
X854854Y641352D01*
X851739Y642156D01*
X850867Y643632D01*
X853259Y652909D01*
X852843Y653614D01*
X850591Y654195D01*
X849887Y653779D01*
X847495Y644502D01*
X846019Y643630D01*
X842904Y644434D01*
X842032Y645910D01*
X844424Y655187D01*
X844008Y655892D01*
X841756Y656473D01*
X841052Y656057D01*
X838660Y646780D01*
X837184Y645908D01*
X785837Y659146D01*
X768304Y661402D01*
X745470D01*
X611895Y664387D01*
X587440Y670557D01*
X528061Y700880D01*
X518692Y709719D01*
X518644Y711433D01*
X519312Y712140D01*
X519288Y712958D01*
X517597Y714555D01*
X516780Y714531D01*
X516112Y713822D01*
X514398Y713774D01*
X512057Y715981D01*
X512009Y717696D01*
X512677Y718403D01*
X512653Y719221D01*
X510962Y720818D01*
X510145Y720794D01*
X509477Y720085D01*
X507763Y720037D01*
X505422Y722244D01*
X505374Y723959D01*
X506042Y724666D01*
X506018Y725484D01*
X504327Y727081D01*
X503510Y727057D01*
X502842Y726348D01*
X501128Y726300D01*
X498787Y728507D01*
X498739Y730222D01*
X499407Y730929D01*
X499383Y731747D01*
X497692Y733344D01*
X496875Y733320D01*
X496207Y732611D01*
X494492Y732563D01*
X486705Y739914D01*
X456756Y777084D01*
X437139Y832549D01*
Y833245D01*
G01X1388976Y737198D02*
X1386848Y737768D01*
X1385555Y740007D01*
X1385545Y740009D01*
X1383524Y742789D01*
X1380920Y745392D01*
X1378507D01*
X1348914Y717005D01*
X1332254Y705035D01*
X1263649Y669038D01*
X1237440Y661642D01*
X1190900Y660692D01*
X1103482Y662180D01*
X1080594D01*
X929212Y623298D01*
X896617Y631701D01*
X896200Y632406D01*
X898592Y641683D01*
X897721Y643158D01*
X894602Y643963D01*
X893127Y643092D01*
X890735Y633815D01*
X890030Y633398D01*
X887782Y633979D01*
X887365Y634684D01*
X889757Y643961D01*
X888886Y645436D01*
X885767Y646241D01*
X884292Y645370D01*
X881900Y636093D01*
X881195Y635676D01*
X878947Y636257D01*
X878530Y636962D01*
X880922Y646239D01*
X880051Y647714D01*
X876932Y648519D01*
X875457Y647648D01*
X873065Y638371D01*
X872360Y637954D01*
X870112Y638535D01*
X869695Y639240D01*
X872087Y648517D01*
X871216Y649992D01*
X868097Y650797D01*
X866622Y649926D01*
X864230Y640649D01*
X863525Y640232D01*
X861277Y640813D01*
X860860Y641518D01*
X863252Y650795D01*
X862381Y652270D01*
X859262Y653075D01*
X857787Y652204D01*
X855395Y642927D01*
X854690Y642510D01*
X852442Y643091D01*
X852025Y643796D01*
X854417Y653073D01*
X853546Y654548D01*
X850427Y655353D01*
X848952Y654482D01*
X846560Y645205D01*
X845855Y644788D01*
X843607Y645369D01*
X843190Y646074D01*
X845582Y655351D01*
X844711Y656826D01*
X841592Y657631D01*
X840117Y656760D01*
X837725Y647483D01*
X837020Y647066D01*
X786042Y660209D01*
X768374Y662482D01*
X745483D01*
X612041Y665465D01*
X587823Y671575D01*
X528690Y701772D01*
X519760Y710198D01*
X519737Y711016D01*
X520405Y711724D01*
X520355Y713437D01*
X518013Y715648D01*
X516301Y715598D01*
X515633Y714890D01*
X514814Y714867D01*
X513125Y716460D01*
X513102Y717279D01*
X513770Y717987D01*
X513720Y719700D01*
X511378Y721911D01*
X509666Y721861D01*
X508998Y721153D01*
X508179Y721130D01*
X506490Y722723D01*
X506467Y723542D01*
X507135Y724250D01*
X507085Y725963D01*
X504743Y728174D01*
X503031Y728124D01*
X502363Y727416D01*
X501544Y727393D01*
X499855Y728986D01*
X499832Y729805D01*
X500500Y730513D01*
X500450Y732226D01*
X498108Y734437D01*
X496396Y734387D01*
X495728Y733679D01*
X494909Y733656D01*
X487500Y740649D01*
X457713Y777618D01*
X441096Y824604D01*
X441388Y825216D01*
X440815Y826839D01*
X440201Y827131D01*
X439567Y828926D01*
X439914Y829653D01*
X439430Y831021D01*
X438703Y831367D01*
X438219Y832735D01*
Y833245D01*
G01X1411431Y833585D02*
X1411430Y833584D01*
Y826551D01*
X1406902Y783628D01*
X1396004Y770195D01*
X1395202Y770111D01*
X1394288Y768984D01*
X1394371Y768183D01*
X1393458Y767057D01*
X1392657Y766974D01*
X1391742Y765847D01*
X1391826Y765045D01*
X1390658Y763605D01*
X1346632Y721012D01*
X1330117Y708995D01*
X1262395Y673589D01*
X1261746Y673212D01*
X1236494Y666152D01*
X1190820Y665301D01*
X1074919Y668125D01*
X939354Y668774D01*
X829846D01*
X789009Y666982D01*
X612655Y669914D01*
X589367Y675874D01*
X538283Y702028D01*
X521412Y724670D01*
X489027Y746194D01*
X483630Y752834D01*
X483700Y753509D01*
X482614Y754845D01*
X481939Y754915D01*
X480694Y756447D01*
X480763Y757122D01*
X479678Y758458D01*
X479002Y758528D01*
X477918Y759862D01*
X477987Y760537D01*
X476902Y761873D01*
X476226Y761943D01*
X475142Y763277D01*
X475211Y763952D01*
X474126Y765288D01*
X473450Y765358D01*
X472366Y766692D01*
X472435Y767367D01*
X471350Y768703D01*
X470674Y768773D01*
X469590Y770107D01*
X469660Y770782D01*
X468574Y772118D01*
X467899Y772187D01*
X464517Y776348D01*
X446961Y826500D01*
Y837051D01*
G01X1408809Y833185D02*
Y826690D01*
X1404419Y785092D01*
X1385578Y761736D01*
X1345492Y722950D01*
X1329198Y711091D01*
X1260996Y675434D01*
X1235960Y668435D01*
X1190849Y667595D01*
X1190848Y667594D01*
X1190826D01*
X1190803Y667595D01*
X1074952Y670417D01*
X939360Y671066D01*
X831792D01*
X791484Y669297D01*
X612717Y672263D01*
X589881Y678106D01*
X539670Y703819D01*
X522626Y726697D01*
X491671Y747271D01*
X466240Y778563D01*
X450091Y824690D01*
Y833715D01*
G01X1412511Y833585D02*
Y829984D01*
X1412510Y829985D01*
Y826494D01*
X1407943Y783196D01*
X1391456Y762874D01*
X1347329Y720183D01*
X1330689Y708074D01*
X1262917Y672642D01*
Y672643D01*
X1262170Y672208D01*
X1236652Y665074D01*
X1190840Y664221D01*
X1190839Y664220D01*
X1190817D01*
X1190794Y664221D01*
X1074903Y667045D01*
X939351Y667694D01*
X829870D01*
X789024Y665901D01*
X612510Y668836D01*
X588982Y674857D01*
X537567Y701181D01*
X520658Y723874D01*
X488292Y745385D01*
X463560Y775813D01*
X445881Y826316D01*
Y837051D01*
G01X1407729Y833185D02*
Y826747D01*
X1403378Y785522D01*
X1384779Y762466D01*
X1344795Y723779D01*
X1328626Y712012D01*
X1260596Y676444D01*
X1235802Y669513D01*
X1190829Y668675D01*
X1074968Y671497D01*
X939363Y672146D01*
X831768D01*
X791469Y670378D01*
X612862Y673341D01*
X590266Y679123D01*
X540386Y704666D01*
X523380Y727493D01*
X492406Y748080D01*
X488380Y753035D01*
X488450Y753710D01*
X487364Y755046D01*
X486689Y755116D01*
X485605Y756450D01*
X485674Y757125D01*
X484589Y758461D01*
X483913Y758530D01*
X482785Y759919D01*
X482854Y760594D01*
X481769Y761930D01*
X481093Y762000D01*
X480009Y763334D01*
X480079Y764009D01*
X478993Y765345D01*
X478318Y765415D01*
X477223Y766762D01*
X477293Y767437D01*
X476207Y768773D01*
X475532Y768843D01*
X474363Y770281D01*
X474432Y770956D01*
X473347Y772292D01*
X472671Y772362D01*
X472672Y772363D01*
X471588Y773696D01*
X471587D01*
X471657Y774371D01*
X470571Y775707D01*
X469896Y775777D01*
X467197Y779098D01*
X451171Y824874D01*
Y833715D01*
G01X1404030Y833315D02*
Y826943D01*
X1399740Y786303D01*
X1381951Y764279D01*
X1342817Y726416D01*
X1327487Y715257D01*
X1259465Y679697D01*
X1235155Y672902D01*
X1190839Y672077D01*
X1075018Y674897D01*
X939372Y675546D01*
X832636D01*
X790286Y673688D01*
X614241Y676610D01*
X590593Y682661D01*
X542501Y707287D01*
X525575Y730007D01*
X496054Y749628D01*
X488078Y759442D01*
X488147Y760117D01*
X487062Y761453D01*
X486386Y761523D01*
X485302Y762857D01*
X485371Y763532D01*
X484286Y764868D01*
X483610Y764938D01*
X482526Y766272D01*
X482595Y766947D01*
X481510Y768283D01*
X480834Y768352D01*
X479643Y769818D01*
X479713Y770493D01*
X478627Y771829D01*
X477951Y771899D01*
X476867Y773233D01*
X476937Y773908D01*
X475851Y775244D01*
X475175Y775314D01*
X475176Y775315D01*
X474092Y776649D01*
X474091Y776648D01*
X474161Y777323D01*
X473075Y778658D01*
X472400Y778728D01*
Y778729D01*
X469778Y781954D01*
X454869Y824542D01*
Y833695D01*
G01X1405110Y833315D02*
Y826886D01*
X1400781Y785872D01*
X1382750Y763549D01*
X1343514Y725587D01*
X1328059Y714336D01*
X1259865Y678687D01*
X1235313Y671824D01*
X1190859Y670997D01*
X1190858Y670996D01*
X1190836D01*
X1190813Y670997D01*
X1075002Y673817D01*
X939367Y674466D01*
X832660D01*
X790301Y672607D01*
X614096Y675532D01*
X590208Y681644D01*
X541785Y706440D01*
X524821Y729211D01*
X495319Y748819D01*
X468821Y781419D01*
X453789Y824358D01*
Y833695D01*
G01X1400331Y833425D02*
Y827139D01*
X1396106Y787121D01*
X1379214Y766220D01*
X1340818Y729072D01*
X1325873Y718192D01*
X1258055Y682737D01*
X1234712Y676212D01*
X1190848Y675396D01*
X1075067Y678214D01*
X939381Y678863D01*
X833220D01*
X790857Y677004D01*
X616102Y679905D01*
X590467Y686464D01*
X544609Y709949D01*
X527753Y732576D01*
X499487Y751363D01*
X493300Y758976D01*
X493382Y759778D01*
X492467Y760904D01*
X491665Y760987D01*
X490751Y762112D01*
X490833Y762914D01*
X489918Y764040D01*
X489116Y764123D01*
X488202Y765248D01*
X488285Y766050D01*
X487370Y767176D01*
X486568Y767259D01*
X485654Y768384D01*
X485736Y769186D01*
X484821Y770312D01*
X484019Y770395D01*
X483105Y771520D01*
X483188Y772321D01*
X482272Y773448D01*
X481470Y773531D01*
X480394Y774855D01*
X480476Y775657D01*
X479561Y776783D01*
X478759Y776866D01*
X477845Y777991D01*
X477927Y778793D01*
X477012Y779919D01*
X476210Y780002D01*
X475296Y781127D01*
X475378Y781929D01*
X474463Y783055D01*
X473661Y783138D01*
X472253Y784871D01*
X458569Y823959D01*
Y833404D01*
X458570Y833405D01*
G01X1401411Y833425D02*
Y827082D01*
X1397147Y786690D01*
X1380013Y765489D01*
X1341515Y728243D01*
X1326445Y717271D01*
X1258455Y681727D01*
X1234870Y675134D01*
X1190868Y674316D01*
X1190867Y674315D01*
X1190845D01*
X1190822Y674316D01*
X1075051Y677134D01*
X939376Y677783D01*
X833244D01*
X790872Y675923D01*
X615957Y678827D01*
X590082Y685447D01*
X543893Y709102D01*
X535314Y720617D01*
X535315D01*
X526999Y731780D01*
X498752Y750554D01*
X493375Y757169D01*
Y757170D01*
X471296Y784336D01*
X457489Y823775D01*
Y833491D01*
X457490Y833492D01*
G01X1394011Y833315D02*
Y830216D01*
X1394010Y830217D01*
Y827465D01*
X1389852Y788098D01*
X1375315Y770105D01*
X1337311Y733334D01*
X1323062Y722957D01*
X1255822Y687806D01*
X1233971Y681698D01*
X1190886Y680897D01*
X1190885Y680896D01*
X1190863D01*
X1190840Y680897D01*
X1075147Y683711D01*
X938096Y684360D01*
X831498D01*
X790498Y682560D01*
X617284Y685435D01*
X592198Y691854D01*
X548140Y714413D01*
X531438Y736830D01*
X506126Y753654D01*
X477050Y789428D01*
X464889Y824163D01*
Y832992D01*
X464890Y832993D01*
Y833615D01*
G01X1397712Y833745D02*
Y830304D01*
X1397711Y830305D01*
Y827287D01*
X1393500Y787415D01*
X1377663Y767814D01*
X1339484Y730875D01*
X1324588Y720030D01*
X1257280Y684844D01*
Y684843D01*
X1257179Y684791D01*
X1234505Y678452D01*
Y678451D01*
X1234373Y678415D01*
X1190877Y677607D01*
X1190876Y677606D01*
X1190854D01*
X1190831Y677607D01*
X1075099Y680423D01*
X938517Y681072D01*
X832447D01*
X790550Y679233D01*
X616925Y682115D01*
X590722Y688820D01*
X546117Y711659D01*
X529326Y734200D01*
X502632Y751942D01*
X474381Y786702D01*
X461188Y824383D01*
Y833541D01*
X461189Y833542D01*
Y833745D01*
G01X1392931Y833315D02*
Y832824D01*
X1392930Y832825D01*
Y827522D01*
X1388811Y788529D01*
X1374516Y770835D01*
X1336614Y734163D01*
X1322490Y723878D01*
X1255422Y688816D01*
X1233813Y682776D01*
X1190866Y681977D01*
X1075163Y684791D01*
X938099Y685440D01*
X831474D01*
X790483Y683641D01*
X617429Y686513D01*
X592583Y692871D01*
X548856Y715260D01*
X532192Y737626D01*
X506861Y754463D01*
X503297Y758847D01*
X503367Y759523D01*
X502281Y760858D01*
X501606Y760928D01*
X500522Y762262D01*
X500591Y762937D01*
X499506Y764273D01*
X498830Y764343D01*
X497746Y765677D01*
X497815Y766352D01*
X496730Y767688D01*
X496054Y767758D01*
X494935Y769135D01*
X495004Y769810D01*
X493919Y771146D01*
X493243Y771216D01*
X493245Y771217D01*
X493244Y771218D01*
X492160Y772552D01*
X492229Y773227D01*
X491143Y774563D01*
X490468Y774633D01*
X489384Y775967D01*
X489453Y776642D01*
X488367Y777978D01*
X487692Y778048D01*
X486397Y779641D01*
X486467Y780317D01*
X485381Y781652D01*
X484706Y781722D01*
X483622Y783056D01*
X483691Y783731D01*
X482605Y785067D01*
X481930Y785137D01*
X478007Y789963D01*
X465969Y824347D01*
Y832992D01*
X465970Y832993D01*
Y833615D01*
G01X1396632Y833745D02*
Y832912D01*
X1396631Y832913D01*
Y827344D01*
X1392459Y787846D01*
X1376864Y768545D01*
X1338787Y731704D01*
X1324016Y720951D01*
X1256779Y685801D01*
X1234215Y679493D01*
X1190857Y678687D01*
X1075115Y681503D01*
X938520Y682152D01*
X832423D01*
X790535Y680314D01*
X617070Y683193D01*
X591107Y689837D01*
X546833Y712506D01*
X530080Y734996D01*
X503367Y752751D01*
X494340Y763859D01*
X494409Y764534D01*
X493324Y765870D01*
X492648Y765940D01*
X491564Y767274D01*
X491634Y767949D01*
X490548Y769285D01*
X489873Y769355D01*
X488789Y770689D01*
X488858Y771364D01*
X487773Y772700D01*
X487097Y772770D01*
X486013Y774104D01*
X486082Y774779D01*
X484997Y776115D01*
X484321Y776185D01*
X483237Y777519D01*
X483306Y778194D01*
X482221Y779530D01*
X481545Y779600D01*
X480461Y780934D01*
X480531Y781609D01*
X479445Y782945D01*
X478770Y783014D01*
Y783015D01*
X475338Y787237D01*
X462268Y824567D01*
Y833541D01*
X462269Y833542D01*
Y833745D01*
G01X1390312Y833315D02*
Y830216D01*
X1390311Y830217D01*
Y827679D01*
X1386211Y788879D01*
X1372623Y772061D01*
X1335393Y736038D01*
X1321366Y725825D01*
X1254404Y690819D01*
X1233623Y685010D01*
X1190895Y684216D01*
X1190894Y684215D01*
X1190872D01*
X1190849Y684216D01*
X1075196Y687028D01*
X939405Y687677D01*
X830615D01*
X789803Y685885D01*
X619340Y688715D01*
X591919Y695732D01*
X550330Y717027D01*
X541762Y728528D01*
X541763D01*
X533458Y739678D01*
X509361Y755689D01*
X479606Y792299D01*
X468588Y823951D01*
Y831392D01*
X468589Y831393D01*
Y833135D01*
G01X1386611Y833315D02*
Y830216D01*
X1386610Y830217D01*
Y827857D01*
X1382576Y789694D01*
X1372758Y777548D01*
X1330536Y736693D01*
X1319567Y728703D01*
X1253009Y693908D01*
X1233215Y688375D01*
X1190905Y687589D01*
X1190904Y687588D01*
X1190882D01*
X1190859Y687589D01*
X1075245Y690399D01*
X939414Y691048D01*
X830003D01*
X788134Y689209D01*
X620164Y691996D01*
X592702Y699024D01*
X552573Y719570D01*
X535629Y742315D01*
X511358Y758446D01*
X484016Y792086D01*
X472349Y825408D01*
X472289Y825468D01*
Y832572D01*
X472290Y832573D01*
Y833785D01*
G01X1382912Y833315D02*
Y830216D01*
X1382911Y830217D01*
Y828071D01*
X1378960Y790705D01*
X1372294Y782456D01*
X1325142Y736828D01*
X1318292Y731839D01*
X1251322Y696830D01*
X1233143Y691748D01*
X1190915Y690964D01*
X1190914Y690963D01*
X1190892D01*
X1190869Y690964D01*
X1075294Y693772D01*
X939423Y694421D01*
X830488D01*
X788594Y692581D01*
X620831Y695365D01*
X593672Y702316D01*
X554697Y722269D01*
X537482Y745376D01*
X512951Y761684D01*
X487815Y792610D01*
X475988Y826385D01*
Y832282D01*
X475989Y832283D01*
Y833705D01*
G01X1385531Y833315D02*
Y832824D01*
X1385530Y832825D01*
Y827914D01*
X1381535Y790125D01*
X1371959Y778279D01*
X1345626Y752798D01*
X1344820Y752811D01*
X1343777Y751802D01*
X1343764Y750996D01*
X1342722Y749988D01*
X1341916Y750001D01*
X1340873Y748992D01*
X1340860Y748186D01*
X1339818Y747178D01*
X1339012Y747191D01*
X1337969Y746182D01*
X1337956Y745376D01*
X1336520Y743987D01*
X1335714Y744000D01*
X1334671Y742991D01*
X1334657Y742185D01*
X1329839Y737522D01*
X1318995Y729624D01*
X1252609Y694918D01*
X1233057Y689453D01*
X1190885Y688669D01*
X1075261Y691479D01*
X939417Y692128D01*
X829979D01*
X788119Y690290D01*
X620309Y693074D01*
X606698Y696558D01*
X606696D01*
X593087Y700041D01*
X553289Y720417D01*
X536383Y743111D01*
X512093Y759255D01*
X484973Y792621D01*
X484974D01*
X484406Y794244D01*
X484700Y794856D01*
X484132Y796480D01*
X483519Y796774D01*
X482951Y798397D01*
X483245Y799009D01*
X482677Y800633D01*
X482064Y800927D01*
X482065Y800928D01*
X476278Y817458D01*
X476573Y818069D01*
X476004Y819694D01*
X475392Y819988D01*
X474824Y821611D01*
X475118Y822222D01*
X474550Y823847D01*
X473937Y824141D01*
X473369Y825764D01*
Y832572D01*
X473370Y832573D01*
Y833785D01*
G01X1389232Y833315D02*
Y832824D01*
X1389231Y832825D01*
Y827736D01*
X1385170Y789310D01*
X1371824Y772791D01*
X1341458Y743410D01*
X1340652Y743423D01*
X1339609Y742414D01*
X1339596Y741608D01*
X1338468Y740517D01*
X1337662Y740530D01*
X1336619Y739521D01*
X1336606Y738715D01*
X1334696Y736867D01*
X1320794Y726746D01*
X1254004Y691829D01*
X1233465Y686088D01*
X1190875Y685296D01*
X1075212Y688108D01*
X939408Y688757D01*
X830591D01*
X789788Y686966D01*
X619485Y689793D01*
X605894Y693271D01*
X605893Y693272D01*
X592304Y696749D01*
X551046Y717874D01*
X534212Y740474D01*
X510096Y756498D01*
X480564Y792833D01*
X479836Y794926D01*
X480187Y795651D01*
X479711Y797022D01*
X478984Y797373D01*
X478316Y799293D01*
X478667Y800019D01*
X478190Y801390D01*
X477463Y801741D01*
X472974Y814639D01*
X473325Y815365D01*
X472848Y816735D01*
X472121Y817086D01*
X471645Y818455D01*
X471996Y819180D01*
X471520Y820551D01*
X470793Y820902D01*
X469668Y824134D01*
Y831392D01*
X469669Y831393D01*
Y833135D01*
G01X1378131Y833315D02*
Y832824D01*
X1378130Y832825D01*
Y828306D01*
X1374271Y791825D01*
X1369104Y785429D01*
X1346925Y768006D01*
Y768007D01*
X1324521Y750408D01*
X1321754Y746376D01*
X1319395Y741491D01*
X1318535Y738688D01*
X1316009Y735649D01*
X1312791Y733967D01*
X1312022Y734208D01*
X1310736Y733536D01*
X1310495Y732766D01*
X1309210Y732095D01*
X1308441Y732336D01*
X1307155Y731664D01*
X1306914Y730894D01*
X1305629Y730223D01*
X1304860Y730464D01*
X1303574Y729792D01*
X1303333Y729022D01*
X1249466Y700862D01*
X1232663Y696165D01*
X1190904Y695390D01*
X1075359Y698196D01*
X939435Y698845D01*
X832045D01*
X789480Y696976D01*
X621703Y699761D01*
X608474Y703147D01*
X608473D01*
X595246Y706532D01*
X557577Y725816D01*
X540545Y748681D01*
X515761Y765154D01*
X492713Y793509D01*
Y793510D01*
X487838Y807435D01*
X488188Y808162D01*
X487709Y809531D01*
X486982Y809881D01*
X486503Y811249D01*
X486852Y811976D01*
X486373Y813345D01*
X485646Y813695D01*
X485167Y815063D01*
X485517Y815790D01*
X485038Y817159D01*
X484311Y817509D01*
X483832Y818877D01*
X484181Y819604D01*
X483702Y820973D01*
X482975Y821323D01*
X482496Y822691D01*
X482846Y823417D01*
X482367Y824787D01*
X481640Y825137D01*
X480768Y827627D01*
Y833315D01*
G01X1381832D02*
Y832824D01*
X1381831Y832825D01*
Y828128D01*
X1377919Y791136D01*
X1371495Y783187D01*
X1339079Y751818D01*
X1338273Y751832D01*
X1337231Y750822D01*
X1337217Y750016D01*
X1336041Y748878D01*
X1335235Y748891D01*
X1334192Y747882D01*
X1334178Y747076D01*
X1324445Y737657D01*
X1317720Y732760D01*
X1250922Y697840D01*
X1232985Y692826D01*
X1190895Y692044D01*
X1075310Y694852D01*
X939426Y695501D01*
X830464D01*
X788579Y693662D01*
X620976Y696443D01*
X607516Y699888D01*
X607515Y699889D01*
X594057Y703333D01*
X555413Y723116D01*
X538236Y746172D01*
X513686Y762493D01*
X488772Y793145D01*
X488016Y795306D01*
X488365Y796033D01*
X487886Y797402D01*
X487159Y797752D01*
X486680Y799120D01*
X487030Y799847D01*
X486550Y801216D01*
X485824Y801565D01*
X479964Y818302D01*
X480313Y819028D01*
X479834Y820397D01*
X479107Y820747D01*
X478628Y822115D01*
X478978Y822841D01*
X478498Y824211D01*
X477771Y824561D01*
X477068Y826569D01*
Y832282D01*
X477069Y832283D01*
Y833705D01*
G01X1379211Y833315D02*
Y830216D01*
X1379210Y830217D01*
Y828249D01*
X1375312Y791394D01*
X1369868Y784655D01*
X1325319Y749660D01*
X1322691Y745832D01*
X1320404Y741095D01*
X1319504Y738164D01*
X1316702Y734791D01*
X1303834Y728064D01*
X1303832D01*
X1249866Y699852D01*
X1232821Y695087D01*
X1190924Y694310D01*
X1190923Y694309D01*
X1190901D01*
X1190878Y694310D01*
X1075343Y697116D01*
X939432Y697765D01*
X832069D01*
X789495Y695895D01*
X621558Y698683D01*
X594861Y705515D01*
X556861Y724969D01*
X539791Y747885D01*
X515026Y764345D01*
X491756Y792974D01*
X479688Y827443D01*
Y833315D01*
G01X1374432D02*
Y832824D01*
X1374431Y832825D01*
Y828520D01*
X1370640Y792654D01*
X1366674Y787766D01*
X1306690Y740586D01*
X1302966Y738016D01*
X1302173Y738161D01*
X1300979Y737337D01*
X1300834Y736543D01*
X1300833Y736545D01*
X1296835Y733786D01*
X1296836Y733784D01*
X1296043Y733930D01*
X1294848Y733106D01*
X1294703Y732312D01*
X1282921Y724180D01*
X1248014Y703861D01*
X1232563Y699538D01*
X1190914Y698765D01*
X1075408Y701569D01*
X939444Y702218D01*
X834170D01*
X790792Y700313D01*
X622049Y703113D01*
X609176Y706408D01*
X609175D01*
X596304Y709702D01*
X559993Y728291D01*
X543138Y750919D01*
X517902Y767691D01*
X496665Y793818D01*
X496666D01*
X496045Y795592D01*
X496340Y796204D01*
X495771Y797828D01*
X495159Y798122D01*
X494424Y800221D01*
X494719Y800833D01*
X494150Y802457D01*
X493538Y802752D01*
X487748Y819289D01*
X488043Y819900D01*
X487475Y821525D01*
X486862Y821819D01*
X486294Y823442D01*
X486589Y824053D01*
X486020Y825678D01*
X485407Y825972D01*
X484468Y828656D01*
Y832842D01*
X484469Y832843D01*
Y833365D01*
G01X1375512Y833315D02*
Y830216D01*
X1375511Y830217D01*
Y828463D01*
X1371681Y792222D01*
X1367437Y786992D01*
X1307331Y739716D01*
X1283501Y723267D01*
X1248438Y702858D01*
X1232721Y698460D01*
X1190911Y697684D01*
X1075392Y700489D01*
X939441Y701138D01*
X834194D01*
X790807Y699232D01*
X621904Y702035D01*
X595919Y708685D01*
X559277Y727444D01*
X542384Y750123D01*
X517167Y766882D01*
X495708Y793283D01*
X483388Y828472D01*
Y832842D01*
X483389Y832843D01*
Y833365D01*
G01X495079Y1696417D02*
Y1695176D01*
X494498Y1694595D01*
X493168D01*
X491709Y1693367D01*
X479511Y1622872D01*
Y1615452D01*
X478351Y1614292D01*
G01X481751D02*
X480591Y1615452D01*
Y1622779D01*
X480838Y1624207D01*
X481474Y1624655D01*
X481722Y1626085D01*
X481274Y1626721D01*
X481521Y1628149D01*
X482157Y1628597D01*
X482405Y1630027D01*
X481957Y1630663D01*
X482204Y1632091D01*
X482840Y1632539D01*
X483088Y1633969D01*
X482639Y1634605D01*
X482886Y1636033D01*
X483522Y1636481D01*
X483770Y1637911D01*
X483321Y1638547D01*
X492707Y1692794D01*
X493563Y1693515D01*
X494246D01*
X495079Y1692682D01*
Y1691692D01*
G01X1368112Y833315D02*
Y830216D01*
X1368111Y830217D01*
Y828856D01*
X1364551Y795182D01*
X1360824Y790593D01*
X1338383Y772940D01*
Y772939D01*
X1315975Y755312D01*
X1297626Y744818D01*
X1294934Y743584D01*
X1286106Y737408D01*
X1280641Y730967D01*
X1279162Y728896D01*
X1277485Y727369D01*
X1246512Y709367D01*
X1231337Y705126D01*
X1190930Y704377D01*
X1075489Y707178D01*
X939459Y707827D01*
X834754D01*
X790112Y705866D01*
X623067Y708637D01*
X598440Y714941D01*
X564007Y732568D01*
X546609Y755924D01*
X520331Y773391D01*
X502419Y795422D01*
X501302Y798618D01*
X501300Y798619D01*
X490787Y828645D01*
Y832612D01*
X490788Y832613D01*
Y833275D01*
G01X1370731Y833315D02*
Y832824D01*
X1370730Y832825D01*
Y828698D01*
X1367076Y794134D01*
X1363630Y789888D01*
X1338335Y769992D01*
X1313551Y750499D01*
X1312751Y750595D01*
X1311610Y749698D01*
X1311515Y748897D01*
X1309551Y747353D01*
X1307617Y746535D01*
X1306870Y746838D01*
X1305534Y746273D01*
X1305231Y745525D01*
X1295960Y741602D01*
X1287375Y735516D01*
X1282128Y729251D01*
X1280981Y727494D01*
X1279248Y725849D01*
X1246901Y707047D01*
X1232074Y702903D01*
X1190924Y702139D01*
X1075457Y704941D01*
X939453Y705590D01*
X835954D01*
X790581Y703597D01*
X622609Y706384D01*
X597696Y712762D01*
X562437Y730809D01*
X545655Y753336D01*
X542575Y755384D01*
X542441Y756049D01*
X541007Y757002D01*
X540342Y756868D01*
X538910Y757820D01*
X538776Y758486D01*
X537342Y759439D01*
X536677Y759305D01*
X535245Y760257D01*
X535111Y760922D01*
X533677Y761875D01*
X533012Y761741D01*
X531580Y762693D01*
X531446Y763359D01*
X530012Y764312D01*
X529347Y764178D01*
X527915Y765130D01*
X527781Y765795D01*
X526347Y766748D01*
X525682Y766614D01*
X524250Y767566D01*
X524116Y768231D01*
X522683Y769184D01*
X522018Y769050D01*
X519891Y770464D01*
X500465Y794361D01*
X488168Y829474D01*
Y833205D01*
G01X1371811Y833315D02*
Y830216D01*
X1371810Y830217D01*
Y828641D01*
X1368117Y793702D01*
X1364393Y789114D01*
X1310106Y746414D01*
X1305652Y744530D01*
X1305651D01*
X1296489Y740653D01*
X1288114Y734715D01*
X1282998Y728606D01*
X1281817Y726797D01*
X1279901Y724978D01*
X1247325Y706044D01*
X1232232Y701825D01*
X1190944Y701059D01*
X1190943Y701058D01*
X1190921D01*
X1190898Y701059D01*
X1075441Y703861D01*
X939450Y704510D01*
X835978D01*
X790596Y702516D01*
X622464Y705306D01*
X597311Y711745D01*
X561721Y729962D01*
X544901Y752540D01*
X519156Y769655D01*
X499508Y793826D01*
X487088Y829290D01*
Y833205D01*
G01X1364411Y833315D02*
Y830216D01*
X1364410Y830217D01*
Y829035D01*
X1360987Y796662D01*
X1357676Y792585D01*
X1313301Y757675D01*
X1289237Y749125D01*
X1288286Y748539D01*
X1272591Y733565D01*
X1267319Y726259D01*
X1266015Y725443D01*
X1266014Y725441D01*
X1245971Y712889D01*
X1230596Y708529D01*
X1188499Y707755D01*
X1075537Y710495D01*
X939468Y711144D01*
X834328D01*
X790309Y709210D01*
X624771Y711958D01*
X598410Y718706D01*
X566197Y735197D01*
X557450Y746936D01*
X557451D01*
X548968Y758323D01*
X523231Y775434D01*
X506214Y796361D01*
X494488Y829851D01*
Y833085D01*
G01X1363331Y833315D02*
Y832824D01*
X1363330Y832825D01*
Y829092D01*
X1359946Y797095D01*
X1356913Y793360D01*
X1312772Y758634D01*
X1288767Y750105D01*
X1287622Y749400D01*
X1271773Y734278D01*
X1270163Y732047D01*
X1269367Y731919D01*
X1268518Y730742D01*
X1268647Y729946D01*
X1266566Y727063D01*
X1263828Y725349D01*
X1263043Y725529D01*
X1261813Y724760D01*
X1261632Y723973D01*
X1260404Y723204D01*
X1259619Y723384D01*
X1258389Y722615D01*
X1258208Y721828D01*
X1245528Y713886D01*
X1230436Y709607D01*
X1188502Y708836D01*
X1075553Y711575D01*
X939471Y712224D01*
X834304D01*
X790294Y710291D01*
X707605Y711664D01*
X707604D01*
X624916Y713036D01*
X598795Y719723D01*
X566913Y736044D01*
X549722Y759119D01*
X523966Y776243D01*
X521241Y779593D01*
X521312Y780283D01*
X520226Y781618D01*
X519537Y781689D01*
X518452Y783023D01*
X518523Y783713D01*
X517437Y785048D01*
X516748Y785119D01*
X515663Y786453D01*
X515734Y787143D01*
X514648Y788478D01*
X513959Y788549D01*
X512874Y789883D01*
X512945Y790573D01*
X511859Y791908D01*
X511170Y791979D01*
X510085Y793313D01*
X510156Y794002D01*
X509070Y795338D01*
X508380Y795409D01*
X507171Y796896D01*
X495568Y830035D01*
Y833085D01*
G01X1367032Y833315D02*
Y832824D01*
X1367031Y832825D01*
Y828913D01*
X1363510Y795615D01*
X1360061Y791367D01*
X1315369Y756211D01*
X1307019Y751435D01*
X1306241Y751647D01*
X1304982Y750927D01*
X1304770Y750148D01*
X1297132Y745780D01*
X1294395Y744525D01*
X1285372Y738214D01*
X1279788Y731631D01*
X1278349Y729618D01*
X1276842Y728246D01*
X1246088Y710371D01*
X1231179Y706204D01*
X1190933Y705458D01*
X1075505Y708258D01*
X939462Y708907D01*
X834730D01*
X790097Y706947D01*
X623212Y709715D01*
X611018Y712837D01*
X611016D01*
X598825Y715958D01*
X564723Y733415D01*
X547363Y756720D01*
X521066Y774200D01*
X503377Y795957D01*
X502177Y799388D01*
X502175Y799389D01*
X500840Y803206D01*
X501189Y803932D01*
X500710Y805302D01*
X499983Y805652D01*
X498806Y809014D01*
X499156Y809741D01*
X498676Y811110D01*
X497949Y811460D01*
X496265Y816271D01*
X496615Y816997D01*
X496135Y818367D01*
X495408Y818717D01*
X494646Y820894D01*
X494995Y821621D01*
X494516Y822990D01*
X493789Y823340D01*
X493310Y824708D01*
X493660Y825434D01*
X493181Y826804D01*
X492453Y827153D01*
X492455D01*
X492454Y827154D01*
X491867Y828829D01*
Y832612D01*
X491868Y832613D01*
Y833275D01*
G01X1360712Y833315D02*
Y830216D01*
X1360711Y830217D01*
Y829249D01*
X1357421Y798143D01*
X1353970Y793894D01*
X1311650Y760602D01*
X1287810Y752087D01*
X1285932Y750930D01*
X1260295Y726462D01*
X1242385Y715285D01*
X1230196Y711834D01*
X1190642Y711107D01*
X1075586Y713897D01*
X939476Y714546D01*
X836316D01*
X789796Y712502D01*
X625545Y715228D01*
X599207Y721970D01*
X568481Y737700D01*
X551388Y760643D01*
X526854Y776950D01*
X509220Y798647D01*
X498187Y830161D01*
Y832542D01*
X498190Y832545D01*
Y833345D01*
G01X1359632Y833315D02*
Y832824D01*
X1359631Y832825D01*
Y829306D01*
X1356380Y798576D01*
X1353207Y794668D01*
Y794669D01*
X1311121Y761560D01*
X1287340Y753066D01*
X1285268Y751791D01*
X1259629Y727320D01*
X1257485Y725982D01*
X1256700Y726164D01*
X1255469Y725396D01*
X1255287Y724610D01*
X1241943Y716283D01*
X1230036Y712912D01*
X1190651Y712188D01*
X1075602Y714977D01*
X939479Y715626D01*
X836292D01*
X789781Y713583D01*
X625690Y716306D01*
X612641Y719647D01*
X612639D01*
X599592Y722987D01*
X569197Y738547D01*
X552142Y761439D01*
X527589Y777759D01*
X524650Y781375D01*
X524722Y782064D01*
X523636Y783400D01*
X522946Y783471D01*
X521862Y784805D01*
X521933Y785495D01*
X520848Y786831D01*
X520158Y786902D01*
X519074Y788236D01*
X519145Y788925D01*
X518060Y790261D01*
X517370Y790332D01*
X516286Y791666D01*
X516357Y792355D01*
X515272Y793691D01*
X514582Y793762D01*
X513498Y795096D01*
X513569Y795786D01*
X512483Y797121D01*
X511794Y797192D01*
X510177Y799182D01*
X499267Y830345D01*
Y832542D01*
X499270Y832545D01*
Y833345D01*
G01X1357011Y833315D02*
Y830216D01*
X1357010Y830217D01*
Y829428D01*
X1353857Y799624D01*
X1350228Y795153D01*
X1310608Y763984D01*
X1286766Y755341D01*
X1282303Y752566D01*
X1279147Y749533D01*
X1265404Y736334D01*
X1250226Y724806D01*
X1241421Y718845D01*
X1229593Y715103D01*
X1190958Y714388D01*
X1075635Y717183D01*
X939486Y717832D01*
X835821D01*
X789715Y715805D01*
X626397Y718517D01*
X599907Y725298D01*
X570740Y740231D01*
X562073Y751863D01*
X562074D01*
X553671Y763143D01*
X530424Y778596D01*
X512375Y800795D01*
X501889Y830743D01*
Y832542D01*
X501890Y832543D01*
Y833785D01*
G01X502953Y1700354D02*
Y1699113D01*
X502372Y1698532D01*
X500691D01*
X499183Y1697024D01*
Y1669186D01*
X491776Y1620099D01*
X491775Y1620098D01*
X491571Y1618739D01*
Y1615452D01*
X490411Y1614292D01*
G01X493811D02*
X492651Y1615452D01*
Y1618658D01*
X492777Y1619494D01*
X493404Y1619956D01*
X493620Y1621391D01*
X493158Y1622017D01*
X493374Y1623450D01*
X494001Y1623912D01*
X494217Y1625347D01*
X493755Y1625973D01*
X500263Y1669104D01*
Y1696576D01*
X501139Y1697452D01*
X502120D01*
X502953Y1696619D01*
Y1695629D01*
G01X1353312Y833045D02*
Y829946D01*
X1353311Y829947D01*
Y829643D01*
X1350291Y801105D01*
X1346397Y796307D01*
X1309178Y767028D01*
X1281331Y756839D01*
X1270065Y747268D01*
X1261316Y741921D01*
X1248733Y728187D01*
X1238681Y721457D01*
X1229241Y718493D01*
X1190968Y717788D01*
X1075685Y720581D01*
X939495Y721230D01*
X836396D01*
X788324Y719117D01*
X627403Y721788D01*
X600480Y728682D01*
X573078Y742707D01*
X556038Y765580D01*
X533925Y780281D01*
X515449Y803007D01*
X505588Y831166D01*
Y832862D01*
X505589Y832863D01*
Y833745D01*
G01X1352232Y833045D02*
Y832554D01*
X1352231Y832555D01*
Y829700D01*
X1349250Y801537D01*
X1345634Y797082D01*
Y797081D01*
X1308645Y767984D01*
X1280778Y757788D01*
X1269430Y748146D01*
X1260622Y742764D01*
X1248024Y729013D01*
X1238209Y722441D01*
X1229066Y719571D01*
X1190971Y718869D01*
X1075701Y721661D01*
X939498Y722310D01*
X836372D01*
X788309Y720198D01*
X707928Y721532D01*
X707927D01*
X627548Y722866D01*
X600865Y729699D01*
X582371Y739164D01*
X582123Y739932D01*
X580831Y740592D01*
X580065Y740345D01*
X578052Y741375D01*
X577805Y742142D01*
X576513Y742803D01*
X575746Y742555D01*
X573794Y743554D01*
X556792Y766376D01*
X541422Y776594D01*
X541263Y777385D01*
X540055Y778188D01*
X539265Y778029D01*
X534660Y781090D01*
X529982Y786845D01*
X530064Y787647D01*
X529149Y788773D01*
X528347Y788856D01*
X527406Y790013D01*
X527489Y790815D01*
X526573Y791941D01*
X525771Y792023D01*
X524857Y793148D01*
X524940Y793950D01*
X524024Y795076D01*
X523223Y795158D01*
X516406Y803542D01*
X506668Y831350D01*
Y832862D01*
X506669Y832863D01*
Y833745D01*
G01X1355931Y833315D02*
Y832824D01*
X1355930Y832825D01*
Y829485D01*
X1352816Y800056D01*
X1349465Y795927D01*
X1310076Y764941D01*
X1286291Y756319D01*
X1281636Y753423D01*
X1277412Y749366D01*
X1276606Y749382D01*
X1275559Y748377D01*
X1275543Y747571D01*
X1273662Y745765D01*
X1272856Y745781D01*
X1271810Y744776D01*
X1271793Y743970D01*
X1270748Y742966D01*
X1269942Y742982D01*
X1268895Y741976D01*
X1268879Y741171D01*
X1264700Y737157D01*
X1261911Y735038D01*
X1261112Y735147D01*
X1259956Y734270D01*
X1259847Y733471D01*
X1249596Y725684D01*
X1240945Y719828D01*
X1229416Y716180D01*
X1190961Y715469D01*
X1075651Y718263D01*
X939489Y718912D01*
X835797D01*
X789700Y716886D01*
X626542Y719595D01*
X600292Y726315D01*
X571456Y741078D01*
X554425Y763939D01*
X531159Y779405D01*
X525241Y786684D01*
X525312Y787373D01*
X524226Y788709D01*
X523537Y788780D01*
X522452Y790114D01*
X522523Y790803D01*
X521437Y792139D01*
X520748Y792210D01*
X519663Y793544D01*
X519734Y794233D01*
X518648Y795569D01*
X517959Y795640D01*
X516874Y796974D01*
X516945Y797663D01*
X515859Y798998D01*
X515170Y799070D01*
X513332Y801330D01*
X502969Y830927D01*
Y832542D01*
X502970Y832543D01*
Y833785D01*
G01X1345912Y833315D02*
Y830216D01*
X1345911Y830217D01*
Y827652D01*
X1343309Y803084D01*
X1341477Y800826D01*
X1308403Y774806D01*
X1297049Y770671D01*
X1297048Y770670D01*
X1285899Y766609D01*
X1258811Y754195D01*
X1254160Y750622D01*
X1242919Y732245D01*
X1236072Y727670D01*
X1229404Y725581D01*
X1190989Y724874D01*
X1075788Y727663D01*
X939514Y728312D01*
X847857D01*
X788820Y725717D01*
X628045Y728386D01*
X602946Y734813D01*
X588543Y742185D01*
X584325Y746180D01*
X560963Y777541D01*
X525513Y801107D01*
X521647Y805862D01*
X512988Y830583D01*
Y831462D01*
X512989Y831463D01*
Y833265D01*
G01X1348531Y833315D02*
Y832824D01*
X1348530Y832825D01*
Y829879D01*
X1345609Y802288D01*
X1343323Y799472D01*
X1307972Y771661D01*
X1293599Y766359D01*
X1292867Y766697D01*
X1291506Y766195D01*
X1291168Y765462D01*
X1279834Y761281D01*
X1277869Y759612D01*
X1277066Y759678D01*
X1275960Y758738D01*
X1275895Y757934D01*
X1274790Y756996D01*
X1273987Y757061D01*
X1272881Y756122D01*
X1272816Y755318D01*
X1271630Y754311D01*
X1270826Y754376D01*
X1269720Y753436D01*
X1269655Y752633D01*
X1268213Y751408D01*
X1265389Y749683D01*
X1264606Y749873D01*
X1263367Y749117D01*
X1263178Y748332D01*
X1261941Y747577D01*
X1261158Y747766D01*
X1259919Y747010D01*
X1259730Y746226D01*
X1257576Y744910D01*
X1254485Y741536D01*
X1253679Y741501D01*
X1252699Y740431D01*
X1252734Y739626D01*
X1251755Y738557D01*
X1250950Y738522D01*
X1249969Y737452D01*
X1250004Y736646D01*
X1247191Y733577D01*
Y733575D01*
X1244591Y730738D01*
X1236743Y725483D01*
X1229724Y723279D01*
X1190982Y722565D01*
X1075755Y725355D01*
X939508Y726004D01*
X845460D01*
X788002Y723479D01*
X627956Y726137D01*
X602158Y732741D01*
X587226Y740385D01*
X582608Y744764D01*
X559455Y775839D01*
Y775840D01*
X524040Y799432D01*
X519570Y804928D01*
X510369Y831202D01*
Y832862D01*
X510370Y832863D01*
Y833745D01*
G01X1349611Y833315D02*
Y830216D01*
X1349610Y830217D01*
Y829821D01*
X1346650Y801856D01*
X1344086Y798698D01*
X1326315Y784717D01*
X1326314Y784716D01*
X1308506Y770706D01*
X1280388Y760333D01*
X1279064Y759209D01*
X1268848Y750530D01*
X1258270Y744067D01*
X1250801Y735916D01*
X1250800D01*
X1248271Y733156D01*
Y733154D01*
X1245300Y729913D01*
X1237215Y724499D01*
X1229899Y722201D01*
X1190979Y721484D01*
X1075739Y724275D01*
X939505Y724924D01*
X845484D01*
X788017Y722398D01*
X627811Y725059D01*
X601773Y731724D01*
X586596Y739494D01*
X581797Y744044D01*
X558701Y775043D01*
X523305Y798623D01*
X518613Y804393D01*
X509289Y831018D01*
Y832862D01*
X509290Y832863D01*
Y833745D01*
G01X1344832Y833315D02*
Y832824D01*
X1344831Y832825D01*
Y827710D01*
X1342268Y803516D01*
X1340714Y801601D01*
Y801600D01*
X1307871Y775762D01*
X1285488Y767610D01*
X1258250Y755126D01*
X1253342Y751357D01*
X1242121Y733012D01*
X1235601Y728655D01*
X1229229Y726658D01*
X1190992Y725955D01*
X1075804Y728743D01*
X939517Y729392D01*
X847833D01*
X788805Y726798D01*
X628190Y729464D01*
X603331Y735830D01*
X589173Y743076D01*
X585136Y746901D01*
X567460Y770628D01*
X567577Y771426D01*
X566710Y772589D01*
X565912Y772706D01*
X564346Y774808D01*
X564463Y775606D01*
X563596Y776770D01*
X562798Y776886D01*
X561717Y778337D01*
X526248Y801916D01*
X522604Y806397D01*
X519412Y815515D01*
X519761Y816241D01*
X519282Y817610D01*
X518555Y817960D01*
X518076Y819328D01*
X518425Y820054D01*
X517946Y821423D01*
X517219Y821773D01*
X516740Y823141D01*
X517089Y823867D01*
X516610Y825236D01*
X515883Y825586D01*
X515404Y826954D01*
X515754Y827680D01*
X515274Y829049D01*
X514547Y829399D01*
X514068Y830767D01*
Y831462D01*
X514069Y831463D01*
Y833265D01*
G01X1341131Y833705D02*
Y825882D01*
X1338918Y804993D01*
X1337493Y803238D01*
X1306369Y778753D01*
X1300798Y776716D01*
X1300067Y777055D01*
X1298705Y776557D01*
X1298365Y775825D01*
X1296833Y775265D01*
X1296101Y775604D01*
X1294739Y775106D01*
X1294399Y774374D01*
X1293038Y773876D01*
X1292307Y774216D01*
X1290944Y773718D01*
X1290604Y772986D01*
X1284162Y770629D01*
X1256414Y757899D01*
X1251072Y754063D01*
X1239535Y735274D01*
X1234061Y731702D01*
X1228622Y730028D01*
X1190848Y729300D01*
X1189975D01*
X1075651Y732453D01*
X1003991Y732615D01*
X1003990Y732614D01*
X1003985D01*
X1003416Y733186D01*
X1001965Y733190D01*
X1001394Y732621D01*
X848533Y732965D01*
X789779Y730114D01*
X628499Y732820D01*
X623054Y734600D01*
X622690Y735320D01*
X621311Y735770D01*
X620592Y735406D01*
X619214Y735856D01*
X618850Y736576D01*
X617470Y737027D01*
X616751Y736662D01*
X611350Y738428D01*
X609637Y739980D01*
X609598Y740785D01*
X608522Y741760D01*
X607717Y741720D01*
X606643Y742693D01*
X605366Y746656D01*
X598987Y752360D01*
X597121Y752255D01*
X594472Y749291D01*
X593656Y749245D01*
X591922Y750795D01*
X591876Y751612D01*
X594526Y754576D01*
X594430Y756288D01*
X592032Y758433D01*
X590319Y758337D01*
X587670Y755373D01*
X586854Y755327D01*
X585120Y756877D01*
X585074Y757694D01*
X587724Y760658D01*
X587628Y762370D01*
X585230Y764515D01*
X583517Y764419D01*
X580868Y761455D01*
X580052Y761409D01*
X578318Y762959D01*
X578272Y763776D01*
X580922Y766740D01*
X580826Y768453D01*
X563497Y783946D01*
X539410Y818190D01*
X531037Y826563D01*
Y826567D01*
X527127Y830477D01*
G01X1342211Y833705D02*
Y825824D01*
X1339959Y804560D01*
X1338332Y802557D01*
Y802556D01*
X1338256Y802463D01*
X1306902Y777797D01*
X1284573Y769629D01*
X1256960Y756960D01*
X1251879Y753312D01*
X1246223Y744102D01*
X1246224D01*
X1240329Y734501D01*
X1234524Y730714D01*
X1228795Y728951D01*
X1190859Y728220D01*
X1189960D01*
X1075635Y731373D01*
X1003989Y731534D01*
X1003983D01*
X848558Y731884D01*
X789796Y729033D01*
X628318Y731742D01*
X610795Y737473D01*
Y737472D01*
X605703Y742086D01*
X604427Y746046D01*
X598601Y751256D01*
X597629Y751201D01*
X594979Y748237D01*
X593269Y748141D01*
X590868Y750288D01*
X590772Y751999D01*
X593422Y754963D01*
X593376Y755781D01*
X591645Y757329D01*
X590827Y757283D01*
X588177Y754319D01*
X586467Y754223D01*
X584066Y756370D01*
X583970Y758081D01*
X586620Y761045D01*
X586574Y761863D01*
X584843Y763411D01*
X584025Y763365D01*
X581375Y760401D01*
X579665Y760305D01*
X577264Y762452D01*
X577168Y764163D01*
X579818Y767127D01*
X579772Y767945D01*
X562685Y783223D01*
X538580Y817492D01*
X529957Y826115D01*
Y826119D01*
X526363Y829713D01*
G01X518701Y1700354D02*
Y1699113D01*
X518050Y1698462D01*
X516021D01*
X514931Y1697372D01*
Y1669495D01*
X515410Y1619913D01*
X515691Y1617092D01*
Y1615452D01*
X514531Y1614292D01*
G01X510827Y1696417D02*
Y1695176D01*
X510246Y1694595D01*
X508269D01*
X507057Y1693383D01*
Y1668942D01*
X503984Y1625453D01*
X503985D01*
X503631Y1620435D01*
Y1615452D01*
X502471Y1614292D01*
G01X517931D02*
X516771Y1615452D01*
Y1617146D01*
X516490Y1619972D01*
X516138Y1656364D01*
X516683Y1656919D01*
X516669Y1658370D01*
X516113Y1658915D01*
X516099Y1660364D01*
X516644Y1660919D01*
X516630Y1662370D01*
X516074Y1662915D01*
X516060Y1664364D01*
X516604Y1664920D01*
X516590Y1666371D01*
X516034Y1666915D01*
X516011Y1669328D01*
Y1696924D01*
X516469Y1697382D01*
X517938D01*
X518701Y1696619D01*
Y1695629D01*
G01X505871Y1614292D02*
X504711Y1615452D01*
Y1620396D01*
X505031Y1624930D01*
X505619Y1625440D01*
X505721Y1626887D01*
X505211Y1627475D01*
X505313Y1628921D01*
X505901Y1629431D01*
X506003Y1630878D01*
X505493Y1631466D01*
X505614Y1633181D01*
X506138Y1633635D01*
X506259Y1635352D01*
X505805Y1635876D01*
X505926Y1637591D01*
X506450Y1638045D01*
X506571Y1639762D01*
X506117Y1640286D01*
X508137Y1668903D01*
Y1692935D01*
X508717Y1693515D01*
X510158D01*
X510827Y1692846D01*
Y1691692D01*
G01X1333731Y833315D02*
Y832824D01*
X1333730Y832825D01*
Y828954D01*
X1330059Y825283D01*
X1322673Y822222D01*
X1308730Y810712D01*
X1308567Y809005D01*
X1316015Y799983D01*
X1315937Y799169D01*
X1314143Y797688D01*
X1313329Y797766D01*
X1305881Y806788D01*
X1304174Y806951D01*
X1290869Y795968D01*
X1283892Y790521D01*
X1283681Y788819D01*
X1285123Y786975D01*
X1285022Y786163D01*
X1283190Y784731D01*
X1282379Y784832D01*
X1280939Y786676D01*
X1279236Y786886D01*
X1248882Y763187D01*
X1242934Y753561D01*
X1242148Y753376D01*
X1241386Y752142D01*
X1241571Y751357D01*
X1240423Y749499D01*
X1239637Y749313D01*
X1238875Y748079D01*
X1239060Y747294D01*
X1234491Y739900D01*
X1230838Y737598D01*
X1227802Y736691D01*
X1190760Y736013D01*
X1176208Y736416D01*
X1175654Y737003D01*
X1174204Y737043D01*
X1173618Y736489D01*
X1074976Y739226D01*
X1070317Y740423D01*
X1059195Y749105D01*
X1057569Y749701D01*
X1053053Y750378D01*
X1027691Y751438D01*
X983844Y763085D01*
X939928Y783181D01*
X934287Y783886D01*
X929428D01*
X917774Y780441D01*
X878891Y755257D01*
X846476Y739939D01*
X831576Y739025D01*
X818057Y739949D01*
X788058Y736833D01*
X629877Y739550D01*
X625497Y742164D01*
X601274Y766386D01*
X591052Y770678D01*
X590747Y771425D01*
X589409Y771986D01*
X588663Y771682D01*
X585699Y772926D01*
X567670Y789614D01*
X560762Y799424D01*
X560900Y800218D01*
X560066Y801405D01*
X559270Y801543D01*
X558436Y802728D01*
X558574Y803522D01*
X557740Y804709D01*
X556944Y804847D01*
X556110Y806032D01*
X556248Y806826D01*
X555413Y808013D01*
X554618Y808151D01*
X542976Y824684D01*
X542974Y824687D01*
X533185Y834476D01*
G01X1338512Y833315D02*
Y830216D01*
X1338511Y830217D01*
Y822627D01*
X1336791Y806385D01*
X1334718Y803833D01*
X1307543Y782452D01*
X1291970Y776644D01*
X1283649Y772870D01*
X1282045Y773474D01*
X1281279Y775158D01*
X1280513Y775446D01*
X1278397Y774484D01*
X1278109Y773719D01*
X1278875Y772033D01*
X1278271Y770427D01*
X1275342Y769095D01*
X1273738Y769701D01*
X1272972Y771384D01*
X1272206Y771672D01*
X1270090Y770710D01*
X1269802Y769945D01*
X1270568Y768259D01*
X1269964Y766653D01*
X1267035Y765321D01*
X1265431Y765927D01*
X1264665Y767610D01*
X1263899Y767898D01*
X1261783Y766936D01*
X1261495Y766171D01*
X1262261Y764485D01*
X1261657Y762880D01*
X1255672Y760162D01*
X1249465Y755772D01*
X1237875Y736842D01*
X1232985Y733661D01*
X1228447Y732269D01*
X1190815Y731570D01*
X1074847Y734771D01*
X1041681Y738840D01*
X1026865Y747042D01*
X981850Y758751D01*
X938697Y778496D01*
X933986Y779086D01*
X928975D01*
X919907Y776406D01*
X879493Y750230D01*
X847530Y735127D01*
X789073Y732395D01*
X628839Y735033D01*
X621456Y739338D01*
X583106Y769402D01*
X565014Y785641D01*
X540206Y820976D01*
X530926Y830257D01*
Y830262D01*
X529369Y831819D01*
G01X1334811Y833315D02*
Y830216D01*
X1334810Y830217D01*
Y828506D01*
X1330671Y824367D01*
X1323236Y821286D01*
X1309763Y810164D01*
X1309685Y809348D01*
X1317133Y800326D01*
X1316970Y798621D01*
X1314486Y796570D01*
X1312781Y796733D01*
X1305333Y805755D01*
X1304517Y805833D01*
X1291546Y795125D01*
X1284910Y789944D01*
X1284809Y789131D01*
X1286250Y787287D01*
X1286040Y785587D01*
X1283502Y783604D01*
X1281802Y783814D01*
X1280362Y785658D01*
X1279548Y785759D01*
X1249700Y762454D01*
X1235279Y739119D01*
X1231289Y736605D01*
X1227970Y735613D01*
X1190781Y734932D01*
X1190756D01*
X1074825Y738149D01*
X1069830Y739433D01*
X1058664Y748149D01*
X1057300Y748649D01*
X1052950Y749301D01*
X1027528Y750363D01*
X983478Y762064D01*
X939629Y782129D01*
X934219Y782806D01*
X929585D01*
X918230Y779449D01*
X879418Y754311D01*
X846750Y738873D01*
X831572Y737942D01*
X818076Y738865D01*
X788105Y735752D01*
X629570Y738474D01*
X624828Y741305D01*
X600660Y765472D01*
X585105Y772004D01*
X566852Y788898D01*
X542146Y823986D01*
X536027Y830106D01*
X532421Y833712D01*
G01X1337432Y833315D02*
Y832824D01*
X1337431Y832825D01*
Y822685D01*
X1335750Y806818D01*
X1333955Y804608D01*
X1307007Y783406D01*
X1291557Y777644D01*
X1283611Y774039D01*
X1282844Y774328D01*
X1282078Y776013D01*
X1280474Y776615D01*
X1277542Y775283D01*
X1276940Y773679D01*
X1277706Y771994D01*
X1277417Y771226D01*
X1275303Y770265D01*
X1274537Y770554D01*
X1273771Y772239D01*
X1272167Y772841D01*
X1269235Y771509D01*
X1268633Y769905D01*
X1269399Y768220D01*
X1269110Y767452D01*
X1266996Y766491D01*
X1266230Y766780D01*
X1265464Y768465D01*
X1263860Y769067D01*
X1260928Y767735D01*
X1260326Y766131D01*
X1261092Y764446D01*
X1260803Y763679D01*
X1255132Y761103D01*
X1248659Y756526D01*
X1237080Y737614D01*
X1237081D01*
X1232523Y734649D01*
X1228275Y733346D01*
X1190820Y732651D01*
X1074928Y735850D01*
X1042021Y739887D01*
X1027269Y748053D01*
X982214Y759773D01*
X938996Y779547D01*
X934054Y780166D01*
X928818D01*
X924134Y778782D01*
X919451Y777398D01*
X878966Y751176D01*
X847264Y736196D01*
X789066Y733476D01*
X789057D01*
X629139Y736109D01*
X622064Y740234D01*
X599639Y757814D01*
X599542Y758614D01*
X598400Y759509D01*
X597600Y759412D01*
X597601Y759413D01*
X596460Y760307D01*
X596459Y760306D01*
X596362Y761107D01*
X595220Y762002D01*
X594421Y761905D01*
X593280Y762800D01*
X593279Y762799D01*
X593182Y763601D01*
X592040Y764495D01*
X591239Y764398D01*
X591240Y764399D01*
X589308Y765914D01*
X589307Y765913D01*
X589211Y766714D01*
X588068Y767609D01*
X587268Y767512D01*
X583801Y770230D01*
X565828Y786363D01*
X541037Y821674D01*
X532454Y830257D01*
Y830262D01*
X530133Y832583D01*
G01X1327002Y833315D02*
Y832824D01*
X1327001Y832825D01*
Y831743D01*
X1324756Y829498D01*
X1320518Y827742D01*
X1317618Y825469D01*
X1315916Y825676D01*
X1314158Y827919D01*
X1313346Y828017D01*
X1311515Y826582D01*
X1311417Y825771D01*
X1313176Y823527D01*
X1312969Y821825D01*
X1310437Y819840D01*
X1308735Y820047D01*
X1306977Y822290D01*
X1306165Y822388D01*
X1304334Y820953D01*
X1304236Y820142D01*
X1305995Y817898D01*
X1305788Y816196D01*
X1303256Y814211D01*
X1301554Y814418D01*
X1299796Y816661D01*
X1298984Y816759D01*
X1297153Y815324D01*
X1297055Y814513D01*
X1298814Y812269D01*
X1298607Y810567D01*
X1286564Y801128D01*
X1239173Y763983D01*
X1231336Y755088D01*
X1230411Y754545D01*
X1214966Y750969D01*
X1208203Y750756D01*
X1208202Y750755D01*
X1201477Y750545D01*
X1188759Y751779D01*
X1188126Y751257D01*
X1187852Y748435D01*
X1186530Y747346D01*
X1183325Y747657D01*
X1182236Y748980D01*
X1182510Y751802D01*
X1181988Y752434D01*
X1173236Y753283D01*
X1127974Y753088D01*
X1127950D01*
X1028374Y757059D01*
X986708Y768174D01*
X942177Y788553D01*
X934638Y789494D01*
X928965D01*
X915997Y786265D01*
X866436Y759969D01*
X820661Y752578D01*
X749138Y755472D01*
X629793Y753874D01*
X621162Y757000D01*
X616351Y759444D01*
X609594Y766261D01*
X607966Y770240D01*
X601127Y777139D01*
X600308Y777142D01*
X598507Y775356D01*
X596794Y775363D01*
X594526Y777650D01*
X594533Y779363D01*
X596334Y781149D01*
X596337Y781968D01*
X594702Y783618D01*
X593883Y783621D01*
X592082Y781835D01*
X590369Y781842D01*
X588101Y784129D01*
X588108Y785842D01*
X589909Y787628D01*
X589912Y788447D01*
X588277Y790097D01*
X587458Y790100D01*
X585657Y788314D01*
X583944Y788321D01*
X581676Y790608D01*
X581683Y792321D01*
X583484Y794107D01*
X583487Y794926D01*
X581852Y796576D01*
X581033Y796579D01*
X579232Y794793D01*
X577519Y794800D01*
X575251Y797087D01*
X575258Y798800D01*
X577059Y800586D01*
X577062Y801405D01*
X575427Y803055D01*
X574608Y803058D01*
X572807Y801272D01*
X571094Y801279D01*
X568826Y803566D01*
X568833Y805279D01*
X570634Y807065D01*
X570637Y807884D01*
X569002Y809534D01*
X568183Y809537D01*
X566382Y807751D01*
X564669Y807758D01*
X562401Y810045D01*
X562408Y811758D01*
X564209Y813544D01*
X564212Y814363D01*
X561633Y816964D01*
X557775Y818583D01*
X536556Y839948D01*
G01X1330680Y833315D02*
Y832824D01*
X1330679Y832825D01*
Y830218D01*
X1327218Y826757D01*
X1322229Y824690D01*
X1241226Y761270D01*
X1240014Y759877D01*
X1232951Y741569D01*
X1229730Y739568D01*
X1227694Y738966D01*
X1190594Y738240D01*
X1184491Y741292D01*
X1179474Y745306D01*
X1174457Y749319D01*
X1172004Y749883D01*
X1127890Y749691D01*
X1027862Y753681D01*
X984780Y765172D01*
X940789Y785303D01*
X934425Y786099D01*
X929127D01*
X917116Y783109D01*
X867428Y756745D01*
X820395Y749159D01*
X751220Y751956D01*
X656548Y750689D01*
X655975Y750104D01*
X656062Y743603D01*
X654866Y742375D01*
X651646Y742331D01*
X650419Y743526D01*
X650332Y750028D01*
X649746Y750600D01*
X647425Y750567D01*
X646852Y749980D01*
X646939Y743480D01*
X645743Y742252D01*
X642523Y742208D01*
X641296Y743403D01*
X641209Y749905D01*
X640623Y750477D01*
X629196Y750323D01*
X619751Y753743D01*
X614235Y756544D01*
X602636Y768248D01*
X595625Y771191D01*
X591298Y775553D01*
X590479Y775556D01*
X589372Y774461D01*
X587660Y774468D01*
X585392Y776755D01*
X585399Y778469D01*
X586505Y779563D01*
X586508Y780382D01*
X584125Y782785D01*
X583305Y782788D01*
X582293Y781785D01*
X580579Y781794D01*
X578312Y784082D01*
X578321Y785795D01*
X579333Y786798D01*
X579337Y787617D01*
X577703Y789267D01*
X576884Y789271D01*
X575871Y788268D01*
X574157Y788277D01*
X571890Y790565D01*
X571899Y792278D01*
X572911Y793281D01*
X572915Y794100D01*
X571281Y795750D01*
X570462Y795754D01*
X569449Y794751D01*
X567735Y794760D01*
X565468Y797048D01*
X565477Y798761D01*
X566489Y799764D01*
X566493Y800583D01*
X554035Y813154D01*
X545471Y826023D01*
X534445Y837049D01*
G01X1325922Y833315D02*
Y832824D01*
X1325921Y832825D01*
Y832191D01*
X1324144Y830414D01*
X1319968Y828684D01*
X1317304Y826596D01*
X1316491Y826695D01*
X1314732Y828938D01*
X1313032Y829144D01*
X1310496Y827156D01*
X1310290Y825456D01*
X1312049Y823213D01*
X1311950Y822400D01*
X1310123Y820967D01*
X1309310Y821066D01*
X1307551Y823309D01*
X1305851Y823515D01*
X1303315Y821527D01*
X1303109Y819827D01*
X1304868Y817584D01*
X1304769Y816771D01*
X1302942Y815338D01*
X1302129Y815437D01*
X1300370Y817680D01*
X1298670Y817886D01*
X1296134Y815898D01*
X1295928Y814198D01*
X1297687Y811955D01*
X1297588Y811142D01*
X1238428Y764772D01*
X1230640Y755932D01*
X1230007Y755561D01*
Y755562D01*
X1230006Y755561D01*
X1214826Y752046D01*
X1201512Y751627D01*
X1188417Y752898D01*
X1187094Y751806D01*
X1186819Y748985D01*
X1186189Y748465D01*
X1183875Y748689D01*
X1183355Y749321D01*
X1183629Y752144D01*
X1182537Y753467D01*
X1173286Y754364D01*
X1127969Y754169D01*
Y754170D01*
X1028537Y758134D01*
X987075Y769195D01*
X942476Y789605D01*
X934706Y790574D01*
X928832D01*
X915607Y787282D01*
X866088Y761007D01*
X820596Y753662D01*
X749153Y756553D01*
X629976Y754957D01*
X621592Y757993D01*
X616996Y760329D01*
X610513Y766869D01*
X608885Y770848D01*
X601580Y778218D01*
X599865Y778224D01*
X598064Y776438D01*
X597246Y776442D01*
X595608Y778093D01*
X595612Y778911D01*
X597413Y780697D01*
X597419Y782411D01*
X595154Y784697D01*
X593440Y784703D01*
X591639Y782917D01*
X590821Y782921D01*
X589183Y784572D01*
X589187Y785390D01*
X590988Y787176D01*
X590994Y788890D01*
X588729Y791176D01*
X587015Y791182D01*
X585214Y789396D01*
X584396Y789400D01*
X582758Y791051D01*
X582762Y791869D01*
X584563Y793655D01*
X584569Y795369D01*
X582304Y797655D01*
X580590Y797661D01*
X578789Y795875D01*
X577971Y795879D01*
X576333Y797530D01*
X576337Y798348D01*
X578138Y800134D01*
X578144Y801848D01*
X575879Y804134D01*
X574165Y804140D01*
X572364Y802354D01*
X571546Y802358D01*
X569908Y804009D01*
X569912Y804827D01*
X571713Y806613D01*
X571719Y808327D01*
X569454Y810613D01*
X567740Y810619D01*
X565939Y808833D01*
X565121Y808837D01*
X563483Y810488D01*
X563487Y811306D01*
X565288Y813092D01*
X565295Y814806D01*
X562249Y817877D01*
X558391Y819496D01*
Y819497D01*
X551577Y826358D01*
X551575D01*
X551578Y827164D01*
X550555Y828194D01*
X549749Y828197D01*
X548728Y829225D01*
X548730Y830031D01*
X547707Y831061D01*
X546901Y831064D01*
X546902Y831065D01*
X545881Y832092D01*
X545880D01*
X545883Y832898D01*
X544860Y833928D01*
X544054Y833931D01*
X544055Y833932D01*
X543015Y834978D01*
X543014D01*
X543017Y835784D01*
X541994Y836814D01*
X541188Y836817D01*
X540167Y837845D01*
X540170Y838651D01*
X539147Y839681D01*
X538341Y839684D01*
X537320Y840712D01*
G01X1329600Y833315D02*
Y832824D01*
X1329599Y832825D01*
Y830666D01*
X1326606Y827673D01*
X1321679Y825632D01*
X1240479Y762057D01*
X1239074Y760443D01*
X1237337Y755941D01*
X1236599Y755614D01*
X1236078Y754261D01*
X1236404Y753524D01*
X1235258Y750552D01*
X1234520Y750225D01*
X1233998Y748871D01*
X1234325Y748134D01*
X1232073Y742296D01*
X1229283Y740563D01*
X1227527Y740043D01*
X1190839Y739326D01*
X1185077Y742208D01*
X1174940Y750317D01*
X1172124Y750964D01*
X1127909Y750772D01*
X1028025Y754756D01*
X985147Y766193D01*
X941088Y786355D01*
X934493Y787179D01*
X928994D01*
X916726Y784126D01*
X867080Y757783D01*
X820330Y750243D01*
X751235Y753037D01*
X656086Y751764D01*
X654889Y750538D01*
X654976Y744036D01*
X654404Y743449D01*
X652079Y743418D01*
X651493Y743988D01*
X651406Y750489D01*
X650180Y751687D01*
X646964Y751641D01*
X645766Y750414D01*
X645853Y743913D01*
X645281Y743326D01*
X642956Y743295D01*
X642370Y743865D01*
X642283Y750366D01*
X641057Y751563D01*
X629378Y751406D01*
X620181Y754736D01*
X614880Y757429D01*
X603252Y769161D01*
X596241Y772104D01*
X591750Y776632D01*
X590036Y776638D01*
X588930Y775543D01*
X588112Y775547D01*
X586474Y777198D01*
X586478Y778016D01*
X587584Y779110D01*
X587590Y780825D01*
X584577Y783864D01*
X582862Y783870D01*
X581850Y782868D01*
X581032Y782872D01*
X579395Y784524D01*
X579399Y785342D01*
X580412Y786345D01*
X580420Y788059D01*
X578156Y790345D01*
X576442Y790354D01*
X575429Y789351D01*
X574610Y789355D01*
X572973Y791007D01*
X572977Y791825D01*
X573990Y792828D01*
X573998Y794542D01*
X571734Y796828D01*
X570020Y796837D01*
X569007Y795834D01*
X568188Y795838D01*
X566551Y797490D01*
X566555Y798308D01*
X567568Y799311D01*
X567576Y801026D01*
X561072Y807588D01*
X561075Y808267D01*
X559863Y809490D01*
X559184Y809493D01*
X557974Y810714D01*
X557977Y811393D01*
X556765Y812616D01*
X556086Y812619D01*
X554876Y813840D01*
Y813841D01*
X553356Y816126D01*
X553515Y816916D01*
X552712Y818124D01*
X551920Y818283D01*
X550818Y819940D01*
X550976Y820730D01*
X550173Y821939D01*
X549382Y822097D01*
X548579Y823304D01*
X548737Y824094D01*
X547934Y825302D01*
X547143Y825461D01*
X546311Y826711D01*
X535209Y837813D01*
G01X526575Y1696417D02*
Y1695176D01*
X525994Y1694595D01*
X524017D01*
X522805Y1693383D01*
Y1669034D01*
X527461Y1618075D01*
X527751Y1616938D01*
Y1615452D01*
X526591Y1614292D01*
G01X529991D02*
X528831Y1615452D01*
Y1617074D01*
X528529Y1618259D01*
X525367Y1652871D01*
X525865Y1653469D01*
X525733Y1654914D01*
X525134Y1655412D01*
X525003Y1656855D01*
X525500Y1657453D01*
X525368Y1658898D01*
X524769Y1659396D01*
X524638Y1660839D01*
X525136Y1661437D01*
X525004Y1662882D01*
X524405Y1663380D01*
X524274Y1664823D01*
X524771Y1665421D01*
X524639Y1666866D01*
X524041Y1667364D01*
X524043D01*
X523887Y1669072D01*
X523885Y1669074D01*
Y1692935D01*
X524465Y1693515D01*
X525742D01*
X526575Y1692682D01*
Y1691692D01*
G01X534449Y1700354D02*
Y1699113D01*
X533868Y1698532D01*
X531891D01*
X530679Y1697320D01*
Y1669322D01*
X539811Y1616130D01*
Y1615452D01*
X538651Y1614292D01*
G01X542051D02*
X540891Y1615452D01*
Y1616297D01*
X540876Y1616312D01*
X533113Y1661529D01*
X533562Y1662164D01*
X533317Y1663594D01*
X532681Y1664043D01*
X532436Y1665472D01*
X532885Y1666107D01*
X532640Y1667537D01*
X532004Y1667986D01*
X531759Y1669415D01*
Y1696872D01*
X532339Y1697452D01*
X533616D01*
X534449Y1696619D01*
Y1695629D01*
G01X542323Y1696417D02*
Y1695176D01*
X541742Y1694595D01*
X539765D01*
X538553Y1693383D01*
Y1669166D01*
X551870Y1616525D01*
Y1615451D01*
X550711Y1614292D01*
G01X554111D02*
X552950Y1615453D01*
Y1616660D01*
X542695Y1657205D01*
X543094Y1657873D01*
X542738Y1659279D01*
X542069Y1659678D01*
X541714Y1661083D01*
X542113Y1661751D01*
X541757Y1663157D01*
X541088Y1663556D01*
X540733Y1664961D01*
X541131Y1665629D01*
X540776Y1667035D01*
X540106Y1667434D01*
X539633Y1669307D01*
Y1692935D01*
X540213Y1693515D01*
X541638D01*
X542323Y1692830D01*
Y1691692D01*
G01X550197Y1700354D02*
Y1699113D01*
X549616Y1698532D01*
X547791D01*
X546427Y1697168D01*
Y1668932D01*
X563931Y1616681D01*
Y1615452D01*
X562771Y1614292D01*
G01X566171D02*
X565011Y1615452D01*
Y1616969D01*
X564955Y1617025D01*
X557876Y1638158D01*
X551427Y1657410D01*
X551774Y1658106D01*
X551313Y1659482D01*
X550616Y1659829D01*
X550156Y1661203D01*
X550503Y1661899D01*
X550042Y1663275D01*
X549345Y1663622D01*
X548885Y1664996D01*
X549232Y1665692D01*
X548772Y1667068D01*
X548074Y1667414D01*
X547507Y1669109D01*
Y1696720D01*
X548239Y1697452D01*
X549364D01*
X550197Y1696619D01*
Y1695629D01*
G01X562008Y1696417D02*
Y1695176D01*
X561427Y1694595D01*
X559450D01*
X558238Y1693383D01*
Y1669082D01*
X576010Y1616347D01*
Y1615471D01*
X574831Y1614292D01*
G01X578231D02*
X577090Y1615433D01*
Y1616525D01*
X564998Y1652412D01*
X565343Y1653109D01*
X564880Y1654484D01*
X564183Y1654829D01*
X563720Y1656203D01*
X564065Y1656900D01*
X563602Y1658275D01*
X562905Y1658620D01*
X562442Y1659994D01*
X562787Y1660691D01*
X562324Y1662066D01*
X561627Y1662411D01*
X561164Y1663785D01*
X561509Y1664481D01*
X561046Y1665857D01*
X560348Y1666202D01*
X559318Y1669260D01*
Y1692935D01*
X559898Y1693515D01*
X561175D01*
X562008Y1692682D01*
Y1691692D01*
G01X569882Y1700354D02*
Y1699113D01*
X569301Y1698532D01*
X567290D01*
X566112Y1697354D01*
Y1669152D01*
X588051Y1616581D01*
Y1615452D01*
X586891Y1614292D01*
G01X590291D02*
X589131Y1615452D01*
Y1616798D01*
X571408Y1659269D01*
X571704Y1659988D01*
X571145Y1661328D01*
X570425Y1661623D01*
X569867Y1662961D01*
X570162Y1663680D01*
X569604Y1665019D01*
X568883Y1665315D01*
X567192Y1669369D01*
Y1696906D01*
X567738Y1697452D01*
X569049D01*
X569882Y1696619D01*
Y1695629D01*
G01X577756Y1696417D02*
Y1695176D01*
X577175Y1694595D01*
X575342D01*
X573986Y1693239D01*
Y1670142D01*
X600111Y1616680D01*
Y1615452D01*
X598951Y1614292D01*
G01X602351D02*
X601191Y1615452D01*
Y1616930D01*
X583388Y1653363D01*
X583389Y1653365D01*
X583641Y1654100D01*
X583005Y1655404D01*
X582268Y1655657D01*
X581632Y1656959D01*
X581884Y1657694D01*
X581248Y1658998D01*
X580511Y1659251D01*
X579875Y1660553D01*
X580127Y1661288D01*
X579491Y1662592D01*
X578754Y1662845D01*
X578118Y1664147D01*
X578371Y1664883D01*
X577734Y1666187D01*
X576997Y1666439D01*
X575066Y1670392D01*
Y1692791D01*
X575790Y1693515D01*
X576923D01*
X577756Y1692682D01*
Y1691692D01*
G01X585630Y1700354D02*
Y1699113D01*
X584989Y1698472D01*
X583530D01*
X581860Y1696802D01*
Y1669002D01*
X612171Y1616819D01*
Y1615452D01*
X611011Y1614292D01*
G01X614411D02*
X613251Y1615452D01*
Y1617110D01*
X589734Y1657599D01*
X589933Y1658350D01*
X589205Y1659605D01*
X588452Y1659805D01*
X587724Y1661058D01*
X587923Y1661809D01*
X587195Y1663064D01*
X586442Y1663264D01*
X585714Y1664517D01*
X585914Y1665269D01*
X585186Y1666523D01*
X584433Y1666723D01*
X582940Y1669293D01*
Y1696354D01*
X583978Y1697392D01*
X584857D01*
X585630Y1696619D01*
Y1695629D01*
G01X593504Y1696417D02*
Y1695176D01*
X592923Y1694595D01*
X590946D01*
X589734Y1693383D01*
Y1667673D01*
X624231Y1616934D01*
Y1615452D01*
X623071Y1614292D01*
G01X626471D02*
X625311Y1615452D01*
Y1617267D01*
X600456Y1653824D01*
X600602Y1654588D01*
X599787Y1655788D01*
X599022Y1655933D01*
X598207Y1657132D01*
X598353Y1657896D01*
X597538Y1659096D01*
X596773Y1659241D01*
X595958Y1660440D01*
X596104Y1661204D01*
X595289Y1662404D01*
X594524Y1662549D01*
X593709Y1663748D01*
X593855Y1664512D01*
X593040Y1665712D01*
X592275Y1665857D01*
X590814Y1668006D01*
Y1692935D01*
X591394Y1693515D01*
X592671D01*
X593504Y1692682D01*
Y1691692D01*
G01X601378Y1700354D02*
Y1699113D01*
X600797Y1698532D01*
X598690D01*
X597608Y1697450D01*
Y1681845D01*
X597607Y1681844D01*
Y1668813D01*
X598153Y1667191D01*
X636291Y1616982D01*
Y1615452D01*
X635131Y1614292D01*
G01X626640Y188752D02*
X627800Y187592D01*
Y186771D01*
X626921Y185892D01*
X624470D01*
X623630Y186732D01*
Y191047D01*
X620889Y193788D01*
X617262D01*
X615071Y191597D01*
Y189853D01*
X613970Y188752D01*
G01X638531Y1614292D02*
X637371Y1615452D01*
Y1617346D01*
X604783Y1660249D01*
X604888Y1661020D01*
X604010Y1662176D01*
X603240Y1662281D01*
X602363Y1663435D01*
X602468Y1664205D01*
X601590Y1665361D01*
X600821Y1665466D01*
X599121Y1667704D01*
X598687Y1668990D01*
Y1681843D01*
X598688Y1681844D01*
Y1697002D01*
X599138Y1697452D01*
X600545D01*
X601378Y1696619D01*
Y1695629D01*
G01X609252Y1696417D02*
Y1695176D01*
X608738Y1694662D01*
X606761D01*
X605482Y1693383D01*
Y1671236D01*
X606206Y1669322D01*
X644709Y1625766D01*
X645366Y1624248D01*
Y1624249D01*
X646770Y1621008D01*
X648351Y1617357D01*
Y1615452D01*
X647191Y1614292D01*
G01X650591D02*
X649431Y1615452D01*
Y1617581D01*
X647372Y1622337D01*
X647658Y1623060D01*
X647081Y1624392D01*
X646357Y1624678D01*
X645632Y1626353D01*
X612940Y1663335D01*
Y1663337D01*
X612987Y1664113D01*
X612026Y1665200D01*
X611250Y1665248D01*
X610290Y1666334D01*
X610338Y1667110D01*
X609377Y1668197D01*
X608601Y1668245D01*
X607147Y1669890D01*
X606562Y1671434D01*
Y1692935D01*
X607209Y1693582D01*
X608730D01*
X609252Y1693060D01*
Y1691692D01*
G01X662651Y1614292D02*
X661491Y1615452D01*
Y1617312D01*
X658235Y1624696D01*
X636381Y1644649D01*
X624165Y1657865D01*
X624195Y1658643D01*
X623210Y1659709D01*
X622433Y1659740D01*
X621449Y1660804D01*
X621479Y1661581D01*
X620494Y1662647D01*
X619717Y1662678D01*
X618733Y1663742D01*
X618763Y1664519D01*
X617778Y1665585D01*
X617001Y1665615D01*
X615499Y1667240D01*
X614436Y1669954D01*
Y1696872D01*
X615016Y1697452D01*
X616293D01*
X617126Y1696619D01*
Y1695629D01*
G01Y1700354D02*
Y1699113D01*
X616545Y1698532D01*
X614568D01*
X613356Y1697320D01*
Y1669750D01*
X614567Y1666656D01*
X623067Y1657460D01*
X623068D01*
X635619Y1643882D01*
X657338Y1624051D01*
X660411Y1617084D01*
Y1615452D01*
X659251Y1614292D01*
G01X630040Y188752D02*
X628880Y187592D01*
Y186323D01*
X627369Y184812D01*
X624022D01*
X622550Y186284D01*
Y190599D01*
X620441Y192708D01*
X617710D01*
X616151Y191149D01*
Y189971D01*
X617370Y188752D01*
G01X656439Y47264D02*
X657599Y46104D01*
Y38933D01*
X661170Y35362D01*
X703238D01*
X719998Y52122D01*
X750638D01*
X752628Y54112D01*
X760152D01*
X813081Y64639D01*
X828276Y79834D01*
X835867Y98179D01*
Y109287D01*
X836542Y109962D01*
X839940D01*
X851181Y121203D01*
X856761D01*
X880300Y144742D01*
X1022379D01*
X1181853Y78684D01*
X1206227Y71291D01*
X1262165Y60165D01*
X1283832Y51191D01*
X1300784D01*
X1308295Y54302D01*
X1338289D01*
X1387578Y74718D01*
X1433133Y105156D01*
X1455490Y127514D01*
Y186853D01*
X1451455Y196595D01*
X1434900Y213150D01*
Y218858D01*
X1436060Y220018D01*
G01X659839Y47264D02*
X658679Y46104D01*
Y39381D01*
X661618Y36442D01*
X702790D01*
X719550Y53202D01*
X750190D01*
X752180Y55192D01*
X760045D01*
X812549Y65635D01*
X827360Y80446D01*
X830850Y88881D01*
X830590Y89508D01*
X831248Y91098D01*
X831876Y91358D01*
X832533Y92947D01*
X832273Y93574D01*
X832930Y95164D01*
X833558Y95424D01*
X834787Y98394D01*
Y109735D01*
X836094Y111042D01*
X839492D01*
X850733Y122283D01*
X856313D01*
X879852Y145822D01*
X1022594D01*
X1182218Y79703D01*
X1194353Y76022D01*
X1194354D01*
X1206490Y72340D01*
X1262480Y61204D01*
X1284047Y52271D01*
X1300569D01*
X1308080Y55382D01*
X1338074D01*
X1387066Y75675D01*
X1432444Y105996D01*
X1445224Y118776D01*
Y119582D01*
X1446250Y120608D01*
X1447056D01*
X1448081Y121633D01*
Y122439D01*
X1449107Y123465D01*
X1449913D01*
X1454410Y127962D01*
Y130077D01*
X1453840Y130647D01*
Y132097D01*
X1454410Y132667D01*
Y134117D01*
X1453840Y134687D01*
Y136137D01*
X1454410Y136707D01*
Y138157D01*
X1453840Y138727D01*
Y140177D01*
X1454410Y140747D01*
Y142197D01*
X1453840Y142767D01*
Y144217D01*
X1454410Y144787D01*
Y186638D01*
X1450539Y195983D01*
X1433820Y212702D01*
Y218858D01*
X1432660Y220018D01*
G01X723041Y-13200D02*
X724201Y-12040D01*
X741400D01*
X742025Y-12565D01*
X745310Y-31199D01*
X746714Y-32184D01*
X752943Y-31086D01*
X753928Y-29682D01*
X749467Y-4379D01*
X749937Y-3708D01*
X755285Y-2765D01*
X755955Y-3235D01*
X760894Y-31238D01*
X762298Y-32223D01*
X768527Y-31125D01*
X769512Y-29721D01*
X765019Y-4236D01*
X765489Y-3565D01*
X770837Y-2622D01*
X771507Y-3092D01*
X776439Y-31072D01*
X777845Y-32055D01*
X784073Y-30956D01*
X785058Y-29552D01*
X780664Y-4623D01*
X781134Y-3952D01*
X786482Y-3008D01*
X787152Y-3478D01*
X792026Y-31121D01*
X793432Y-32104D01*
X799660Y-31005D01*
X800645Y-29601D01*
X796205Y-4421D01*
X796675Y-3751D01*
X802023Y-2807D01*
X802693Y-3277D01*
X807514Y-30622D01*
X808920Y-31605D01*
X815148Y-30508D01*
X816133Y-29104D01*
X811808Y-4570D01*
X812278Y-3899D01*
X817625Y-2955D01*
X818296Y-3425D01*
X823109Y-30724D01*
X824513Y-31709D01*
X830743Y-30611D01*
X831727Y-29204D01*
X827352Y-4389D01*
X827822Y-3718D01*
X833170Y-2775D01*
X833840Y-3245D01*
X838439Y-29320D01*
X839843Y-30305D01*
X846072Y-29206D01*
X847057Y-27802D01*
X842963Y-4584D01*
X843433Y-3913D01*
X848781Y-2970D01*
X849451Y-3440D01*
X854006Y-29261D01*
X855410Y-30245D01*
X861638Y-29146D01*
X862623Y-27742D01*
X858563Y-4714D01*
X859033Y-4041D01*
Y-4042D01*
X864381Y-3098D01*
X865051Y-3567D01*
X869609Y-29413D01*
X871013Y-30397D01*
X877243Y-29300D01*
X878226Y-27894D01*
X874091Y-4446D01*
X874561Y-3774D01*
Y-3775D01*
X879909Y-2831D01*
X880582Y-3301D01*
X885144Y-29173D01*
X886546Y-30157D01*
X892776Y-29058D01*
X893760Y-27656D01*
X889709Y-4680D01*
X890179Y-4009D01*
X895527Y-3066D01*
X896199Y-3538D01*
X900726Y-29202D01*
X902128Y-30186D01*
X908358Y-29087D01*
X909342Y-27685D01*
X905260Y-4531D01*
X905730Y-3858D01*
Y-3859D01*
X911078Y-2915D01*
X911750Y-3386D01*
X916324Y-29330D01*
X917728Y-30314D01*
X923957Y-29214D01*
X924941Y-27812D01*
X920862Y-4676D01*
X921332Y-4005D01*
X926680Y-3061D01*
X927353Y-3531D01*
X931860Y-29092D01*
X933262Y-30076D01*
X939493Y-28979D01*
X940476Y-27573D01*
X936388Y-4387D01*
X936857Y-3715D01*
X942206Y-2772D01*
X942878Y-3242D01*
X947432Y-29068D01*
X948835Y-30052D01*
X955066Y-28955D01*
X956048Y-27550D01*
X951999Y-4583D01*
X952468Y-3913D01*
X957816Y-2970D01*
X958488Y-3440D01*
X959822Y-11010D01*
X961049Y-12040D01*
X979739D01*
X980899Y-13200D01*
G01X723041Y-9800D02*
X724201Y-10960D01*
X741793D01*
X743021Y-11990D01*
X746296Y-30571D01*
X746968Y-31042D01*
X752315Y-30099D01*
X752786Y-29428D01*
X748325Y-4125D01*
X749308Y-2721D01*
X755538Y-1623D01*
X756942Y-2606D01*
X761880Y-30610D01*
X762552Y-31081D01*
X767899Y-30138D01*
X768370Y-29467D01*
X763877Y-3982D01*
X764860Y-2578D01*
X771090Y-1480D01*
X772494Y-2463D01*
X777426Y-30443D01*
X778098Y-30913D01*
X783445Y-29970D01*
X783916Y-29298D01*
X779522Y-4370D01*
X780505Y-2965D01*
X786735Y-1866D01*
X788139Y-2849D01*
X793013Y-30492D01*
X793685Y-30962D01*
X799032Y-30019D01*
X799503Y-29347D01*
X795063Y-4168D01*
X796046Y-2764D01*
X802276Y-1665D01*
X803680Y-2648D01*
X808500Y-29993D01*
X809173Y-30463D01*
X814520Y-29521D01*
X814991Y-28850D01*
X810666Y-4316D01*
X811649Y-2912D01*
X817879Y-1813D01*
X819282Y-2797D01*
X824096Y-30096D01*
X824767Y-30567D01*
X830114Y-29624D01*
X830585Y-28951D01*
X826210Y-4135D01*
X827193Y-2731D01*
X833423Y-1633D01*
X834827Y-2616D01*
X839425Y-28692D01*
X840097Y-29163D01*
X845444Y-28220D01*
X845915Y-27548D01*
X841821Y-4331D01*
X842804Y-2926D01*
X849034Y-1828D01*
X850438Y-2811D01*
X854992Y-28633D01*
X855663Y-29103D01*
X861010Y-28160D01*
X861481Y-27488D01*
X857421Y-4460D01*
X858405Y-3055D01*
X864634Y-1956D01*
X866037Y-2939D01*
X870595Y-28785D01*
X871266Y-29255D01*
X876614Y-28313D01*
X877084Y-27641D01*
X872949Y-4192D01*
X873933Y-2788D01*
X880162Y-1689D01*
X881568Y-2672D01*
X886130Y-28545D01*
X886800Y-29015D01*
X892148Y-28072D01*
X892618Y-27402D01*
X888567Y-4427D01*
X889550Y-3022D01*
X895781Y-1924D01*
X897186Y-2910D01*
X901712Y-28574D01*
X902382Y-29044D01*
X907730Y-28101D01*
X908200Y-27431D01*
X904118Y-4278D01*
X905101Y-2872D01*
X911332Y-1773D01*
X912736Y-2758D01*
X917310Y-28702D01*
X917981Y-29172D01*
X923329Y-28228D01*
X923799Y-27558D01*
X919720Y-4422D01*
X920703Y-3018D01*
X926933Y-1919D01*
X928339Y-2902D01*
X932846Y-28464D01*
X933516Y-28934D01*
X938864Y-27992D01*
X939334Y-27320D01*
X935246Y-4132D01*
X936229Y-2729D01*
X942459Y-1630D01*
X943865Y-2613D01*
X948418Y-28440D01*
X949089Y-28910D01*
X954437Y-27969D01*
X954906Y-27297D01*
X950857Y-4329D01*
X951840Y-2927D01*
X958069Y-1828D01*
X959475Y-2811D01*
X960818Y-10435D01*
X961443Y-10960D01*
X979739D01*
X980899Y-9800D01*
G01X840001Y20200D02*
X841161Y19040D01*
X856680D01*
X860299Y15421D01*
X861332Y9566D01*
X862003Y9095D01*
X867351Y10038D01*
X867822Y10711D01*
X863801Y33512D01*
X864785Y34916D01*
X871014Y36014D01*
X872418Y35031D01*
X876949Y9338D01*
X877620Y8867D01*
X882968Y9810D01*
X883439Y10483D01*
X879368Y33566D01*
X880352Y34971D01*
X886581Y36070D01*
X887985Y35087D01*
X892513Y9407D01*
X893185Y8937D01*
X898533Y9880D01*
X899003Y10552D01*
X894958Y33494D01*
X895941Y34900D01*
X902171Y35999D01*
X903574Y35016D01*
X908105Y9321D01*
X908777Y8851D01*
X914125Y9794D01*
X914595Y10465D01*
X910503Y33670D01*
X911486Y35074D01*
X917716Y36172D01*
X919120Y35189D01*
X923688Y9282D01*
X924360Y8811D01*
X929708Y9754D01*
X930178Y10427D01*
X926117Y33460D01*
X927100Y34865D01*
X933330Y35963D01*
X934733Y34980D01*
X939232Y9471D01*
X939904Y9000D01*
X945252Y9943D01*
X945722Y10615D01*
X941645Y33734D01*
X942628Y35139D01*
X948858Y36237D01*
X950262Y35254D01*
X954794Y9553D01*
X955466Y9083D01*
X960814Y10026D01*
X961284Y10698D01*
X957247Y33589D01*
X958230Y34993D01*
X964460Y36092D01*
X965865Y35109D01*
X968425Y20594D01*
X969979Y19040D01*
X979739D01*
X980899Y20200D01*
G01X840001Y16800D02*
X841161Y17960D01*
X856232D01*
X859294Y14898D01*
X860345Y8938D01*
X861749Y7953D01*
X867980Y9051D01*
X868964Y10458D01*
X864943Y33259D01*
X865413Y33930D01*
X870761Y34872D01*
X871431Y34402D01*
X875962Y8710D01*
X877366Y7725D01*
X883597Y8823D01*
X884581Y10230D01*
X880510Y33313D01*
X880980Y33985D01*
X886328Y34928D01*
X886998Y34458D01*
X891526Y8778D01*
X892932Y7795D01*
X899162Y8893D01*
X900145Y10299D01*
X896100Y33241D01*
X896570Y33914D01*
X901918Y34857D01*
X902588Y34388D01*
X907118Y8692D01*
X908524Y7709D01*
X914753Y8807D01*
X915737Y10212D01*
X911645Y33417D01*
X912115Y34087D01*
X917463Y35030D01*
X918133Y34560D01*
X922702Y8654D01*
X924107Y7669D01*
X930337Y8768D01*
X931320Y10175D01*
X927259Y33207D01*
X927729Y33878D01*
X933077Y34821D01*
X933747Y34352D01*
X938246Y8843D01*
X939651Y7858D01*
X945881Y8956D01*
X946864Y10362D01*
X942787Y33481D01*
X943257Y34152D01*
X948605Y35095D01*
X949275Y34625D01*
X953807Y8924D01*
X955213Y7941D01*
X955653Y8018D01*
Y8019D01*
X961443Y9039D01*
X962426Y10445D01*
X958389Y33336D01*
X958859Y34006D01*
X964207Y34950D01*
X964878Y34480D01*
X967420Y20071D01*
X969531Y17960D01*
X979739D01*
X980899Y16800D01*
G01X1384002Y197668D02*
X1382842Y198828D01*
Y201145D01*
X1385818Y204121D01*
X1386624D01*
X1387651Y205148D01*
Y205954D01*
X1388676Y206979D01*
X1389482D01*
X1390508Y208005D01*
Y208811D01*
X1391533Y209836D01*
X1392339D01*
X1393365Y210862D01*
Y211668D01*
X1397759Y216062D01*
X1400100D01*
X1400580Y215582D01*
X1402300D01*
X1402780Y216062D01*
X1404500D01*
X1404980Y215582D01*
X1406700D01*
X1407180Y216062D01*
X1408900D01*
X1409380Y215582D01*
X1411100D01*
X1411580Y216062D01*
X1413520D01*
X1414000Y215582D01*
X1415720D01*
X1416200Y216062D01*
X1417920D01*
X1418400Y215582D01*
X1420120D01*
X1420600Y216062D01*
X1425150D01*
X1427590Y213622D01*
Y212929D01*
X1428807Y211712D01*
X1429500D01*
X1430716Y210496D01*
Y209803D01*
X1431933Y208586D01*
X1432626D01*
X1433842Y207370D01*
Y206677D01*
X1435059Y205460D01*
X1435752D01*
X1445640Y195572D01*
Y170320D01*
X1418687Y105250D01*
X1407456Y94018D01*
X1384229Y78498D01*
X1357220Y67310D01*
X1340180Y63920D01*
X1324101Y62337D01*
X1298489D01*
X1283933Y65232D01*
X1271011D01*
X1190923Y81163D01*
X1174645Y87905D01*
X1120573Y124038D01*
X1083254Y161356D01*
X1060110Y170942D01*
X1043768D01*
X1029499Y185211D01*
X1026901Y191485D01*
X1026900D01*
X1024820Y196506D01*
Y226402D01*
X1021819Y229403D01*
X1019963Y230172D01*
X1016462D01*
X1012772Y226482D01*
X980682D01*
X956341Y202141D01*
X954679Y201452D01*
X948818D01*
X935209Y207089D01*
X903555D01*
X902350Y208294D01*
G01X1389256Y197668D02*
X1390416Y198828D01*
Y201985D01*
X1401383Y212952D01*
X1423848D01*
X1442680Y194120D01*
Y173188D01*
X1414343Y104776D01*
X1405186Y95617D01*
X1384993Y82126D01*
X1357354Y70678D01*
X1333781Y65989D01*
X1322895Y64917D01*
X1298896D01*
X1282128Y68252D01*
X1269057D01*
X1192449Y83490D01*
X1175218Y90629D01*
X1125597Y123784D01*
X1085381Y164000D01*
X1061572Y173862D01*
X1044978D01*
X1031658Y187182D01*
X1027400Y197463D01*
Y227502D01*
X1023334Y231568D01*
X1019994Y232952D01*
X983858D01*
X981422Y231943D01*
X976832Y227353D01*
X959735Y220272D01*
X934725D01*
X917505Y213140D01*
X908630D01*
X907470Y211980D01*
G01X1380602Y197668D02*
X1381762Y198828D01*
Y201593D01*
X1397311Y217142D01*
X1425598D01*
X1446720Y196020D01*
Y170105D01*
X1419603Y104638D01*
X1408145Y93178D01*
X1384741Y77541D01*
X1357535Y66271D01*
X1340339Y62850D01*
X1324155Y61257D01*
X1298382D01*
X1283826Y64152D01*
X1270904D01*
X1190608Y80124D01*
X1174133Y86948D01*
X1119884Y123198D01*
X1082642Y160440D01*
X1059895Y169862D01*
X1043320D01*
X1028583Y184599D01*
X1028500Y184798D01*
X1028501D01*
X1026179Y190405D01*
X1026178D01*
X1023740Y196291D01*
Y225954D01*
X1021207Y228487D01*
X1019748Y229092D01*
X1016910D01*
X1013220Y225402D01*
X981130D01*
X956953Y201225D01*
X954894Y200372D01*
X948603D01*
X934994Y206009D01*
X903465D01*
X902350Y204894D01*
G01X1392656Y197668D02*
X1391496Y198828D01*
Y201537D01*
X1393389Y203430D01*
X1394195D01*
X1395222Y204457D01*
Y205263D01*
X1396339Y206380D01*
X1397145D01*
X1398172Y207407D01*
Y208213D01*
X1401831Y211872D01*
X1403900D01*
X1404380Y211392D01*
X1406100D01*
X1406580Y211872D01*
X1423400D01*
X1430206Y205066D01*
Y204373D01*
X1431423Y203156D01*
X1432116D01*
X1433332Y201940D01*
Y201247D01*
X1434549Y200030D01*
X1435242D01*
X1436458Y198814D01*
Y198121D01*
X1437675Y196904D01*
X1438368D01*
X1441600Y193672D01*
Y190557D01*
X1441030Y189987D01*
Y188537D01*
X1441600Y187967D01*
Y173403D01*
X1440736Y171316D01*
X1440108Y171057D01*
X1439449Y169467D01*
X1439709Y168840D01*
X1439051Y167251D01*
X1439052D01*
X1438307Y166943D01*
X1437752Y165602D01*
X1438060Y164857D01*
X1437506Y163518D01*
X1436760Y163210D01*
X1436205Y161869D01*
X1436514Y161125D01*
X1424870Y133018D01*
X1424872Y133015D01*
X1424126Y132707D01*
X1423571Y131366D01*
X1423880Y130621D01*
X1423256Y129114D01*
X1423253Y129113D01*
X1422699Y127774D01*
X1421953Y127465D01*
X1421398Y126125D01*
X1421707Y125380D01*
X1413427Y105388D01*
X1404497Y96457D01*
X1384481Y83083D01*
X1357039Y71717D01*
X1333622Y67059D01*
X1322841Y65997D01*
X1299003D01*
X1282235Y69332D01*
X1269164D01*
X1192764Y84529D01*
X1175730Y91586D01*
X1126286Y124624D01*
X1085993Y164916D01*
X1061787Y174942D01*
X1045426D01*
X1032574Y187794D01*
X1028480Y197678D01*
Y227950D01*
X1023946Y232484D01*
X1020209Y234032D01*
X983643D01*
X980810Y232859D01*
X976220Y228269D01*
X959520Y221352D01*
X934510D01*
X917290Y214220D01*
X908630D01*
X907470Y215380D01*
G01X1398006Y197668D02*
X1399166Y198828D01*
Y202297D01*
X1405641Y208772D01*
X1422120D01*
X1437680Y193212D01*
Y177464D01*
X1435964Y173319D01*
X1435963D01*
X1422817Y141581D01*
X1408708Y127472D01*
X1404796Y125852D01*
X1401311D01*
X1397686Y124350D01*
X1393030Y119694D01*
X1389432Y111009D01*
X1370901Y83274D01*
X1368424Y80797D01*
X1350740Y73472D01*
X1328798Y71312D01*
X1287939D01*
X1282458Y72402D01*
X1266955D01*
X1193522Y87009D01*
X1176959Y93870D01*
X1128893Y125989D01*
X1087429Y167453D01*
X1075106Y172557D01*
X1075107D01*
X1062782Y177662D01*
X1046553D01*
X1034646Y189569D01*
X1031060Y198226D01*
Y229033D01*
X1025431Y234662D01*
X1020676Y236632D01*
X982045D01*
X977168Y234612D01*
X952947D01*
X947938Y233869D01*
X944508Y233187D01*
X939275Y231019D01*
X936846Y228590D01*
X916655Y220228D01*
X903510D01*
X902350Y219068D01*
G01X1406786Y197668D02*
X1407946Y198828D01*
Y201029D01*
X1409159Y202242D01*
X1422690D01*
X1432790Y192142D01*
Y182658D01*
X1429946Y175791D01*
Y175792D01*
X1427408Y169664D01*
X1427407D01*
X1424352Y162287D01*
X1411803Y149737D01*
X1400496Y143695D01*
X1366098Y136850D01*
X1361299Y132052D01*
X1340380Y100744D01*
X1315911Y76275D01*
X1312765Y74972D01*
X1288352D01*
X1281211Y76392D01*
X1265658D01*
X1194595Y90528D01*
X1179631Y96726D01*
X1132908Y127946D01*
X1090289Y170562D01*
X1077253Y175962D01*
Y175961D01*
X1064216Y181362D01*
X1048087D01*
X1038009Y191440D01*
X1034720Y199380D01*
Y230583D01*
X1027560Y237743D01*
X1021334Y240322D01*
X981047D01*
X976276Y238346D01*
X952502D01*
X947954Y237671D01*
X942068Y236500D01*
Y236499D01*
X936184Y235330D01*
X916825Y227314D01*
X908630D01*
X907470Y226154D01*
G01X1401406Y197668D02*
X1400246Y198828D01*
Y201849D01*
X1406089Y207692D01*
X1407809D01*
X1408289Y207212D01*
X1410009D01*
X1410489Y207692D01*
X1412209D01*
X1412689Y207212D01*
X1414409D01*
X1414889Y207692D01*
X1416609D01*
X1417089Y207212D01*
X1418809D01*
X1419289Y207692D01*
X1421672D01*
X1422926Y206438D01*
Y205745D01*
X1424143Y204528D01*
X1424836D01*
X1426052Y203312D01*
Y202619D01*
X1427269Y201402D01*
X1427962D01*
X1429178Y200186D01*
Y199493D01*
X1430395Y198276D01*
X1431088D01*
X1432304Y197060D01*
Y196367D01*
X1433521Y195150D01*
X1434214D01*
X1436600Y192764D01*
Y190627D01*
X1436030Y190057D01*
Y188607D01*
X1436600Y188037D01*
Y185787D01*
X1436030Y185217D01*
Y183767D01*
X1436600Y183197D01*
Y177679D01*
X1434965Y173731D01*
X1434220Y173423D01*
X1433665Y172082D01*
X1433974Y171337D01*
X1433408Y169971D01*
X1432662Y169662D01*
X1432107Y168322D01*
X1432415Y167577D01*
X1431610Y165632D01*
X1430865Y165324D01*
X1430310Y163983D01*
X1430618Y163238D01*
X1429964Y161658D01*
X1429218Y161350D01*
X1428664Y160009D01*
X1428972Y159265D01*
X1421901Y142193D01*
X1408096Y128388D01*
X1404581Y126932D01*
X1401096D01*
X1397089Y125281D01*
X1392114Y120306D01*
X1388476Y111524D01*
X1388473Y111519D01*
X1370061Y83963D01*
X1367812Y81713D01*
X1350474Y74532D01*
X1328744Y72392D01*
X1288046D01*
X1282565Y73482D01*
X1267062D01*
X1193837Y88048D01*
X1177471Y94827D01*
X1129582Y126829D01*
X1088041Y168369D01*
X1062997Y178742D01*
X1047001D01*
X1035562Y190181D01*
X1032140Y198441D01*
Y229481D01*
X1026043Y235578D01*
X1020891Y237712D01*
X981830D01*
X976953Y235692D01*
X952867D01*
X947753Y234934D01*
X944193Y234226D01*
X944094Y234185D01*
X944095D01*
X938663Y231935D01*
X936234Y229506D01*
X916440Y221308D01*
X903510D01*
X902350Y222468D01*
G01X1410186Y197668D02*
X1409026Y198828D01*
Y200581D01*
X1409607Y201162D01*
X1422242D01*
X1426460Y196944D01*
Y196138D01*
X1427486Y195112D01*
X1428292D01*
X1431710Y191694D01*
Y189477D01*
X1431140Y188907D01*
Y187457D01*
X1431710Y186887D01*
Y182873D01*
X1430494Y179937D01*
X1429749Y179629D01*
X1429194Y178288D01*
X1429502Y177543D01*
X1428948Y176204D01*
X1428202Y175895D01*
X1427647Y174555D01*
X1427955Y173810D01*
X1427401Y172471D01*
X1426656Y172163D01*
X1426101Y170822D01*
X1426409Y170077D01*
X1423436Y162899D01*
X1411152Y150615D01*
X1400128Y144723D01*
X1396287Y143960D01*
X1395617Y144407D01*
X1394194Y144125D01*
X1393746Y143453D01*
X1381418Y141002D01*
X1380748Y141450D01*
X1379324Y141167D01*
X1378877Y140495D01*
X1377455Y140213D01*
X1376785Y140661D01*
X1375361Y140378D01*
X1374914Y139706D01*
X1373492Y139424D01*
X1372822Y139872D01*
X1371398Y139589D01*
X1370951Y138917D01*
X1369529Y138635D01*
X1368859Y139083D01*
X1367435Y138800D01*
X1366988Y138128D01*
X1365566Y137846D01*
X1360460Y132741D01*
X1348032Y114141D01*
X1347240Y113984D01*
X1346434Y112777D01*
X1346592Y111987D01*
X1339540Y101433D01*
X1315299Y77191D01*
X1312550Y76052D01*
X1288459D01*
X1281318Y77472D01*
X1265765D01*
X1252142Y80182D01*
X1251694Y80853D01*
X1250271Y81136D01*
X1249600Y80688D01*
X1194910Y91567D01*
X1180143Y97683D01*
X1133597Y128786D01*
X1090901Y171478D01*
X1064431Y182442D01*
X1048535D01*
X1038925Y192052D01*
X1035800Y199595D01*
Y231031D01*
X1028172Y238659D01*
X1021549Y241402D01*
X980832D01*
X976061Y239426D01*
X952422D01*
X947769Y238736D01*
X935869Y236369D01*
X916610Y228394D01*
X908630D01*
X907470Y229554D01*
G01X1238780Y1682244D02*
Y1681002D01*
X1238199Y1680421D01*
X1236222D01*
X1234259Y1678458D01*
X1197202Y1617067D01*
Y1601652D01*
X1197932Y1594237D01*
Y1591254D01*
X1196772Y1590094D01*
G01X1200172D02*
X1199012Y1591254D01*
Y1594291D01*
X1198282Y1601706D01*
Y1616766D01*
X1212873Y1640937D01*
X1213629Y1641124D01*
X1214378Y1642366D01*
X1214191Y1643122D01*
X1215884Y1645926D01*
X1216640Y1646112D01*
X1217389Y1647355D01*
X1217202Y1648110D01*
X1218968Y1651035D01*
X1219723Y1651222D01*
X1220473Y1652464D01*
X1220286Y1653219D01*
X1221790Y1655711D01*
X1222546Y1655898D01*
X1223296Y1657140D01*
X1223109Y1657895D01*
X1225512Y1661876D01*
X1226267Y1662062D01*
X1227017Y1663305D01*
X1226830Y1664060D01*
X1235116Y1677787D01*
X1236670Y1679341D01*
X1237947D01*
X1238780Y1678508D01*
Y1677519D01*
G01X1212232Y1590094D02*
X1211072Y1591254D01*
Y1594291D01*
X1210342Y1601706D01*
Y1616666D01*
X1222591Y1637000D01*
X1223347Y1637188D01*
X1224095Y1638431D01*
X1223908Y1639186D01*
X1224656Y1640428D01*
X1225412Y1640615D01*
X1226160Y1641858D01*
X1225972Y1642613D01*
X1227161Y1644587D01*
X1227917Y1644774D01*
X1228665Y1646017D01*
X1228478Y1646772D01*
X1229226Y1648014D01*
X1229982Y1648201D01*
X1230730Y1649444D01*
X1230542Y1650199D01*
X1243964Y1672482D01*
Y1682698D01*
X1244544Y1683278D01*
X1245821D01*
X1246654Y1682445D01*
Y1681456D01*
G01Y1686180D02*
Y1684939D01*
X1246073Y1684358D01*
X1244096D01*
X1242884Y1683146D01*
Y1672787D01*
X1209262Y1616967D01*
Y1601652D01*
X1209992Y1594237D01*
Y1591254D01*
X1208832Y1590094D01*
G01X1254528Y1682244D02*
Y1681002D01*
X1253947Y1680421D01*
X1251970D01*
X1250758Y1679209D01*
Y1671316D01*
X1221322Y1616858D01*
Y1601652D01*
X1222052Y1594237D01*
Y1591254D01*
X1220892Y1590094D01*
G01X1262402Y1686180D02*
Y1684939D01*
X1261821Y1684358D01*
X1259844D01*
X1258632Y1683146D01*
Y1670852D01*
X1233382Y1616659D01*
Y1601652D01*
X1234112Y1594237D01*
Y1591254D01*
X1232952Y1590094D01*
G01X1224292D02*
X1223132Y1591254D01*
Y1594291D01*
X1222402Y1601706D01*
Y1616584D01*
X1233372Y1636879D01*
X1234118Y1637102D01*
X1234808Y1638378D01*
X1234585Y1639124D01*
X1235663Y1641119D01*
X1236409Y1641341D01*
X1237099Y1642618D01*
X1236877Y1643363D01*
X1238171Y1645757D01*
X1238917Y1645980D01*
X1239607Y1647256D01*
X1239384Y1648002D01*
X1240509Y1650084D01*
X1241256Y1650307D01*
X1241945Y1651583D01*
X1241723Y1652329D01*
X1242412Y1653604D01*
X1243158Y1653826D01*
X1243848Y1655103D01*
X1243626Y1655848D01*
X1251838Y1671042D01*
Y1678761D01*
X1252418Y1679341D01*
X1253695D01*
X1254528Y1678508D01*
Y1677519D01*
G01X1270276Y1682244D02*
Y1681002D01*
X1269695Y1680421D01*
X1267718D01*
X1266506Y1679209D01*
Y1671125D01*
X1253605Y1637574D01*
X1253604Y1637571D01*
X1245442Y1616344D01*
Y1601652D01*
X1246172Y1594237D01*
Y1591254D01*
X1245012Y1590094D01*
G01X1236352D02*
X1235192Y1591254D01*
Y1594291D01*
X1234462Y1601706D01*
Y1616419D01*
X1242571Y1633822D01*
X1243302Y1634088D01*
X1243915Y1635403D01*
X1243649Y1636134D01*
X1244261Y1637448D01*
X1244993Y1637714D01*
X1245605Y1639029D01*
X1245339Y1639760D01*
X1246002Y1641183D01*
X1246734Y1641450D01*
X1247346Y1642765D01*
X1247080Y1643496D01*
X1247692Y1644810D01*
X1248424Y1645076D01*
X1249036Y1646392D01*
X1248770Y1647122D01*
X1259712Y1670612D01*
Y1682698D01*
X1260292Y1683278D01*
X1261569D01*
X1262402Y1682445D01*
Y1681456D01*
G01X1248412Y1590094D02*
X1247252Y1591254D01*
Y1594291D01*
X1246522Y1601706D01*
Y1616143D01*
X1252068Y1630567D01*
X1252070Y1630573D01*
X1252692Y1630848D01*
X1253309Y1632455D01*
X1253033Y1633075D01*
X1253650Y1634680D01*
X1253649D01*
X1254271Y1634955D01*
X1254888Y1636562D01*
X1254612Y1637182D01*
X1254613Y1637185D01*
X1255229Y1638787D01*
Y1638788D01*
X1255851Y1639063D01*
X1256468Y1640670D01*
X1256192Y1641290D01*
X1256191Y1641291D01*
X1256192D01*
X1258386Y1646998D01*
Y1646999D01*
X1258387Y1647002D01*
X1259009Y1647277D01*
X1259626Y1648884D01*
X1259350Y1649504D01*
X1259351Y1649507D01*
X1259967Y1651109D01*
X1260588Y1651385D01*
X1261205Y1652991D01*
X1260930Y1653612D01*
X1261547Y1655217D01*
X1262168Y1655493D01*
X1262785Y1657099D01*
X1262510Y1657719D01*
X1267569Y1670879D01*
X1267583D01*
X1267586Y1670882D01*
Y1678761D01*
X1268166Y1679341D01*
X1269443D01*
X1270276Y1678508D01*
Y1677519D01*
G01X1278150Y1686180D02*
Y1684939D01*
X1277569Y1684358D01*
X1275592D01*
X1274380Y1683146D01*
Y1670526D01*
X1266422Y1644789D01*
X1266421Y1644786D01*
X1263989Y1636920D01*
X1263987Y1636914D01*
Y1636913D01*
X1257502Y1615941D01*
Y1601652D01*
X1258232Y1594237D01*
Y1591254D01*
X1257072Y1590094D01*
G01X1260472D02*
X1259312Y1591254D01*
Y1594291D01*
X1258582Y1601706D01*
Y1615777D01*
X1265019Y1636594D01*
X1265020Y1636599D01*
X1265022Y1636600D01*
X1265021Y1636601D01*
X1265739Y1638924D01*
X1266428Y1639287D01*
X1266856Y1640673D01*
X1266493Y1641361D01*
X1267453Y1644466D01*
X1267454Y1644469D01*
X1268142Y1644831D01*
X1268571Y1646217D01*
X1268208Y1646905D01*
X1268659Y1648364D01*
X1269348Y1648727D01*
X1269776Y1650113D01*
X1269413Y1650801D01*
X1269931Y1652477D01*
X1270620Y1652840D01*
X1271048Y1654226D01*
X1270685Y1654914D01*
X1275460Y1670362D01*
Y1682698D01*
X1276040Y1683278D01*
X1277317D01*
X1278150Y1682445D01*
Y1681456D01*
G01X1286024Y1682244D02*
Y1681002D01*
X1285514Y1680492D01*
X1283635D01*
X1282180Y1679037D01*
Y1669331D01*
X1273711Y1633063D01*
X1273709D01*
X1269562Y1615293D01*
Y1601652D01*
X1270292Y1594237D01*
Y1591254D01*
X1269132Y1590094D01*
G01X1293898Y1686180D02*
Y1684939D01*
X1293317Y1684358D01*
X1291340D01*
X1290128Y1683146D01*
Y1671142D01*
X1283537Y1626663D01*
X1283535Y1626661D01*
X1282463Y1619424D01*
X1281622Y1615194D01*
Y1601652D01*
X1282352Y1594237D01*
Y1591254D01*
X1281192Y1590094D01*
G01X1272532D02*
X1271372Y1591254D01*
Y1594291D01*
X1270642Y1601706D01*
Y1615168D01*
X1274761Y1632818D01*
X1274763Y1632819D01*
X1275424Y1633230D01*
X1275754Y1634643D01*
X1275344Y1635303D01*
X1275832Y1637393D01*
X1276493Y1637804D01*
X1276823Y1639217D01*
X1276412Y1639877D01*
X1277160Y1643081D01*
X1277821Y1643491D01*
X1278151Y1644904D01*
X1277740Y1645565D01*
X1278355Y1648203D01*
X1279017Y1648613D01*
X1279347Y1650026D01*
X1278936Y1650687D01*
X1279614Y1653594D01*
X1280276Y1654005D01*
X1280606Y1655418D01*
X1280195Y1656079D01*
X1283260Y1669206D01*
Y1678589D01*
X1284083Y1679412D01*
X1285120D01*
X1286024Y1678508D01*
Y1677519D01*
G01X1305709Y1682244D02*
Y1681002D01*
X1305128Y1680421D01*
X1303151D01*
X1301939Y1679209D01*
Y1670442D01*
X1294259Y1618251D01*
X1293682Y1615348D01*
Y1601652D01*
X1294412Y1594237D01*
Y1591254D01*
X1293252Y1590094D01*
G01X1284592D02*
X1283432Y1591254D01*
Y1594291D01*
X1282702Y1601706D01*
Y1615087D01*
X1283528Y1619239D01*
X1284604Y1626503D01*
X1284606D01*
X1285305Y1631233D01*
X1285931Y1631697D01*
X1286143Y1633132D01*
X1285680Y1633757D01*
X1286168Y1637053D01*
X1286794Y1637516D01*
X1287006Y1638952D01*
X1286543Y1639576D01*
X1286886Y1641896D01*
X1287512Y1642359D01*
X1287724Y1643795D01*
X1287261Y1644419D01*
X1287758Y1647778D01*
X1288384Y1648241D01*
X1288596Y1649677D01*
X1288133Y1650301D01*
X1288132Y1650302D01*
Y1650304D01*
X1291208Y1671062D01*
Y1682698D01*
X1291788Y1683278D01*
X1293065D01*
X1293898Y1682445D01*
Y1681456D01*
G01X1296652Y1590094D02*
X1295492Y1591254D01*
Y1594291D01*
X1294762Y1601706D01*
Y1615241D01*
X1295324Y1618067D01*
X1297098Y1630119D01*
X1297722Y1630582D01*
X1297933Y1632018D01*
X1297469Y1632642D01*
X1297680Y1634076D01*
X1298305Y1634540D01*
X1298516Y1635976D01*
X1298052Y1636600D01*
X1298394Y1638927D01*
X1299019Y1639391D01*
X1299230Y1640826D01*
X1298766Y1641450D01*
X1299047Y1643364D01*
X1299672Y1643828D01*
X1299883Y1645264D01*
X1299419Y1645888D01*
X1299797Y1648463D01*
X1300423Y1648928D01*
X1300634Y1650363D01*
X1300170Y1650987D01*
X1303019Y1670362D01*
Y1678761D01*
X1303599Y1679341D01*
X1304876D01*
X1305709Y1678508D01*
Y1677519D01*
G01X1417716Y837051D02*
Y823779D01*
X1421659Y801348D01*
X1444619Y768561D01*
X1444617Y768559D01*
X1464800Y754432D01*
X1479515Y733414D01*
X1486640Y693054D01*
X1473861Y620653D01*
X1317226Y360905D01*
X1308837Y330748D01*
Y324156D01*
X1307677Y322996D01*
G01X1418796Y837051D02*
Y823874D01*
X1422682Y801772D01*
X1445395Y769337D01*
X1445394Y769335D01*
X1465576Y755208D01*
X1480538Y733838D01*
X1487737Y693054D01*
X1474890Y620267D01*
X1318228Y360473D01*
X1309917Y330600D01*
Y324156D01*
X1311077Y322996D01*
G01X1313583Y1686180D02*
Y1684939D01*
X1313002Y1684358D01*
X1311025D01*
X1309813Y1683146D01*
Y1670909D01*
X1306334Y1618974D01*
X1305742Y1615996D01*
Y1601652D01*
X1306472Y1594237D01*
Y1591254D01*
X1305312Y1590094D01*
G01X1308712D02*
X1307552Y1591254D01*
Y1594291D01*
X1306822Y1601706D01*
Y1615889D01*
X1307407Y1618832D01*
X1308084Y1628941D01*
X1308670Y1629453D01*
X1308767Y1630901D01*
X1308255Y1631487D01*
X1308351Y1632933D01*
X1308938Y1633445D01*
X1309035Y1634893D01*
X1308523Y1635479D01*
X1308658Y1637501D01*
X1309244Y1638013D01*
X1309341Y1639461D01*
X1308829Y1640046D01*
X1309020Y1642900D01*
X1309606Y1643412D01*
X1309703Y1644860D01*
X1309191Y1645446D01*
X1310893Y1670872D01*
Y1682698D01*
X1311473Y1683278D01*
X1312750D01*
X1313583Y1682445D01*
Y1681456D01*
G01X1319618Y318073D02*
X1318458Y319233D01*
Y329716D01*
X1326820Y360372D01*
X1478205Y617241D01*
X1491558Y692899D01*
X1484240Y734358D01*
X1467197Y758699D01*
X1448117Y772059D01*
X1426270Y803258D01*
X1422586Y824207D01*
Y834897D01*
G01X1425092Y837051D02*
Y824427D01*
X1428642Y804240D01*
X1439292Y789031D01*
X1439293Y789030D01*
X1449916Y773859D01*
X1468341Y760956D01*
X1486858Y734510D01*
X1494152Y693184D01*
X1480229Y614285D01*
X1331459Y354735D01*
X1326240Y335136D01*
Y325062D01*
X1325080Y323902D01*
G01X1316218Y318073D02*
X1317378Y319233D01*
Y329861D01*
X1317870Y331664D01*
X1317498Y332315D01*
X1317871Y333686D01*
X1318523Y334058D01*
X1318522D01*
X1325816Y360796D01*
X1477175Y617621D01*
X1490461Y692899D01*
X1483217Y733934D01*
X1466421Y757923D01*
X1447341Y771283D01*
X1436308Y787039D01*
X1436307Y787040D01*
X1425247Y802834D01*
X1421506Y824112D01*
Y834897D01*
G01X1426172Y837051D02*
Y824522D01*
X1429665Y804664D01*
X1450692Y774635D01*
X1459747Y768294D01*
X1459748Y768293D01*
X1469117Y761732D01*
X1487881Y734934D01*
X1495249Y693184D01*
X1481261Y613911D01*
X1332467Y354320D01*
X1329894Y344659D01*
Y344657D01*
X1327320Y334994D01*
Y325062D01*
X1328480Y323902D01*
G01X1321457Y1682244D02*
Y1681002D01*
X1320876Y1680421D01*
X1318899D01*
X1317644Y1679166D01*
Y1675086D01*
X1318262Y1621799D01*
X1318070Y1617359D01*
X1317802Y1614631D01*
Y1601652D01*
X1318532Y1594237D01*
Y1591254D01*
X1317372Y1590094D01*
G01X1320772D02*
X1319612Y1591254D01*
Y1594291D01*
X1318882Y1601706D01*
Y1614578D01*
X1319148Y1617283D01*
X1319343Y1621782D01*
X1319313Y1624378D01*
X1319798Y1624873D01*
X1319778Y1626594D01*
X1319281Y1627078D01*
X1319262Y1628797D01*
X1319746Y1629293D01*
X1319726Y1631014D01*
X1319229Y1631498D01*
X1319210Y1633217D01*
X1319694Y1633713D01*
X1319674Y1635434D01*
X1319177Y1635918D01*
X1319179Y1635919D01*
X1319160Y1637638D01*
X1319644Y1638134D01*
X1319624Y1639855D01*
X1319127Y1640339D01*
X1319108Y1642058D01*
X1319592Y1642554D01*
X1319572Y1644275D01*
X1319075Y1644759D01*
X1319077Y1644760D01*
X1318683Y1678677D01*
X1319347Y1679341D01*
X1320624D01*
X1321457Y1678508D01*
Y1677519D01*
G01X1329331Y1686180D02*
Y1684939D01*
X1328750Y1684358D01*
X1326773D01*
X1325561Y1683146D01*
Y1670702D01*
X1329862Y1623296D01*
Y1601652D01*
X1330592Y1594237D01*
Y1591254D01*
X1329432Y1590094D01*
G01X1332832D02*
X1331672Y1591254D01*
Y1594291D01*
X1330942Y1601706D01*
Y1623345D01*
X1330731Y1625680D01*
X1331229Y1626277D01*
X1331098Y1627722D01*
X1330499Y1628220D01*
X1330080Y1632846D01*
X1330578Y1633443D01*
X1330447Y1634888D01*
X1329848Y1635386D01*
X1329718Y1636830D01*
X1330216Y1637427D01*
X1330085Y1638872D01*
X1329486Y1639370D01*
X1329280Y1641648D01*
X1329778Y1642245D01*
X1329647Y1643690D01*
X1329049Y1644188D01*
X1329052D01*
X1326641Y1670751D01*
Y1682698D01*
X1327221Y1683278D01*
X1328498D01*
X1329331Y1682445D01*
Y1681456D01*
G01X1448481Y831815D02*
Y823883D01*
X1449976Y815390D01*
X1471464Y784704D01*
X1489326Y772197D01*
X1495437Y766086D01*
X1511602Y743001D01*
X1519228Y699748D01*
X1499333Y586937D01*
X1372692Y348453D01*
X1350107Y296742D01*
X1345844Y285425D01*
Y281419D01*
X1344684Y280259D01*
G01X1341431Y322693D02*
X1340271Y323853D01*
Y332283D01*
X1345903Y353876D01*
X1489366Y610167D01*
X1503339Y689371D01*
X1499149Y713116D01*
X1494952Y736908D01*
X1474299Y766406D01*
X1459962Y776444D01*
X1448249Y793171D01*
X1436537Y809898D01*
X1434800Y819765D01*
Y837051D01*
G01X1338031Y322693D02*
X1339191Y323853D01*
Y332422D01*
X1340035Y335659D01*
X1339656Y336305D01*
X1340014Y337680D01*
X1340662Y338059D01*
X1340661D01*
X1344893Y354283D01*
X1488334Y610535D01*
X1502242Y689371D01*
X1493929Y736484D01*
X1473523Y765630D01*
X1459186Y775668D01*
X1435514Y809474D01*
X1433720Y819670D01*
Y837051D01*
G01X1437254Y830642D02*
Y820095D01*
X1438886Y810822D01*
X1461685Y778265D01*
X1476021Y768227D01*
X1500730Y732937D01*
X1507172Y696414D01*
X1506683Y694203D01*
X1491601Y608692D01*
X1348443Y347805D01*
X1346584Y340553D01*
Y335532D01*
X1346054Y335002D01*
Y333582D01*
X1346584Y333052D01*
Y330141D01*
X1345424Y328981D01*
G01X1335145Y332616D02*
X1333985Y333776D01*
Y337785D01*
X1337399Y350744D01*
X1485290Y611986D01*
X1499367Y691770D01*
X1491625Y735646D01*
X1471897Y763820D01*
X1455453Y775335D01*
X1432973Y807440D01*
X1430472Y821652D01*
Y833045D01*
G01X1331745Y332616D02*
X1332905Y333776D01*
Y337925D01*
X1333266Y339298D01*
X1332889Y339945D01*
X1333250Y341319D01*
X1333899Y341697D01*
X1334260Y343070D01*
X1333883Y343717D01*
X1334244Y345091D01*
X1334893Y345469D01*
X1334892D01*
X1336390Y351154D01*
X1484258Y612357D01*
X1498270Y691770D01*
X1490602Y735222D01*
X1471121Y763044D01*
X1463055Y768693D01*
X1463054D01*
X1454677Y774559D01*
X1443327Y790768D01*
X1431950Y807016D01*
X1429392Y821557D01*
Y833045D01*
G01X1337205Y1682244D02*
Y1681002D01*
X1336624Y1680421D01*
X1334647D01*
X1333435Y1679209D01*
Y1670872D01*
X1341922Y1620694D01*
Y1601652D01*
X1342652Y1594237D01*
Y1591254D01*
X1341492Y1590094D01*
G01X1344892D02*
X1343732Y1591254D01*
Y1594291D01*
X1343002Y1601706D01*
Y1620785D01*
X1341188Y1631510D01*
X1341190Y1631512D01*
X1341640Y1632146D01*
X1341399Y1633576D01*
X1340764Y1634027D01*
X1340491Y1635642D01*
X1340941Y1636276D01*
X1340699Y1637707D01*
X1340064Y1638158D01*
X1339697Y1640333D01*
X1340147Y1640967D01*
X1339906Y1642397D01*
X1339271Y1642848D01*
X1338920Y1644923D01*
X1339370Y1645557D01*
X1339129Y1646988D01*
X1338494Y1647438D01*
X1338495D01*
X1338494Y1647439D01*
X1337720Y1652014D01*
X1338171Y1652648D01*
X1337929Y1654079D01*
X1337295Y1654528D01*
X1334515Y1670963D01*
Y1678761D01*
X1335095Y1679341D01*
X1336372D01*
X1337205Y1678508D01*
Y1677519D01*
G01X1345079Y1686180D02*
Y1684939D01*
X1344498Y1684358D01*
X1342521D01*
X1341309Y1683146D01*
Y1670532D01*
X1353982Y1619734D01*
Y1601652D01*
X1354712Y1594237D01*
Y1591254D01*
X1353552Y1590094D01*
G01X1356952D02*
X1355792Y1591254D01*
Y1594291D01*
X1355062Y1601706D01*
Y1619867D01*
X1353919Y1624452D01*
X1354319Y1625119D01*
X1353968Y1626527D01*
X1353301Y1626927D01*
X1352836Y1628791D01*
X1353236Y1629458D01*
X1352885Y1630866D01*
X1352218Y1631266D01*
X1351284Y1635013D01*
X1351684Y1635680D01*
X1351333Y1637088D01*
X1350666Y1637487D01*
X1349575Y1641863D01*
X1349975Y1642530D01*
X1349624Y1643938D01*
X1348957Y1644339D01*
X1342389Y1670665D01*
Y1682698D01*
X1342969Y1683278D01*
X1344246D01*
X1345079Y1682445D01*
Y1681456D01*
G01X1449561Y831815D02*
Y823978D01*
X1450999Y815814D01*
X1472240Y785480D01*
X1490024Y773028D01*
X1496268Y766784D01*
X1512625Y743425D01*
X1520325Y699748D01*
X1500367Y586581D01*
X1373666Y347982D01*
X1351112Y296345D01*
X1350506Y294736D01*
X1350786Y294118D01*
X1350180Y292507D01*
X1349561Y292227D01*
X1348955Y290618D01*
X1349235Y290000D01*
X1348629Y288389D01*
X1348009Y288109D01*
X1346929Y285240D01*
X1346926D01*
X1346924Y285242D01*
Y281419D01*
X1348084Y280259D01*
G01X1453133Y833445D02*
Y824292D01*
X1454492Y816583D01*
X1474481Y788037D01*
X1492182Y775643D01*
X1499141Y768684D01*
X1516758Y743524D01*
X1524214Y701227D01*
X1503878Y585903D01*
X1367770Y320780D01*
X1357464Y289850D01*
Y285804D01*
X1358624Y284644D01*
G01X1452053Y833445D02*
Y824197D01*
X1453469Y816159D01*
X1473705Y787261D01*
X1491485Y774812D01*
X1498310Y767986D01*
X1515735Y743100D01*
X1523117Y701227D01*
X1502842Y586251D01*
X1366771Y321200D01*
X1359325Y298852D01*
X1358717Y298548D01*
X1358174Y296915D01*
X1358477Y296308D01*
X1357934Y294677D01*
X1357326Y294373D01*
X1356782Y292741D01*
X1357086Y292134D01*
X1356384Y290026D01*
Y285804D01*
X1355224Y284644D01*
G01X1438334Y830642D02*
Y820190D01*
X1439909Y811246D01*
X1462461Y779041D01*
X1469472Y774132D01*
X1476797Y769003D01*
X1501753Y733361D01*
X1508273Y696390D01*
X1507743Y693992D01*
X1492634Y608329D01*
X1349456Y347405D01*
X1347664Y340416D01*
Y330141D01*
X1348824Y328981D01*
G01X1442242Y833035D02*
Y819306D01*
X1443320Y813193D01*
X1465902Y780942D01*
X1479478Y771436D01*
X1504878Y735160D01*
X1511925Y695205D01*
X1496251Y606325D01*
X1355015Y344750D01*
X1354040Y340897D01*
Y339003D01*
X1355200Y337843D01*
G01X1444700Y832485D02*
Y831728D01*
X1444699Y831727D01*
Y819601D01*
X1445663Y814131D01*
X1467793Y782527D01*
X1480961Y773307D01*
X1507160Y735891D01*
X1514377Y694962D01*
X1498279Y603669D01*
X1497617Y602413D01*
X1496900Y602192D01*
X1496238Y600935D01*
X1496459Y600219D01*
X1495797Y598963D01*
X1495080Y598742D01*
X1494418Y597485D01*
X1494639Y596769D01*
X1361273Y343886D01*
X1359531Y336851D01*
Y333435D01*
X1358371Y332275D01*
G01X1441162Y833035D02*
Y819211D01*
X1442297Y812769D01*
X1465126Y780166D01*
X1478702Y770660D01*
X1503855Y734736D01*
X1510828Y695205D01*
X1495217Y606685D01*
X1354000Y345145D01*
X1352960Y341032D01*
Y339003D01*
X1351800Y337843D01*
G01X1445780Y832485D02*
Y831728D01*
X1445779Y831727D01*
Y819697D01*
X1446686Y814555D01*
X1468569Y783303D01*
X1481737Y774083D01*
X1508183Y736315D01*
X1515474Y694962D01*
X1499314Y603315D01*
X1362290Y343499D01*
X1360611Y336719D01*
Y333435D01*
X1361771Y332275D01*
G01X1352953Y1682244D02*
Y1681002D01*
X1352263Y1680312D01*
X1350499D01*
X1349183Y1678996D01*
Y1668877D01*
X1366042Y1617407D01*
Y1601652D01*
X1366772Y1594237D01*
Y1591254D01*
X1365612Y1590094D01*
G01X1369012D02*
X1367852Y1591254D01*
Y1594291D01*
X1367122Y1601706D01*
Y1617580D01*
X1362704Y1631071D01*
X1363068Y1631791D01*
X1362617Y1633170D01*
X1361897Y1633534D01*
X1360765Y1636991D01*
X1361130Y1637710D01*
X1360678Y1639089D01*
X1359958Y1639453D01*
X1356582Y1649763D01*
X1356946Y1650482D01*
X1356495Y1651861D01*
X1355775Y1652226D01*
X1355033Y1654492D01*
X1355397Y1655211D01*
X1354946Y1656590D01*
X1354226Y1656954D01*
X1353485Y1659216D01*
X1353849Y1659935D01*
X1353397Y1661314D01*
X1352677Y1661678D01*
X1352679D01*
X1352678Y1661679D01*
X1350263Y1669050D01*
Y1678548D01*
X1350947Y1679232D01*
X1352229D01*
X1352953Y1678508D01*
Y1677519D01*
G01X1360827Y1686180D02*
Y1684939D01*
X1360246Y1684358D01*
X1358269D01*
X1357057Y1683146D01*
Y1669796D01*
X1378102Y1618466D01*
Y1601652D01*
X1378832Y1594237D01*
Y1591254D01*
X1377672Y1590094D01*
G01X1381072D02*
X1379912Y1591254D01*
Y1594291D01*
X1379182Y1601706D01*
Y1618679D01*
X1370707Y1639350D01*
X1370708Y1639351D01*
X1371008Y1640068D01*
X1370458Y1641411D01*
X1369740Y1641711D01*
X1369032Y1643439D01*
X1369332Y1644156D01*
X1368782Y1645499D01*
X1368064Y1645799D01*
X1367198Y1647911D01*
X1367498Y1648629D01*
X1366948Y1649971D01*
X1366230Y1650272D01*
X1365574Y1651872D01*
X1365874Y1652589D01*
X1365324Y1653932D01*
X1364605Y1654232D01*
X1364607D01*
X1364606Y1654233D01*
X1358137Y1670009D01*
Y1682698D01*
X1358717Y1683278D01*
X1359994D01*
X1360827Y1682445D01*
Y1681456D01*
G01X1459496Y833765D02*
Y824849D01*
X1460565Y818782D01*
X1479316Y792003D01*
X1494530Y781350D01*
X1503143Y772737D01*
X1522965Y744427D01*
X1530493Y701721D01*
X1509382Y582011D01*
X1379127Y316943D01*
X1373457Y298780D01*
Y283484D01*
X1370904Y277322D01*
X1364407Y270825D01*
Y256705D01*
X1374330Y246782D01*
X1379550D01*
X1380638Y245694D01*
G01X1460576Y833765D02*
Y824944D01*
X1461588Y819206D01*
X1480092Y792779D01*
X1495228Y782181D01*
X1503974Y773435D01*
X1523988Y744851D01*
X1531590Y701721D01*
X1510419Y581672D01*
X1380134Y316541D01*
X1378473Y311218D01*
X1378788Y310616D01*
X1378275Y308974D01*
X1377673Y308658D01*
X1377161Y307017D01*
X1377476Y306415D01*
X1376963Y304772D01*
X1376361Y304457D01*
X1375849Y302816D01*
X1376164Y302214D01*
X1375651Y300571D01*
X1375049Y300256D01*
X1374537Y298615D01*
Y283269D01*
X1371820Y276710D01*
X1365487Y270377D01*
Y257153D01*
X1374778Y247862D01*
X1379406D01*
X1380638Y249094D01*
G01X1470791Y831695D02*
Y830372D01*
X1470790Y830373D01*
Y825772D01*
X1471494Y821759D01*
X1487282Y799210D01*
X1514016Y780490D01*
X1533157Y753154D01*
X1541715Y704631D01*
X1529849Y637340D01*
Y637339D01*
X1517984Y570049D01*
X1392163Y314817D01*
X1384595Y282357D01*
X1380648Y272825D01*
X1374612Y266789D01*
Y262688D01*
X1375904Y261396D01*
X1379362D01*
X1380522Y260236D01*
G01X1466889Y835384D02*
Y832059D01*
X1466888Y832058D01*
Y825498D01*
X1467659Y821120D01*
X1484737Y796731D01*
X1498716Y786945D01*
X1511939Y773722D01*
X1522580Y758524D01*
X1526977Y755445D01*
X1530107Y750976D01*
X1538265Y704716D01*
X1515389Y574971D01*
X1388015Y314280D01*
X1381077Y284284D01*
X1376647Y273584D01*
X1371280Y268217D01*
Y260175D01*
X1375830Y255625D01*
X1382281D01*
X1383880Y254963D01*
X1387594D01*
X1388754Y253803D01*
G01X1464312Y832565D02*
Y825272D01*
X1465221Y820109D01*
X1482888Y794880D01*
X1497939Y784343D01*
X1509339Y772943D01*
X1520730Y756674D01*
X1526056Y752945D01*
X1526954Y751664D01*
Y751663D01*
X1527880Y750341D01*
X1535788Y705503D01*
X1513586Y579589D01*
X1388095Y322658D01*
X1378373Y290990D01*
Y283766D01*
X1374724Y274956D01*
X1369019Y269251D01*
Y259102D01*
X1374749Y253372D01*
X1381840D01*
X1390233Y244979D01*
Y240998D01*
X1389046Y239811D01*
X1387790D01*
X1386630Y238651D01*
G01X1471871Y831695D02*
Y830243D01*
X1471870Y830242D01*
Y825867D01*
X1472517Y822183D01*
X1488058Y799986D01*
X1514792Y781266D01*
X1534180Y753578D01*
X1542812Y704631D01*
X1519021Y569710D01*
X1393187Y314451D01*
X1386627Y286311D01*
X1386985Y285734D01*
X1386594Y284058D01*
X1386017Y283700D01*
X1385627Y282025D01*
X1384878Y280215D01*
X1385138Y279588D01*
X1384480Y277997D01*
X1383852Y277738D01*
X1383194Y276149D01*
X1383454Y275521D01*
X1382796Y273931D01*
X1382168Y273671D01*
X1381564Y272213D01*
X1379595Y270244D01*
Y269565D01*
X1378377Y268347D01*
X1377698D01*
X1375692Y266341D01*
Y263136D01*
X1376352Y262476D01*
X1379362D01*
X1380522Y263636D01*
G01X1467969Y835384D02*
Y831611D01*
X1467968Y831610D01*
Y825593D01*
X1468682Y821544D01*
X1485513Y797507D01*
X1499413Y787776D01*
X1512770Y774419D01*
X1523356Y759300D01*
X1527753Y756221D01*
X1530992Y751596D01*
X1530993D01*
X1531130Y751400D01*
X1539362Y704716D01*
X1516427Y574633D01*
X1389040Y313916D01*
X1382110Y283953D01*
X1382109D01*
X1380930Y281105D01*
X1381190Y280478D01*
X1380532Y278888D01*
X1379904Y278628D01*
X1379247Y277039D01*
X1379507Y276412D01*
X1378849Y274822D01*
X1378221Y274562D01*
X1377563Y272972D01*
X1372360Y267769D01*
Y260623D01*
X1376278Y256705D01*
X1382496D01*
X1384095Y256043D01*
X1387594D01*
X1388754Y257203D01*
G01X1463232Y832565D02*
Y825177D01*
X1464198Y819685D01*
X1482112Y794104D01*
X1497242Y783512D01*
X1508508Y772246D01*
X1519954Y755898D01*
X1525280Y752169D01*
X1526857Y749917D01*
X1534691Y705503D01*
X1512548Y579927D01*
X1387087Y323056D01*
X1385533Y317991D01*
X1384932Y317673D01*
X1384427Y316028D01*
X1384745Y315428D01*
X1384241Y313784D01*
X1383640Y313466D01*
X1383135Y311821D01*
X1383453Y311221D01*
Y311219D01*
X1380326Y301031D01*
X1379725Y300713D01*
X1379220Y299067D01*
X1379538Y298468D01*
X1379034Y296824D01*
X1378433Y296506D01*
X1377929Y294861D01*
X1378247Y294261D01*
X1377293Y291153D01*
Y283981D01*
X1373808Y275568D01*
X1367939Y269699D01*
Y258654D01*
X1374301Y252292D01*
X1381392D01*
X1383637Y250047D01*
Y249298D01*
X1384642Y248293D01*
X1385391D01*
X1386395Y247289D01*
Y246540D01*
X1387400Y245535D01*
X1388149D01*
X1389153Y244531D01*
Y241446D01*
X1388598Y240891D01*
X1387790D01*
X1386630Y242051D01*
G01X1456981Y833375D02*
Y832363D01*
X1456982Y832362D01*
Y824629D01*
X1458185Y817795D01*
X1477510Y790198D01*
X1493561Y778960D01*
X1501709Y770812D01*
X1520488Y743993D01*
X1527940Y701721D01*
X1507041Y583227D01*
X1373917Y315105D01*
X1367364Y294706D01*
Y283904D01*
X1368524Y282744D01*
G01X1455901Y833375D02*
Y831915D01*
X1455902Y831914D01*
Y824534D01*
X1457162Y817371D01*
X1476734Y789422D01*
X1492864Y778129D01*
X1500878Y770114D01*
X1519465Y743569D01*
X1526843Y701721D01*
X1506004Y583568D01*
X1372913Y315513D01*
X1366284Y294876D01*
Y283904D01*
X1365124Y282744D01*
G01X1475395Y833695D02*
Y826176D01*
X1475855Y823566D01*
X1477812Y820771D01*
X1483928Y812035D01*
X1490590Y802518D01*
X1502712Y794030D01*
X1517324Y783798D01*
X1537517Y754960D01*
X1546392Y704631D01*
X1522518Y569227D01*
X1397057Y313191D01*
X1389914Y282389D01*
Y271042D01*
X1388702Y269830D01*
X1387433D01*
X1386273Y268670D01*
G01X1474315Y833695D02*
Y826081D01*
X1474832Y823142D01*
X1489814Y801742D01*
X1516548Y783022D01*
X1536494Y754536D01*
X1545295Y704631D01*
X1521480Y569565D01*
X1396032Y313556D01*
X1393341Y301951D01*
X1392764Y301592D01*
X1392376Y299915D01*
X1392735Y299339D01*
X1392347Y297664D01*
X1391770Y297305D01*
X1391382Y295628D01*
X1391741Y295052D01*
X1391353Y293377D01*
X1390776Y293018D01*
X1390388Y291341D01*
X1390747Y290765D01*
X1390359Y289090D01*
X1389782Y288731D01*
X1389394Y287054D01*
X1389753Y286478D01*
X1388834Y282513D01*
Y280732D01*
X1388354Y280252D01*
Y278532D01*
X1388834Y278052D01*
Y271490D01*
X1388254Y270910D01*
X1387433D01*
X1386273Y272070D01*
G01X1502953Y1696417D02*
Y1695176D01*
X1502372Y1694595D01*
X1500395D01*
X1498368Y1692568D01*
X1468755Y1625344D01*
Y1615452D01*
X1467595Y1614292D01*
G01X1470995D02*
X1469835Y1615452D01*
Y1625116D01*
X1471165Y1628135D01*
X1471917Y1628427D01*
X1472502Y1629755D01*
X1472210Y1630506D01*
X1472794Y1631832D01*
X1473546Y1632124D01*
X1474131Y1633452D01*
X1473839Y1634204D01*
X1474423Y1635530D01*
X1475175Y1635822D01*
X1475760Y1637150D01*
X1475468Y1637902D01*
X1476052Y1639228D01*
X1476804Y1639520D01*
X1477389Y1640848D01*
X1477097Y1641600D01*
X1499275Y1691947D01*
X1500843Y1693515D01*
X1502120D01*
X1502953Y1692682D01*
Y1691692D01*
G01X1518701Y1696417D02*
Y1695176D01*
X1518157Y1694632D01*
X1516180D01*
X1514931Y1693383D01*
Y1671352D01*
X1492875Y1619138D01*
Y1615452D01*
X1491715Y1614292D01*
G01X1510827Y1700354D02*
Y1699113D01*
X1510246Y1698532D01*
X1508089D01*
X1507057Y1697500D01*
Y1672306D01*
X1480815Y1619081D01*
Y1615452D01*
X1479655Y1614292D01*
G01X1483055D02*
X1481895Y1615452D01*
Y1618829D01*
X1484334Y1623774D01*
X1485098Y1624033D01*
X1485739Y1625335D01*
X1485480Y1626098D01*
X1486121Y1627398D01*
X1486885Y1627657D01*
X1487526Y1628959D01*
X1487267Y1629722D01*
X1508137Y1672054D01*
Y1697052D01*
X1508537Y1697452D01*
X1509994D01*
X1510827Y1696619D01*
Y1695629D01*
G01X1526575Y1700354D02*
Y1699113D01*
X1525964Y1698502D01*
X1524059D01*
X1522805Y1697248D01*
Y1672350D01*
X1504935Y1619575D01*
Y1615452D01*
X1503775Y1614292D01*
G01X1507175D02*
X1506015Y1615452D01*
Y1619396D01*
X1507934Y1625064D01*
X1508556Y1625371D01*
X1509108Y1627001D01*
X1508801Y1627622D01*
X1509352Y1629252D01*
X1509974Y1629558D01*
X1510525Y1631189D01*
X1510218Y1631810D01*
X1510219Y1631809D01*
X1510770Y1633438D01*
X1511392Y1633745D01*
X1511944Y1635375D01*
X1511637Y1635996D01*
X1511636Y1635997D01*
X1523828Y1672003D01*
X1523885Y1672060D01*
Y1696800D01*
X1524507Y1697422D01*
X1525772D01*
X1526575Y1696619D01*
Y1695629D01*
G01X1495115Y1614292D02*
X1493955Y1615452D01*
Y1618919D01*
X1495507Y1622592D01*
X1496254Y1622895D01*
X1496818Y1624232D01*
X1496515Y1624978D01*
X1497079Y1626313D01*
X1497827Y1626617D01*
X1498391Y1627953D01*
X1498088Y1628701D01*
X1498757Y1630285D01*
X1499400Y1630546D01*
X1500069Y1632131D01*
X1499808Y1632773D01*
X1500477Y1634357D01*
X1501120Y1634618D01*
X1501789Y1636203D01*
X1501528Y1636845D01*
X1516011Y1671133D01*
Y1692935D01*
X1516628Y1693552D01*
X1517831D01*
X1518701Y1692682D01*
Y1691692D01*
G01X1534449Y1696417D02*
Y1695176D01*
X1533868Y1694595D01*
X1531891D01*
X1530682Y1693386D01*
Y1672466D01*
X1516995Y1621175D01*
Y1615452D01*
X1515835Y1614292D01*
G01X1519235D02*
X1518075Y1615452D01*
Y1621033D01*
X1519317Y1625686D01*
X1520015Y1626089D01*
X1520389Y1627491D01*
X1519985Y1628189D01*
X1520358Y1629589D01*
X1521057Y1629993D01*
X1521431Y1631395D01*
X1521027Y1632093D01*
X1521400Y1633493D01*
X1522099Y1633897D01*
X1522473Y1635299D01*
X1522069Y1635997D01*
X1522442Y1637397D01*
X1523141Y1637801D01*
X1523515Y1639203D01*
X1523111Y1639901D01*
X1531762Y1672324D01*
Y1692938D01*
X1532339Y1693515D01*
X1533616D01*
X1534449Y1692682D01*
Y1691692D01*
G01X1542323Y1700354D02*
Y1699113D01*
X1541742Y1698532D01*
X1539689D01*
X1538553Y1697396D01*
Y1671588D01*
X1529293Y1622030D01*
X1529292Y1622028D01*
X1529055Y1620757D01*
Y1615452D01*
X1527895Y1614292D01*
G01X1550197Y1696417D02*
Y1695176D01*
X1549653Y1694632D01*
X1547676D01*
X1546427Y1693383D01*
Y1671832D01*
X1541115Y1623432D01*
Y1615452D01*
X1539955Y1614292D01*
G01X1531295D02*
X1530135Y1615452D01*
Y1620657D01*
X1530354Y1621830D01*
X1531020Y1622286D01*
X1531286Y1623712D01*
X1530831Y1624377D01*
X1531097Y1625802D01*
X1531763Y1626257D01*
X1532029Y1627684D01*
X1531573Y1628349D01*
X1539633Y1671487D01*
Y1696948D01*
X1540137Y1697452D01*
X1541490D01*
X1542323Y1696619D01*
Y1695629D01*
G01X1558071Y1700354D02*
Y1699113D01*
X1557460Y1698502D01*
X1555659D01*
X1554266Y1697109D01*
Y1671810D01*
X1553140Y1617612D01*
Y1615417D01*
X1552015Y1614292D01*
G01X1555415D02*
X1554220Y1615487D01*
Y1617600D01*
X1554312Y1622064D01*
X1554813Y1622543D01*
X1554849Y1624264D01*
X1554369Y1624764D01*
X1554404Y1626483D01*
X1554905Y1626963D01*
X1554941Y1628683D01*
X1554461Y1629184D01*
X1554496Y1630903D01*
X1554997Y1631383D01*
X1555033Y1633103D01*
X1554553Y1633604D01*
Y1633618D01*
X1555346Y1671788D01*
Y1696661D01*
X1556107Y1697422D01*
X1557268D01*
X1558071Y1696619D01*
Y1695629D01*
G01X1543355Y1614292D02*
X1542195Y1615452D01*
Y1623372D01*
X1542619Y1627228D01*
X1543248Y1627732D01*
X1543407Y1629175D01*
X1542902Y1629803D01*
X1543060Y1631244D01*
X1543689Y1631748D01*
X1543848Y1633191D01*
X1543343Y1633819D01*
X1543530Y1635528D01*
X1544072Y1635962D01*
X1544259Y1637673D01*
X1543826Y1638213D01*
X1544013Y1639922D01*
X1544555Y1640356D01*
X1544742Y1642067D01*
X1544308Y1642607D01*
X1547507Y1671772D01*
Y1692935D01*
X1548124Y1693552D01*
X1549327D01*
X1550197Y1692682D01*
Y1691692D01*
G01X1569882Y1696417D02*
Y1695176D01*
X1569301Y1694595D01*
X1567324D01*
X1565975Y1693246D01*
Y1670121D01*
X1565200Y1617470D01*
Y1615417D01*
X1564075Y1614292D01*
G01X1567475D02*
X1566280Y1615487D01*
Y1617462D01*
X1566356Y1622612D01*
X1566853Y1623093D01*
X1566879Y1624814D01*
X1566396Y1625311D01*
X1566421Y1627030D01*
X1566919Y1627513D01*
X1566944Y1629234D01*
X1566462Y1629731D01*
X1566487Y1631450D01*
X1566985Y1631933D01*
X1567010Y1633654D01*
X1566527Y1634151D01*
X1566552Y1635870D01*
X1567050Y1636353D01*
X1567075Y1638074D01*
X1566592Y1638571D01*
X1566591Y1638572D01*
X1567055Y1670106D01*
Y1692798D01*
X1567772Y1693515D01*
X1569049D01*
X1569882Y1692682D01*
Y1691692D01*
G01X1577756Y1700354D02*
Y1699113D01*
X1577175Y1698532D01*
X1575290D01*
X1573986Y1697228D01*
Y1671193D01*
X1577260Y1617403D01*
Y1615417D01*
X1576135Y1614292D01*
G01X1585630Y1696417D02*
Y1695176D01*
X1585096Y1694642D01*
X1583119D01*
X1581860Y1693383D01*
Y1672298D01*
X1589320Y1618053D01*
Y1615417D01*
X1588195Y1614292D01*
G01X1591595D02*
X1590400Y1615487D01*
Y1618127D01*
X1589748Y1622877D01*
X1590166Y1623429D01*
X1589932Y1625134D01*
X1589379Y1625553D01*
X1589107Y1627533D01*
X1589526Y1628085D01*
X1589292Y1629790D01*
X1588739Y1630209D01*
X1588505Y1631912D01*
X1588503D01*
X1588922Y1632465D01*
X1588688Y1634170D01*
X1588134Y1634588D01*
X1588137D01*
X1587903Y1636291D01*
X1588322Y1636844D01*
X1588087Y1638549D01*
X1587534Y1638967D01*
X1582940Y1672372D01*
Y1692935D01*
X1583567Y1693562D01*
X1584750D01*
X1585630Y1692682D01*
Y1691692D01*
G01X1579535Y1614292D02*
X1578340Y1615487D01*
Y1617436D01*
X1578045Y1622284D01*
X1578505Y1622803D01*
X1578400Y1624521D01*
X1577880Y1624980D01*
X1577776Y1626696D01*
X1578235Y1627215D01*
X1578131Y1628933D01*
X1577611Y1629392D01*
X1577613Y1629393D01*
X1575066Y1671226D01*
Y1696780D01*
X1575738Y1697452D01*
X1576923D01*
X1577756Y1696619D01*
Y1695629D01*
G01X1593504Y1700354D02*
Y1699113D01*
X1592853Y1698462D01*
X1590876D01*
X1589734Y1697320D01*
Y1671472D01*
X1601380Y1617374D01*
Y1615417D01*
X1600255Y1614292D01*
G01X1603655D02*
X1602460Y1615487D01*
Y1617489D01*
X1601088Y1623866D01*
X1601464Y1624448D01*
X1601102Y1626130D01*
X1600519Y1626506D01*
X1600086Y1628521D01*
X1600461Y1629103D01*
X1600099Y1630785D01*
X1599517Y1631160D01*
X1599080Y1633191D01*
X1599456Y1633773D01*
X1599094Y1635456D01*
X1598512Y1635830D01*
X1590814Y1671587D01*
Y1696872D01*
X1591324Y1697382D01*
X1592741D01*
X1593504Y1696619D01*
Y1695629D01*
G01X1601378Y1696417D02*
Y1695176D01*
X1600797Y1694595D01*
X1598820D01*
X1597608Y1693383D01*
Y1671844D01*
X1613440Y1617372D01*
Y1615417D01*
X1612315Y1614292D01*
G01X1615715D02*
X1614520Y1615487D01*
Y1617526D01*
X1611991Y1626228D01*
X1612325Y1626835D01*
X1611845Y1628488D01*
X1611237Y1628822D01*
X1610757Y1630473D01*
X1611091Y1631080D01*
X1610611Y1632733D01*
X1610004Y1633066D01*
X1609524Y1634718D01*
X1609858Y1635325D01*
X1609378Y1636978D01*
X1608770Y1637312D01*
X1608290Y1638963D01*
X1608624Y1639570D01*
X1608144Y1641223D01*
X1607537Y1641556D01*
X1598688Y1671998D01*
Y1692935D01*
X1599268Y1693515D01*
X1600545D01*
X1601378Y1692682D01*
Y1691692D01*
G01X1609252Y1700354D02*
Y1699113D01*
X1608671Y1698532D01*
X1606690D01*
X1605482Y1697324D01*
Y1670268D01*
X1625500Y1617103D01*
Y1615417D01*
X1624375Y1614292D01*
G01X1627775D02*
X1626580Y1615487D01*
Y1617300D01*
X1623090Y1626569D01*
X1623376Y1627200D01*
X1622770Y1628811D01*
X1622138Y1629097D01*
X1621532Y1630706D01*
X1621818Y1631337D01*
X1621212Y1632948D01*
X1620581Y1633233D01*
X1606562Y1670465D01*
Y1696876D01*
X1607138Y1697452D01*
X1608419D01*
X1609252Y1696619D01*
Y1695629D01*
G01X1617126Y1696417D02*
Y1695176D01*
X1616545Y1694595D01*
X1614568D01*
X1613356Y1693383D01*
Y1671814D01*
X1637560Y1617390D01*
Y1615417D01*
X1636435Y1614292D01*
G01X1639835D02*
X1638640Y1615487D01*
Y1617620D01*
X1634005Y1628042D01*
X1634254Y1628689D01*
X1633555Y1630261D01*
X1632907Y1630510D01*
X1632209Y1632081D01*
X1632457Y1632728D01*
X1631758Y1634301D01*
X1631110Y1634549D01*
X1631111Y1634550D01*
X1630413Y1636121D01*
X1630661Y1636768D01*
X1629962Y1638341D01*
X1629315Y1638589D01*
X1628617Y1640160D01*
X1628865Y1640807D01*
X1628166Y1642379D01*
X1627518Y1642628D01*
X1614436Y1672044D01*
Y1692935D01*
X1615016Y1693515D01*
X1616293D01*
X1617126Y1692682D01*
Y1691692D01*
G01X1651895Y1614292D02*
X1650700Y1615487D01*
Y1617983D01*
X1645502Y1627599D01*
X1645700Y1628263D01*
X1644882Y1629777D01*
X1644217Y1629975D01*
X1643400Y1631488D01*
X1643598Y1632152D01*
X1642780Y1633666D01*
X1642115Y1633864D01*
X1622310Y1670498D01*
Y1696872D01*
X1622890Y1697452D01*
X1624167D01*
X1625000Y1696619D01*
Y1695629D01*
G01Y1700354D02*
Y1699113D01*
X1624419Y1698532D01*
X1622442D01*
X1621230Y1697320D01*
Y1670224D01*
X1649620Y1617709D01*
Y1615417D01*
X1648495Y1614292D01*
G01X1942395Y1195248D02*
X1946275D01*
X1946855Y1194668D01*
Y603628D01*
X1946275Y603048D01*
X1942395D01*
G01X1952395Y1195248D02*
X1948515D01*
X1947935Y1194668D01*
Y603628D01*
X1948515Y603048D01*
X1952395D01*
G54D23*
G01X212891Y635981D02*
X212800Y636072D01*
Y639162D01*
X211700Y640262D01*
X208900D01*
X205100Y644062D01*
Y650762D01*
X198300Y657562D01*
Y664262D01*
X195800Y666762D01*
Y672062D01*
X196600Y672862D01*
X198220D01*
X198420Y672662D01*
G01X392947Y1397827D02*
X390107D01*
X388607Y1399327D01*
Y1401758D01*
X390934Y1404085D01*
G01X392947Y1397827D02*
Y1392957D01*
X394336Y1391568D01*
X402720D01*
X415795Y1404643D01*
Y1420036D01*
X421035Y1425276D01*
X424179D01*
X429220Y1430317D01*
Y1439614D01*
X445076Y1455470D01*
X471369D01*
X474153Y1452686D01*
X512185D01*
X515226Y1449645D01*
Y1438613D01*
X524089Y1429750D01*
X622608D01*
X636583Y1443725D01*
X708701D01*
X724439Y1437206D01*
X764620Y1397025D01*
Y1379362D01*
X768520Y1375462D01*
G01X523731Y1437205D02*
X526478Y1439952D01*
G01D02*
X529225Y1437205D01*
G01X526478Y1439952D02*
X529225Y1442699D01*
G01X523731D02*
X526478Y1439952D01*
G01X614220Y462862D02*
X611323Y465759D01*
X609522D01*
X608126Y464363D01*
X604991D01*
X603930Y465424D01*
X596661D01*
X594627Y463390D01*
X565280D01*
X562860Y460970D01*
Y453110D01*
X561642Y451892D01*
X552378D01*
X548464Y455806D01*
Y456534D01*
G01X629000Y67362D02*
X624970Y63332D01*
Y57252D01*
X623580Y55862D01*
Y53692D01*
X628310Y48962D01*
X631066D01*
X643516Y36512D01*
X650200D01*
X651943Y34769D01*
Y33535D01*
G01X670275Y1317960D02*
X673093Y1320778D01*
G01D02*
X675911Y1323596D01*
G01X670275D02*
X673093Y1320778D01*
G01D02*
X675911Y1317960D01*
G01X685968Y58157D02*
X692173Y64362D01*
X701000D01*
X713000Y76362D01*
Y79362D01*
X712500Y79862D01*
G01X694648Y1317985D02*
X697466Y1320803D01*
G01X694648Y1323621D02*
X697466Y1320803D01*
G01D02*
X700284Y1323621D01*
G01X697466Y1320803D02*
X700284Y1317985D01*
G01X719048D02*
X721866Y1320803D01*
G01D02*
X724684Y1323621D01*
G01X719048D02*
X721866Y1320803D01*
G01D02*
X724684Y1317985D01*
G01X1194840Y236592D02*
X1188410Y230162D01*
X1163300D01*
X1159500Y226362D01*
X1147600D01*
X1142500Y221262D01*
X1137100D01*
X1111971Y246391D01*
X1100281D01*
X1099030Y245140D01*
G01X1275856Y1358098D02*
Y1359596D01*
X1271673Y1363779D01*
X1241905D01*
X1198052Y1407632D01*
X1120920D01*
X1115853Y1412699D01*
Y1426342D01*
G01X1131100Y1357088D02*
X1133918Y1359906D01*
G01X1128282D02*
X1131100Y1357088D01*
G01X1155500D02*
X1158318Y1359906D01*
G01X1152682D02*
X1155500Y1357088D01*
G01X1179900D02*
X1182718Y1359906D01*
G01X1177082D02*
X1179900Y1357088D01*
G01X1240728Y136198D02*
X1244050Y139520D01*
Y152912D01*
X1237481Y159481D01*
X1224061D01*
X1222890Y158310D01*
Y157002D01*
G01X1397389Y860993D02*
X1399020D01*
G01X1457714Y741622D02*
X1445936D01*
X1433418Y729104D01*
G01X1500209Y1436783D02*
X1502956Y1439530D01*
G01D02*
X1505703Y1436783D01*
G01X1502956Y1439530D02*
X1505703Y1442277D01*
G01X1500209D02*
X1502956Y1439530D01*
G01X1576589Y300927D02*
X1578030D01*
X1637060Y241897D01*
Y210642D01*
X1633111Y206693D01*
G01X1664410Y617953D02*
Y614232D01*
X1668440Y610202D01*
X1670030D01*
X1680700Y599532D01*
Y582862D01*
X1675100Y577262D01*
X1636180D01*
X1618920Y560002D01*
X1602980D01*
G01X1631441Y1351556D02*
X1634259Y1354374D01*
G01D02*
X1637077Y1357192D01*
G01X1631441D02*
X1634259Y1354374D01*
G01D02*
X1637077Y1351556D01*
G01X1655814Y1351581D02*
X1658632Y1354399D01*
G01X1655814Y1357217D02*
X1658632Y1354399D01*
G01X1719530Y162950D02*
X1719340Y162760D01*
X1703700D01*
X1696340Y170120D01*
Y177410D01*
X1692898Y180852D01*
X1668100D01*
G01X1658632Y1354399D02*
X1661450Y1357217D01*
G01X1658632Y1354399D02*
X1661450Y1351581D01*
G01X1680214D02*
X1683032Y1354399D01*
G01D02*
X1685850Y1357217D01*
G01X1680214D02*
X1683032Y1354399D01*
G01D02*
X1685850Y1351581D01*
G54D14*
X322500Y1391830D03*
X537477Y1395413D03*
X1298642Y1391830D03*
X1513618Y1395413D03*
G54D33*
G01X377062Y1012501D02*
X378293D01*
X378519Y1012275D01*
G02X377834Y1011244I-1458J225D01*
G01X377799Y1011224D01*
G02X376325I-737J1277D01*
G03X374157Y1011258I-1114J-1927D01*
G01X374099Y1011224D01*
G02X372625I-737J1277D01*
G03X370399I-1113J-1927D01*
G02X368925I-737J1277D01*
G03X366739Y1011248I-1114J-1927D01*
G01X366698Y1011224D01*
G02X365224I-737J1277D01*
G03X363040Y1011248I-1113J-1927D01*
G01X362999Y1011224D01*
G02X361525I-737J1277D01*
G03X359339Y1011248I-1114J-1927D01*
G01X359298Y1011224D01*
G02X357824I-737J1277D01*
G03X355598I-1113J-1927D01*
G02X354124I-737J1277D01*
G03X351898I-1113J-1927D01*
G02X350424I-737J1277D01*
G03X348198I-1113J-1927D01*
G02X346724I-737J1277D01*
G03X344498I-1113J-1927D01*
G02X343024I-737J1277D01*
G03X340798I-1113J-1927D01*
G02X339324I-737J1277D01*
G03X337098I-1113J-1927D01*
G02X335624I-737J1277D01*
G03X333398I-1113J-1927D01*
G02X331924I-737J1277D01*
G03X330811Y1011522I-1112J-1927D01*
G01X329013D01*
X328661Y1011170D01*
X326940D01*
G01X374778Y969939D02*
G02X374465Y966009I-6346J-1472D01*
G02X374074Y965643I-594J242D01*
G03X373724Y965492I704J-2113D01*
G01X373666Y965458D01*
G02X372192I-737J1277D01*
G03X370024Y965492I-1115J-1928D01*
G01X369966Y965458D01*
G02X368492I-737J1277D01*
G03X366306Y965482I-1114J-1928D01*
G01X366265Y965458D01*
G02X364791I-737J1277D01*
G01X364750Y965482D01*
G03X362566Y965458I-1071J-1952D01*
G02X361092I-737J1277D01*
G03X358906Y965482I-1114J-1928D01*
G01X358865Y965458D01*
G02X357391I-737J1277D01*
G01X357350Y965482D01*
G03X355166Y965458I-1071J-1952D01*
G02X353692I-737J1277D01*
G03X351524Y965492I-1115J-1928D01*
G01X351466Y965458D01*
G02X349992I-737J1277D01*
G03X347824Y965492I-1115J-1928D01*
G01X347766Y965458D01*
G02X346292I-737J1277D01*
G03X344124Y965492I-1115J-1928D01*
G01X344066Y965458D01*
G02X342592I-737J1277D01*
G03X340424Y965492I-1115J-1928D01*
G01X340366Y965458D01*
G02X338892I-737J1277D01*
G03X336724Y965492I-1115J-1928D01*
G01X336666Y965458D01*
G02X335192I-737J1277D01*
G03X333024Y965492I-1115J-1928D01*
G01X332966Y965458D01*
G02X331492I-737J1277D01*
G01X331386Y965564D01*
X331086D01*
X329169Y967481D01*
Y967840D01*
X328658Y969073D01*
X328361Y969370D01*
X327525D01*
G01X380762Y1012501D02*
X379531D01*
X379272Y1012242D01*
G02X378198Y1010588I-2210J259D01*
G01X378174Y1010574D01*
X378116Y1010540D01*
G02X375948Y1010574I-1054J1961D01*
G03X374474I-737J-1277D01*
G01X374433Y1010550D01*
G02X372249Y1010574I-1071J1951D01*
G03X370775I-737J-1277D01*
G01X370734Y1010550D01*
G02X368548Y1010574I-1072J1951D01*
G03X367074I-737J-1277D01*
G02X364848I-1113J1927D01*
G03X363374I-737J-1277D01*
G01X363316Y1010540D01*
G02X361148Y1010574I-1054J1961D01*
G03X359674I-737J-1277D01*
G02X357448I-1113J1927D01*
G03X355974I-737J-1277D01*
G02X353748I-1113J1927D01*
G03X352274I-737J-1277D01*
G02X350048I-1113J1927D01*
G03X348574I-737J-1277D01*
G02X346348I-1113J1927D01*
G03X344874I-737J-1277D01*
G02X342648I-1113J1927D01*
G03X341174I-737J-1277D01*
G02X338948I-1113J1927D01*
G03X337474I-737J-1277D01*
G02X335248I-1113J1927D01*
G03X333774I-737J-1277D01*
G02X331548I-1113J1927D01*
G03X330811Y1010773I-740J-1276D01*
G01X330023D01*
X328460Y1009210D01*
X327121D01*
G01X382178Y969939D02*
G02X381993Y966907I-20271J-285D01*
G02X380154Y965081I-2113J289D01*
G02X379464Y965051I-520J4010D01*
G03X378699Y965018I-191J-4458D01*
G02X378494Y965005I-196J1461D01*
G03X377735Y964804I-16J-1475D01*
G02X377420Y964652I-1075J1825D01*
G02X375515Y964807I-789J2082D01*
G03X374041I-737J-1277D01*
G01X373983Y964773D01*
G02X371815Y964807I-1053J1962D01*
G03X370341I-737J-1277D01*
G01X370283Y964773D01*
G02X368115Y964807I-1053J1962D01*
G03X366641I-737J-1277D01*
G02X364457Y964783I-1113J1928D01*
G01X364416Y964807D01*
G03X362942I-737J-1277D01*
G01X362901Y964783D01*
G02X360715Y964807I-1072J1952D01*
G03X359241I-737J-1277D01*
G02X357057Y964783I-1113J1928D01*
G01X357016Y964807D01*
G03X355542I-737J-1277D01*
G01X355501Y964783D01*
G02X353315Y964807I-1072J1952D01*
G03X351841I-737J-1277D01*
G01X351783Y964773D01*
G02X349615Y964807I-1053J1962D01*
G03X348141I-737J-1277D01*
G01X348083Y964773D01*
G02X345915Y964807I-1053J1962D01*
G03X344441I-737J-1277D01*
G01X344383Y964773D01*
G02X342215Y964807I-1053J1962D01*
G03X340741I-737J-1277D01*
G01X340683Y964773D01*
G02X338515Y964807I-1053J1962D01*
G03X337041I-737J-1277D01*
G01X336983Y964773D01*
G02X334815Y964807I-1053J1962D01*
G03X333341I-737J-1277D01*
G01X333283Y964773D01*
G02X331115Y964807I-1053J1962D01*
G01X330744D01*
X328400Y967151D01*
Y967652D01*
X328051Y968001D01*
X327524D01*
G01X375211Y1009297D02*
X373704Y1008740D01*
G03X372596Y1008220I2523J-6816D01*
G01X372249Y1008020D01*
G02X370775I-737J1277D01*
G01X370734Y1008044D01*
G03X368548Y1008020I-1072J-1951D01*
G02X367074I-737J1277D01*
G01X367016Y1008054D01*
G03X364848Y1008020I-1054J-1961D01*
G02X363374I-737J1277D01*
G03X361148I-1113J-1927D01*
G02X359674I-737J1277D01*
G01X359616Y1008054D01*
G03X357448Y1008020I-1054J-1961D01*
G02X355974I-737J1277D01*
G03X353748I-1113J-1927D01*
G02X352274I-737J1277D01*
G01X352216Y1008054D01*
G03X350048Y1008020I-1054J-1961D01*
G02X348574I-737J1277D01*
G03X346348I-1113J-1927D01*
G02X344874I-737J1277D01*
G03X342648I-1113J-1927D01*
G02X341174I-737J1277D01*
G03X338948I-1113J-1927D01*
G02X337474I-737J1277D01*
G03X335248I-1113J-1927D01*
G02X333774I-737J1277D01*
G03X331548I-1113J-1927D01*
G02X330811Y1007821I-740J1276D01*
G01X329872D01*
X329300Y1007249D01*
X327121D01*
G01X374778Y912262D02*
G03X373378Y911887I1J-2803D01*
G01X371816Y910985D01*
G02X370342I-737J1277D01*
G01X370301Y911009D01*
G03X368115Y910985I-1072J-1952D01*
G02X366641I-737J1277D01*
G01X366583Y911019D01*
G03X364415Y910985I-1053J-1962D01*
G02X362941I-737J1277D01*
G01X362883Y911019D01*
G03X360715Y910985I-1053J-1962D01*
G02X359241I-737J1277D01*
G03X357015I-1113J-1928D01*
G03X355903Y909130I1113J-1928D01*
G01Y909023D01*
G02X355166Y907780I-1474J34D01*
G02X353692I-737J1277D01*
G03X351524Y907814I-1114J-1927D01*
G01X351466Y907780D01*
G02X349992I-737J1277D01*
G03X347824Y907814I-1114J-1927D01*
G01X347766Y907780D01*
G02X346335Y907756I-737J1277D01*
G01X346292Y907781D01*
G03X344066I-1113J-1927D01*
G02X342592I-737J1277D01*
G03X340424Y907815I-1115J-1928D01*
G01X340366Y907781D01*
G03X339254Y905910I1113J-1927D01*
G01X339253Y905854D01*
Y905820D01*
G02X338516Y904577I-1474J34D01*
G02X337042I-737J1277D01*
G03X334816I-1113J-1927D01*
G02X333342I-737J1277D01*
G03X332106Y904908I-1236J-2142D01*
G01X332097Y904917D01*
X331252D01*
X329953Y903618D01*
Y900403D01*
X326596Y897046D01*
X324723D01*
G01X376629Y909057D02*
G02X374044Y907955I-9572J18871D01*
G03X373724Y907814I735J-2101D01*
G01X373666Y907780D01*
G02X372192I-737J1277D01*
G03X370024Y907814I-1114J-1927D01*
G01X369966Y907780D01*
G02X368492I-737J1277D01*
G03X366324Y907814I-1114J-1927D01*
G01X366266Y907780D01*
G02X364792I-737J1277D01*
G03X362624Y907814I-1114J-1927D01*
G01X362566Y907780D01*
G02X361092I-737J1277D01*
G03X357753Y905892I-1114J-1927D01*
G01Y905819D01*
G02X355542Y904576I-1474J34D01*
G01X355501Y904600D01*
G03X353315Y904576I-1072J-1951D01*
G02X351841I-737J1277D01*
G01X351783Y904610D01*
G03X349615Y904576I-1054J-1961D01*
G02X348141I-737J1277D01*
G01X348073Y904615D01*
G03X345916Y904577I-1044J-1966D01*
G02X344442I-737J1277D01*
G03X342283Y904616I-1115J-1928D01*
G01X342215Y904576D01*
G03X341104Y902689I1114J-1926D01*
G01X341103Y902650D01*
Y902616D01*
G02X338892Y901373I-1474J34D01*
G03X336666I-1113J-1927D01*
G01X336667Y901372D01*
G02X335193I-737J1277D01*
G01X335152Y901396D01*
G03X331854Y899445I-1072J-1951D01*
G01Y899065D01*
X325915Y893126D01*
X324723D01*
G01X374778Y918670D02*
G03X372191Y920598I-9501J-10049D01*
G03X370007Y920622I-1113J-1928D01*
G01X369966Y920598D01*
G02X368492I-737J1277D01*
G03X366324Y920632I-1115J-1928D01*
G01X366266Y920598D01*
G02X364792I-737J1277D01*
G03X362624Y920632I-1115J-1928D01*
G01X362566Y920598D01*
G02X361092I-737J1277D01*
G03X358866I-1113J-1928D01*
G02X357392I-737J1277D01*
G03X355224Y920632I-1115J-1928D01*
G01X355166Y920598D01*
G02X353692I-737J1277D01*
G03X351524Y920632I-1115J-1928D01*
G01X351466Y920598D01*
G02X349992I-737J1277D01*
G03X346653Y918726I-1113J-1928D01*
G01Y918636D01*
G02X344442Y917393I-1474J34D01*
G01X344388Y917425D01*
G03X342216Y917394I-1058J-1959D01*
G02X340742I-737J1278D01*
G01X340701Y917418D01*
G03X338515Y917394I-1072J-1952D01*
G02X337041I-737J1277D01*
G03X333703Y915522I-1113J-1928D01*
G01Y915466D01*
G02X332228Y913990I-1476J0D01*
G01X329349D01*
X328098Y912739D01*
Y908992D01*
X326432Y907326D01*
X325323D01*
G01X372929Y915466D02*
X372804Y915922D01*
X372651Y916009D01*
G03X372042Y916170I-609J-1071D01*
G01X370962D01*
X369967Y916743D01*
X369966D01*
G03X368492I-737J-1277D01*
G02X366324Y916709I-1114J1927D01*
G01X366266Y916743D01*
G03X364792I-737J-1277D01*
G02X362606Y916719I-1114J1927D01*
G01X362565Y916743D01*
G03X361091I-737J-1277D01*
G01X361050Y916719D01*
G02X358866Y916743I-1071J1951D01*
G03X357392I-737J-1277D01*
G02X355224Y916709I-1114J1927D01*
G01X355166Y916743D01*
G03X352954Y915466I-737J-1277D01*
G02X351858Y913549I-2225J0D01*
G01X351783Y913505D01*
G02X349615Y913539I-1054J1961D01*
G03X348141I-737J-1277D01*
G01X348100Y913515D01*
G02X345916Y913539I-1071J1951D01*
G03X344442I-737J-1277D01*
G02X342216I-1113J1927D01*
G03X340742I-737J-1277D01*
G02X338516I-1113J1927D01*
G03X336304Y912262I-737J-1277D01*
G01Y912189D01*
G02X332966Y910334I-2225J73D01*
G03X331492I-737J-1277D01*
G03X331185Y910101I731J-1282D01*
G01X330402Y909318D01*
Y907477D01*
X327557Y904632D01*
Y903281D01*
X326697Y902421D01*
X325650D01*
X325415Y902186D01*
X325323D01*
G01X376629Y915466D02*
G02X375289Y915820I-1J2708D01*
G01X373615Y916772D01*
G03X372810Y916936I-648J-1121D01*
G01X372585Y916909D01*
X372566Y916919D01*
X371163D01*
X370283Y917427D01*
G03X368115Y917393I-1054J-1961D01*
G02X366641I-737J1277D01*
G01X366583Y917427D01*
G03X364415Y917393I-1054J-1961D01*
G02X362941I-737J1277D01*
G03X360757Y917417I-1113J-1927D01*
G01X360716Y917393D01*
G02X359242I-737J1277D01*
G01X359201Y917417D01*
G03X357015Y917393I-1072J-1951D01*
G02X355541I-737J1277D01*
G01X355483Y917427D01*
G03X352204Y915527I-1054J-1961D01*
G01Y915466D01*
G02X351501Y914209I-1475J0D01*
G01X351472Y914192D01*
X351466Y914189D01*
G02X349992I-737J1277D01*
G03X347824Y914223I-1114J-1927D01*
G01X347766Y914189D01*
G02X346292I-737J1277D01*
G03X344066I-1113J-1927D01*
G02X342592I-737J1277D01*
G03X340366I-1113J-1927D01*
G02X338892I-737J1277D01*
G01X338851Y914213D01*
G03X335554Y912323I-1072J-1951D01*
G01Y912262D01*
G02X333342Y910985I-1475J0D01*
G03X330655Y910631I-1113J-1928D01*
G01X329653Y909629D01*
Y907788D01*
X326808Y904943D01*
Y903592D01*
X326386Y903170D01*
X325651D01*
X325415Y903406D01*
X325323D01*
G01X376629Y921875D02*
G03X374089Y923774I-9569J-10151D01*
G01X374041Y923802D01*
G03X371815I-1113J-1927D01*
G02X370341I-737J1277D01*
G01X370283Y923836D01*
G03X368115Y923802I-1054J-1961D01*
G02X366641I-737J1277D01*
G01X366583Y923836D01*
G03X364415Y923802I-1054J-1961D01*
G02X362941I-737J1277D01*
G01X362883Y923836D01*
G03X360715Y923802I-1054J-1961D01*
G02X359241I-737J1277D01*
G01X359200Y923826D01*
G03X357016Y923802I-1071J-1951D01*
G02X355542I-737J1277D01*
G01X355501Y923826D01*
G03X353315Y923802I-1072J-1951D01*
G02X351841I-737J1277D01*
G01X351783Y923836D01*
G03X349615Y923802I-1054J-1961D01*
G02X348141I-737J1277D01*
G01X348073Y923841D01*
G03X345916Y923803I-1044J-1966D01*
G03X344805Y921949I1114J-1927D01*
G01X344804Y921876D01*
Y921848D01*
G02X344066Y920598I-1475J28D01*
G02X342635Y920574I-737J1278D01*
G01X342592Y920599D01*
X342551Y920623D01*
G03X340365Y920599I-1072J-1951D01*
G01X340322Y920574D01*
G02X338891Y920598I-694J1301D01*
G01X338856Y920619D01*
G03X336666Y920599I-1077J-1948D01*
G01X336633Y920580D01*
G02X335193Y920599I-703J1296D01*
G01X335152Y920623D01*
G03X332966Y920599I-1072J-1951D01*
G01X332942Y920585D01*
G03X331854Y918671I1138J-1913D01*
G02X331151Y917414I-1475J0D01*
G01X331116Y917394D01*
G02X330379Y917194I-742J1276D01*
G01X330068D01*
X326477Y913603D01*
Y911595D01*
X326128Y911246D01*
X325324D01*
G01X382611Y1009297D02*
X380123Y1007443D01*
G02X379821Y1007265I-959J1282D01*
G02X377857Y1007336I-910J2032D01*
G01X377799Y1007370D01*
G03X376325I-737J-1277D01*
G02X374157Y1007336I-1114J1927D01*
G01X374099Y1007370D01*
G03X372625I-737J-1277D01*
G02X370399I-1113J1927D01*
G03X368925I-737J-1277D01*
G02X366757Y1007336I-1114J1927D01*
G01X366699Y1007370D01*
G03X365225I-737J-1277D01*
G02X363039Y1007346I-1114J1927D01*
G01X362998Y1007370D01*
G03X361524I-737J-1277D01*
G02X359340Y1007346I-1113J1927D01*
G01X359299Y1007370D01*
G03X357825I-737J-1277D01*
G02X355639Y1007346I-1114J1927D01*
G01X355598Y1007370D01*
G03X354124I-737J-1277D01*
G02X351940Y1007346I-1113J1927D01*
G01X351899Y1007370D01*
G03X350425I-737J-1277D01*
G02X348239Y1007346I-1114J1927D01*
G01X348198Y1007370D01*
G03X346724I-737J-1277D01*
G02X344498I-1113J1927D01*
G03X343024I-737J-1277D01*
G02X340798I-1113J1927D01*
G03X339324I-737J-1277D01*
G02X337098I-1113J1927D01*
G03X335624I-737J-1277D01*
G02X333398I-1113J1927D01*
G03X331924I-737J-1277D01*
G02X330811Y1007072I-1112J1927D01*
G01X330270D01*
X328445Y1005247D01*
X327121D01*
G01X380329Y966735D02*
X379098D01*
X378839Y966994D01*
G03X377765Y968648I-2210J-259D01*
G01X377741Y968662D01*
X377706Y968682D01*
G02X377003Y969939I772J1257D01*
G01Y970000D01*
G03X375892Y971866I-2225J-61D01*
G03X373724Y971900I-1114J-1927D01*
G01X373666Y971866D01*
X373642Y971852D01*
G03X372553Y969939I1136J-1913D01*
G01Y969905D01*
G02X371816Y968662I-1474J34D01*
G02X370342I-737J1277D01*
G01X370301Y968686D01*
G03X368115Y968662I-1072J-1951D01*
G02X366641I-737J1277D01*
G03X364415I-1113J-1927D01*
G02X362941I-737J1277D01*
G01X362883Y968696D01*
G03X360715Y968662I-1054J-1961D01*
G02X359241I-737J1277D01*
G03X357015I-1113J-1927D01*
G02X355541I-737J1277D01*
G01X355483Y968696D01*
G03X353315Y968662I-1054J-1961D01*
G02X351841I-737J1277D01*
G01X351783Y968696D01*
G03X349615Y968662I-1054J-1961D01*
G02X348141I-737J1277D01*
G01X348100Y968686D01*
G03X345916Y968662I-1071J-1951D01*
G02X344442I-737J1277D01*
G03X342216I-1113J-1927D01*
G02X340742I-737J1277D01*
G03X338516I-1113J-1927D01*
G02X337042I-737J1277D01*
G03X334816I-1113J-1927D01*
G02X333342I-737J1277D01*
G03X331116I-1113J-1927D01*
G01X330746D01*
X330397Y969011D01*
Y971662D01*
X329620Y972439D01*
X328821D01*
G01X377062Y1076587D02*
X378293D01*
X378519Y1076361D01*
G02X376325Y1075310I-1457J226D01*
G03X374139Y1075334I-1114J-1927D01*
G01X374098Y1075310D01*
G02X372624I-737J1277D01*
G03X370440Y1075334I-1113J-1927D01*
G01X370399Y1075310D01*
G02X368925I-737J1277D01*
G03X366757Y1075344I-1114J-1927D01*
G01X366699Y1075310D01*
G02X365225I-737J1277D01*
G03X363057Y1075344I-1114J-1927D01*
G01X362999Y1075310D01*
G02X361525I-737J1277D01*
G03X359357Y1075344I-1114J-1927D01*
G01X359299Y1075310D01*
G02X357825I-737J1277D01*
G01X357784Y1075334D01*
G03X355598Y1075310I-1072J-1951D01*
G02X354124I-737J1277D01*
G03X351898I-1113J-1927D01*
G02X350424I-737J1277D01*
G01X350389Y1075330D01*
G02X349686Y1076587I772J1257D01*
G01Y1076626D01*
G03X348574Y1078514I-2225J-39D01*
G03X346348I-1113J-1927D01*
G02X344874I-737J1277D01*
G01X344839Y1078534D01*
G02X344136Y1079791I772J1257D01*
G03X343047Y1081704I-2225J0D01*
G01X343023Y1081718D01*
X342965Y1081752D01*
G03X340797Y1081718I-1054J-1961D01*
G02X339323I-737J1277D01*
G01X339288Y1081738D01*
G02X338585Y1082995I772J1257D01*
G01Y1083068D01*
G03X337473Y1084923I-2225J-73D01*
G03X335247I-1113J-1928D01*
G02X333773I-737J1277D01*
G01X333738Y1084943D01*
G02X333035Y1086200I772J1257D01*
G01Y1086261D01*
G03X331924Y1088127I-2225J-61D01*
G01Y1092684D01*
X330841Y1093767D01*
X328123D01*
G01X375211Y1079791D02*
X373750Y1079394D01*
X372248Y1078514D01*
G02X370774I-737J1277D01*
G01X370716Y1078548D01*
G03X368548Y1078514I-1054J-1961D01*
G02X367074I-737J1277D01*
G01X367016Y1078548D01*
G03X364848Y1078514I-1054J-1961D01*
G02X363374I-737J1277D01*
G01X363333Y1078538D01*
G03X361149Y1078514I-1071J-1951D01*
G02X359675I-737J1277D01*
G01X359634Y1078538D01*
G03X357448Y1078514I-1072J-1951D01*
G02X355974I-737J1277D01*
G03X353748I-1113J-1927D01*
G02X352274I-737J1277D01*
G01X352239Y1078534D01*
G02X351536Y1079791I772J1257D01*
G01Y1079830D01*
G03X350424Y1081718I-2225J-39D01*
G03X348198I-1113J-1927D01*
G02X346724I-737J1277D01*
G01X346689Y1081738D01*
G02X345986Y1082995I772J1257D01*
G01Y1083025D01*
G03X344873Y1084923I-2226J-30D01*
G03X342647I-1113J-1928D01*
G02X341173I-737J1277D01*
G01X341138Y1084943D01*
G02X340435Y1086200I772J1257D01*
G01Y1086261D01*
G03X339324Y1088127I-2225J-61D01*
G03X337156Y1088161I-1114J-1927D01*
G01X337098Y1088127D01*
G02X335892Y1088286I-499J865D01*
G01X334398Y1089780D01*
Y1093297D01*
X329520Y1098175D01*
X328727D01*
G01X375211Y1086200D02*
X372975Y1087920D01*
X372625Y1088127D01*
G03X370399I-1113J-1927D01*
G02X368925I-737J1277D01*
G03X366757Y1088161I-1114J-1927D01*
G01X366699Y1088127D01*
G02X365225I-737J1277D01*
G03X363057Y1088161I-1114J-1927D01*
G01X362999Y1088127D01*
G02X361525I-737J1277D01*
G03X359339Y1088151I-1114J-1927D01*
G01X359298Y1088127D01*
G02X357824I-737J1277D01*
G01X357789Y1088147D01*
G02X357086Y1089404I772J1257D01*
G01Y1089465D01*
G03X355975Y1091331I-2225J-61D01*
G01X355940Y1091351D01*
G02X355237Y1092608I772J1257D01*
G01Y1092638D01*
G03X354124Y1094536I-2226J-30D01*
G01X354089Y1094556D01*
G02X353386Y1095813I772J1257D01*
G01Y1095852D01*
G03X352274Y1097740I-2225J-39D01*
G03X350048I-1113J-1927D01*
G02X348574I-737J1277D01*
G03X346348I-1113J-1927D01*
G02X344874I-737J1277D01*
G03X342648I-1113J-1927D01*
G02X341174I-737J1277D01*
G01X341139Y1097760D01*
G02X340436Y1099017I772J1257D01*
G01Y1099056D01*
G03X339324Y1100944I-2225J-39D01*
G01X339289Y1100964D01*
G02X338586Y1102221I772J1257D01*
G01Y1102294D01*
G03X337474Y1104149I-2225J-73D01*
G02X337167Y1104382I731J1282D01*
G01X336307Y1105242D01*
Y1107769D01*
X333932Y1110144D01*
X332922D01*
G01X373362Y1082995D02*
X373237Y1083451D01*
X373084Y1083538D01*
G03X372475Y1083699I-609J-1071D01*
G01X371398D01*
X370401Y1084273D01*
X370400Y1084272D01*
G03X368926I-737J-1277D01*
G01X368925D01*
G02X366757Y1084238I-1115J1928D01*
G01X366699Y1084272D01*
G03X365225I-737J-1277D01*
G02X363039Y1084248I-1114J1927D01*
G01X362998Y1084272D01*
G03X361524I-737J-1277D01*
G02X359340Y1084248I-1113J1927D01*
G01X359299Y1084272D01*
G03X357825I-737J-1277D01*
G02X355639Y1084248I-1114J1927D01*
G01X355598Y1084272D01*
G02X354486Y1086127I1113J1928D01*
G01Y1086200D01*
G03X353783Y1087457I-1475J0D01*
G01X353751Y1087475D01*
X353748Y1087477D01*
G02X352636Y1089365I1113J1927D01*
G01Y1089404D01*
G03X351933Y1090661I-1475J0D01*
G01X351898Y1090681D01*
X351850Y1090709D01*
G02X350785Y1092609I1161J1899D01*
G03X350082Y1093866I-1475J0D01*
G01X350047Y1093886D01*
G03X348573I-737J-1277D01*
G01X348515Y1093852D01*
G02X346347Y1093886I-1054J1961D01*
G03X344873I-737J-1277D01*
G01X344815Y1093852D01*
G02X342647Y1093886I-1054J1961D01*
G03X341173I-737J-1277D01*
G01X341115Y1093852D01*
G02X338947Y1093886I-1054J1961D01*
G02X338487Y1094239I1114J1927D01*
G01X337472Y1095254D01*
Y1097664D01*
X332787Y1102349D01*
Y1104544D01*
X332172Y1105159D01*
X331250D01*
X331015Y1104924D01*
X330923D01*
G01X377062Y1082995D02*
G02X376669Y1083095I17157J68249D01*
G02X376338Y1083207I640J2436D01*
G01X375155Y1083696D01*
G02X374842Y1083849I1069J2583D01*
G01X374048Y1084301D01*
G03X373243Y1084465I-648J-1121D01*
G01X373018Y1084438D01*
X372999Y1084448D01*
X371599D01*
X370719Y1084955D01*
G03X368549Y1084922I-1055J-1960D01*
G01X368548Y1084923D01*
G02X367074I-737J1277D01*
G01X367016Y1084957D01*
G03X364848Y1084923I-1053J-1962D01*
G01Y1084922D01*
G02X363374I-737J1277D01*
G03X361148I-1113J-1927D01*
G02X359674I-737J1277D01*
G01X359616Y1084956D01*
G03X357448Y1084922I-1054J-1961D01*
G02X355974I-737J1277D01*
G01Y1084923D01*
X355939Y1084943D01*
G02X355236Y1086200I772J1257D01*
G01Y1086239D01*
G03X354124Y1088127I-2225J-39D01*
G01X354089Y1088147D01*
G02X353386Y1089404I772J1257D01*
G01Y1089443D01*
G03X352274Y1091331I-2225J-39D01*
G01X352271Y1091333D01*
X352264Y1091337D01*
X352261Y1091339D01*
X352242Y1091349D01*
X352239Y1091351D01*
G02X351536Y1092608I772J1257D01*
G03X350448Y1094522I-2226J1D01*
G01X350424Y1094536D01*
G03X348256Y1094570I-1114J-1927D01*
G01X348198Y1094536D01*
G02X346724I-737J1277D01*
G03X344556Y1094570I-1114J-1927D01*
G01X344498Y1094536D01*
G02X343024I-737J1277D01*
G03X340856Y1094570I-1114J-1927D01*
G01X340798Y1094536D01*
G02X339324I-737J1277D01*
G02X339017Y1094769I731J1282D01*
G01X338221Y1095565D01*
Y1097975D01*
X333536Y1102660D01*
Y1104855D01*
X332483Y1105908D01*
X331251D01*
X331015Y1106144D01*
X330923D01*
G01X377062Y1089404D02*
X378293D01*
X378519Y1089178D01*
G02X377834Y1088147I-1458J225D01*
G01X377799Y1088127D01*
G02X376325I-737J1277D01*
G01X376290Y1088147D01*
G02X375587Y1089404I772J1257D01*
G03X374498Y1091317I-2225J0D01*
G01X374474Y1091331D01*
X374416Y1091365D01*
G03X372248Y1091331I-1054J-1961D01*
G02X370774I-737J1277D01*
G01X370716Y1091365D01*
G03X368548Y1091331I-1054J-1961D01*
G02X367074I-737J1277D01*
G01X367016Y1091365D01*
G03X364848Y1091331I-1054J-1961D01*
G02X363374I-737J1277D01*
G01X363316Y1091365D01*
G03X361148Y1091331I-1054J-1961D01*
G02X359674I-737J1277D01*
G02X358937Y1092574I737J1277D01*
G01Y1092664D01*
G03X357824Y1094536I-2225J-56D01*
G01X357789Y1094556D01*
G02X357086Y1095813I772J1257D01*
G01Y1095852D01*
G03X355974Y1097740I-2225J-39D01*
G01X355939Y1097760D01*
G02X355236Y1099017I772J1257D01*
G01Y1099056D01*
G03X354124Y1100944I-2225J-39D01*
G03X351898I-1113J-1927D01*
G02X350424I-737J1277D01*
G03X348198I-1113J-1927D01*
G02X346724I-737J1277D01*
G03X344498I-1113J-1927D01*
G02X343024I-737J1277D01*
G01X342989Y1100964D01*
G02X342286Y1102221I772J1257D01*
G01Y1102294D01*
G03X341174Y1104149I-2225J-73D01*
G01X341139Y1104169D01*
G02X340436Y1105426I772J1257D01*
G01Y1105465D01*
G03X339324Y1107353I-2225J-39D01*
G01X339289Y1107373D01*
G02X338586Y1108630I772J1257D01*
G01Y1108669D01*
G03X337474Y1110557I-2225J-39D01*
G01Y1110558D01*
X337418Y1110590D01*
G02X336909Y1111142I794J1243D01*
G02X336736Y1111795I1301J694D01*
G01Y1112271D01*
X333672Y1115335D01*
X331620D01*
X330758Y1116197D01*
G01X380329Y909057D02*
G02X377019Y907419I-3069J2037D01*
G03X374552Y907310I-739J-11250D01*
G03X374041Y907130I226J-1457D01*
G01X373983Y907096D01*
G02X371815Y907130I-1054J1961D01*
G03X370341I-737J-1277D01*
G01X370283Y907096D01*
G02X368115Y907130I-1054J1961D01*
G03X366641I-737J-1277D01*
G01X366583Y907096D01*
G02X364415Y907130I-1054J1961D01*
G03X362941I-737J-1277D01*
G01X362883Y907096D01*
G02X360715Y907130I-1054J1961D01*
G03X358504Y905887I-737J-1277D01*
G01Y905814D01*
G02X355166Y903926I-2225J39D01*
G03X353692I-737J-1277D01*
G02X351524Y903892I-1114J1927D01*
G01X351466Y903926D01*
G03X349992I-737J-1277D01*
G02X347824Y903892I-1114J1927D01*
G01X347766Y903926D01*
G03X346292I-737J-1277D01*
G01X346251Y903902D01*
G02X344065Y903926I-1072J1952D01*
G03X341854Y902683I-737J-1277D01*
G01Y902649D01*
X341853Y902610D01*
G02X338516Y900723I-2224J40D01*
G03X337042I-737J-1277D01*
G01Y900722D01*
X337001Y900698D01*
G02X334817Y900722I-1071J1951D01*
G03X332604Y899445I-738J-1277D01*
G01X332603Y899446D01*
Y897914D01*
X325855Y891166D01*
X324723D01*
G01X382178Y912262D02*
X382177Y912261D01*
G02X379244Y910656I-4206J4204D01*
G02X378895Y910619I-345J1591D01*
G01X373241D01*
G03X372192Y910334I15J-2128D01*
G02X369966I-1113J1928D01*
G03X368492I-737J-1277D01*
G02X366324Y910300I-1115J1928D01*
G01X366266Y910334D01*
G03X364792I-737J-1277D01*
G02X362624Y910300I-1115J1928D01*
G01X362566Y910334D01*
G03X361092I-737J-1277D01*
G02X358906Y910310I-1114J1928D01*
G01X358865Y910334D01*
G03X357391I-737J-1277D01*
G03X356654Y909091I737J-1277D01*
G01Y909018D01*
G02X355542Y907130I-2225J39D01*
G01X355501Y907106D01*
G02X353315Y907130I-1072J1951D01*
G03X351841I-737J-1277D01*
G01X351783Y907096D01*
G02X349615Y907130I-1054J1961D01*
G03X348141I-737J-1277D01*
G01X348100Y907106D01*
G02X345916Y907130I-1071J1951D01*
G01X345873Y907155D01*
G03X344442Y907131I-694J-1301D01*
G01X344374Y907091D01*
G02X342215Y907130I-1044J1967D01*
G03X340741I-737J-1277D01*
G03X340004Y905887I737J-1277D01*
G01Y905853D01*
X340003Y905814D01*
G02X338892Y903927I-2225J39D01*
G02X336666I-1113J1927D01*
G03X335192I-737J-1277D01*
G01X335138Y903895D01*
G02X332966Y903926I-1058J1959D01*
G03X332229Y904126I-742J-1276D01*
G01X331580D01*
X330744Y903290D01*
Y900075D01*
X325755Y895086D01*
X324723D01*
G01X382178Y918670D02*
G03X380783Y918297I0J-2795D01*
G01X379193Y917380D01*
G02X377741Y917393I-715J1290D01*
G03X375539Y917406I-1112J-1927D01*
G01X375493Y917380D01*
G02X374041Y917393I-715J1290D01*
G02X372535Y918896I2061J3571D01*
G03X371850Y919927I-1458J-225D01*
G01X371815Y919947D01*
G03X370341I-737J-1277D01*
G01X370283Y919913D01*
G02X368115Y919947I-1053J1962D01*
G03X366641I-737J-1277D01*
G01X366583Y919913D01*
G02X364415Y919947I-1053J1962D01*
G03X362941I-737J-1277D01*
G01X362900Y919923D01*
G02X360716Y919947I-1071J1952D01*
G03X359242I-737J-1277D01*
G01X359201Y919923D01*
G02X357015Y919947I-1072J1952D01*
G03X355541I-737J-1277D01*
G01X355483Y919913D01*
G02X353315Y919947I-1053J1962D01*
G03X351841I-737J-1277D01*
G01X351783Y919913D01*
G02X349615Y919947I-1053J1962D01*
G03X348141I-737J-1277D01*
G03X347404Y918704I737J-1277D01*
G01Y918631D01*
G02X346292Y916743I-2225J39D01*
G02X344066I-1113J1927D01*
G01X344023Y916768D01*
G03X342592Y916744I-694J-1302D01*
G02X340366I-1113J1928D01*
G03X338935Y916768I-737J-1278D01*
G01X338892Y916743D01*
G02X336706Y916719I-1114J1928D01*
G01X336665Y916743D01*
X336637Y916759D01*
G03X335192Y916744I-709J-1293D01*
G01X335170Y916732D01*
G03X334453Y915466I759J-1266D01*
G01Y915427D01*
G02X332228Y913241I-2225J39D01*
G01X329660D01*
X328847Y912428D01*
Y908159D01*
X326054Y905366D01*
X325323D01*
G01X380329Y915466D02*
X381561D01*
X381786Y915241D01*
G02X379592Y914189I-1457J224D01*
G03X377424Y914223I-1114J-1927D01*
G01X377366Y914189D01*
G02X375892I-737J1277D01*
G03X373724Y914223I-1114J-1927D01*
G01X373666Y914189D01*
G02X372192I-737J1277D01*
G03X369966I-1113J-1927D01*
G02X368492I-737J1277D01*
G03X366324Y914223I-1114J-1927D01*
G01X366266Y914189D01*
G02X364792I-737J1277D01*
G03X362606Y914213I-1114J-1927D01*
G01X362565Y914189D01*
G02X361091I-737J1277D01*
G03X358907Y914213I-1113J-1927D01*
G01X358866Y914189D01*
G02X357392I-737J1277D01*
G03X354053Y912262I-1114J-1927D01*
G02X354052Y912204I-1475J-4D01*
G02X351841Y910985I-1474J59D01*
G01X351783Y911019D01*
G03X349615Y910985I-1053J-1962D01*
G02X348141I-737J1277D01*
G01X348100Y911009D01*
G03X345916Y910985I-1071J-1952D01*
G02X344442I-737J1277D01*
G03X342216I-1113J-1927D01*
G02X340742I-737J1277D01*
G03X337404Y909097I-1113J-1927D01*
G01Y909058D01*
G02X335192Y907781I-1475J0D01*
G01X335151Y907805D01*
G03X332965Y907781I-1072J-1951D01*
G02X332228Y907581I-742J1276D01*
G01X331633D01*
X328362Y904310D01*
Y901816D01*
X326537Y899991D01*
X325650D01*
X325415Y900226D01*
X325323D01*
G01X384029Y915466D02*
X382797D01*
X382539Y915208D01*
G02X381465Y913553I-2210J258D01*
G01X381444Y913541D01*
X381441Y913539D01*
X381383Y913505D01*
G02X379215Y913539I-1054J1961D01*
G03X377741I-737J-1277D01*
G01X377683Y913505D01*
G02X375515Y913539I-1054J1961D01*
G03X374041I-737J-1277D01*
G01X374000Y913515D01*
G02X371816Y913539I-1071J1951D01*
G03X370342I-737J-1277D01*
G01X370301Y913515D01*
G02X368115Y913539I-1072J1951D01*
G03X366641I-737J-1277D01*
G01X366583Y913505D01*
G02X364415Y913539I-1054J1961D01*
G03X362941I-737J-1277D01*
G02X360715I-1113J1927D01*
G03X359241I-737J-1277D01*
G01X359183Y913505D01*
G02X357015Y913539I-1054J1961D01*
G03X355541I-737J-1277D01*
G01X355535Y913536D01*
X355506Y913519D01*
G03X354803Y912262I772J-1257D01*
G01Y912175D01*
G02X351524Y910300I-2225J87D01*
G01X351466Y910334D01*
G03X349992I-737J-1277D01*
G02X347824Y910300I-1115J1928D01*
G01X347766Y910334D01*
G03X346292I-737J-1277D01*
G02X344120Y910303I-1114J1928D01*
G01X344066Y910335D01*
G03X342592I-737J-1277D01*
G02X340366I-1113J1927D01*
G03X338154Y909058I-737J-1277D01*
G01Y909019D01*
G02X334816Y907131I-2225J39D01*
G03X333342I-737J-1277D01*
G02X332228Y906832I-1114J1926D01*
G01X331944D01*
X329111Y903999D01*
Y901505D01*
X326848Y899242D01*
X325651D01*
X325415Y899006D01*
X325323D01*
G01X380329Y921875D02*
G02X377019Y920419I-6222J9654D01*
G02X375619Y920519I-553J2110D01*
G02X374385Y922101I799J1896D01*
G03X373700Y923132I-1458J-225D01*
G01X373665Y923152D01*
G03X372191I-737J-1277D01*
G02X370007Y923128I-1113J1927D01*
G01X369966Y923152D01*
G03X368492I-737J-1277D01*
G02X366324Y923118I-1114J1927D01*
G01X366266Y923152D01*
G03X364792I-737J-1277D01*
G02X362624Y923118I-1114J1927D01*
G01X362566Y923152D01*
G03X361092I-737J-1277D01*
G02X358924Y923118I-1114J1927D01*
G01X358866Y923152D01*
G03X357392I-737J-1277D01*
G02X355166I-1113J1927D01*
G03X353692I-737J-1277D01*
G02X351524Y923118I-1114J1927D01*
G01X351466Y923152D01*
G03X349992I-737J-1277D01*
G02X347824Y923118I-1114J1927D01*
G01X347766Y923152D01*
G03X346292I-737J-1277D01*
G01X346257Y923132D01*
G03X345554Y921875I772J-1257D01*
G01X345553Y921802D01*
G02X344442Y919948I-2225J73D01*
G02X342270Y919917I-1114J1928D01*
G01X342216Y919949D01*
G03X340785Y919973I-737J-1277D01*
G01X340742Y919948D01*
G02X338556Y919924I-1114J1927D01*
G01X338515Y919948D01*
G03X337075Y919967I-737J-1277D01*
G01X337042Y919948D01*
G02X334852Y919928I-1113J1928D01*
G01X334817Y919949D01*
G03X333386Y919973I-737J-1277D01*
G01X333343Y919948D01*
X333287Y919916D01*
G03X332605Y918672I794J-1244D01*
G02X330379Y916445I-2226J-1D01*
G01X327267Y913333D01*
Y910161D01*
X326392Y909286D01*
X325323D01*
G01X376629Y966735D02*
X377860D01*
X378086Y966961D01*
G03X377401Y967992I-1458J-225D01*
G01X377366Y968012D01*
X377342Y968026D01*
G02X376253Y969939I1136J1913D01*
G03X375550Y971196I-1475J0D01*
G01X375515Y971216D01*
G03X374041I-737J-1277D01*
G03X373304Y969973I737J-1277D01*
G01Y969900D01*
G02X372192Y968012I-2225J39D01*
G02X369966I-1113J1927D01*
G03X368492I-737J-1277D01*
G02X366306Y967988I-1114J1927D01*
G01X366265Y968012D01*
G03X364791I-737J-1277D01*
G02X362607Y967988I-1113J1927D01*
G01X362566Y968012D01*
G03X361092I-737J-1277D01*
G02X358906Y967988I-1114J1927D01*
G01X358865Y968012D01*
G03X357391I-737J-1277D01*
G02X355207Y967988I-1113J1927D01*
G01X355166Y968012D01*
G03X353692I-737J-1277D01*
G02X351524Y967978I-1114J1927D01*
G01X351466Y968012D01*
G03X349992I-737J-1277D01*
G02X347824Y967978I-1114J1927D01*
G01X347766Y968012D01*
G03X346292I-737J-1277D01*
G02X344066I-1113J1927D01*
G03X342592I-737J-1277D01*
G02X340366I-1113J1927D01*
G03X338892I-737J-1277D01*
G02X336666I-1113J1927D01*
G03X335192I-737J-1277D01*
G02X332966I-1113J1927D01*
G03X331492I-737J-1277D01*
G01X331357Y967877D01*
X330405D01*
X329737Y968545D01*
X329184Y969880D01*
Y970405D01*
X328507Y971082D01*
X327525D01*
G01X380762Y1076587D02*
X379531D01*
X379272Y1076328D01*
G02X378198Y1074674I-2210J259D01*
G01X378174Y1074660D01*
X378116Y1074626D01*
G02X375948Y1074660I-1054J1961D01*
G03X374474I-737J-1277D01*
G02X372248I-1113J1927D01*
G03X370774I-737J-1277D01*
G01X370716Y1074626D01*
G02X368548Y1074660I-1054J1961D01*
G03X367074I-737J-1277D01*
G01X367016Y1074626D01*
G02X364848Y1074660I-1054J1961D01*
G03X363374I-737J-1277D01*
G01X363316Y1074626D01*
G02X361148Y1074660I-1054J1961D01*
G03X359674I-737J-1277D01*
G01X359633Y1074636D01*
G02X357449Y1074660I-1071J1951D01*
G03X355975I-737J-1277D01*
G02X353789Y1074636I-1114J1927D01*
G01X353748Y1074660D01*
G03X352274I-737J-1277D01*
G02X350090Y1074636I-1113J1927D01*
G01X350049Y1074660D01*
X350025Y1074674D01*
G02X348936Y1076587I1136J1913D01*
G03X348233Y1077844I-1475J0D01*
G01X348198Y1077864D01*
G03X346724I-737J-1277D01*
G02X344498I-1113J1927D01*
G02X343386Y1079752I1113J1927D01*
G01Y1079791D01*
G03X342683Y1081048I-1475J0D01*
G01X342648Y1081068D01*
G03X341174I-737J-1277D01*
G02X339006Y1081034I-1114J1927D01*
G01X338948Y1081068D01*
X338924Y1081082D01*
G02X337835Y1082995I1136J1913D01*
G03X337132Y1084252I-1475J0D01*
G01X337097Y1084272D01*
G03X335623I-737J-1277D01*
G02X333397I-1113J1928D01*
G02X332285Y1086127I1113J1928D01*
G01Y1086200D01*
G03X331582Y1087457I-1475J0D01*
G01X331515D01*
X330658Y1088314D01*
Y1090078D01*
X330263Y1090473D01*
X329078D01*
X328123Y1091428D01*
G01X382611Y1079791D02*
X380413Y1078092D01*
X380086Y1077900D01*
G02X377846Y1077894I-1125J1921D01*
G03X376367Y1077889I-735J-1274D01*
G01X376266Y1077830D01*
G02X374098Y1077864I-1054J1961D01*
G03X372624I-737J-1277D01*
G02X370440Y1077840I-1113J1927D01*
G01X370399Y1077864D01*
G03X368925I-737J-1277D01*
G02X366757Y1077830I-1114J1927D01*
G01X366699Y1077864D01*
G03X365225I-737J-1277D01*
G02X363057Y1077830I-1114J1927D01*
G01X362999Y1077864D01*
G03X361525I-737J-1277D01*
G02X359299I-1113J1927D01*
G03X357825I-737J-1277D01*
G02X355639Y1077840I-1114J1927D01*
G01X355598Y1077864D01*
G03X354124I-737J-1277D01*
G02X351898I-1113J1927D01*
G02X350786Y1079752I1113J1927D01*
G01Y1079791D01*
G03X350083Y1081048I-1475J0D01*
G01X350048Y1081068D01*
G03X348574I-737J-1277D01*
G02X346348I-1113J1927D01*
G01X346300Y1081096D01*
G02X345235Y1082995I1161J1899D01*
G03X344532Y1084252I-1475J0D01*
G01X344497Y1084272D01*
G03X343023I-737J-1277D01*
G02X340797I-1113J1928D01*
G02X339685Y1086127I1113J1928D01*
G01Y1086200D01*
G03X338982Y1087457I-1475J0D01*
G01X338947Y1087477D01*
G03X337473I-737J-1277D01*
G01X337415Y1087443D01*
G02X333649Y1089695I-1210J2252D01*
G01Y1092986D01*
X330487Y1096148D01*
X328123D01*
G01X380762Y1082995D02*
X380760D01*
X379661Y1081929D01*
X378192Y1081079D01*
X378183Y1081073D01*
X378178Y1081070D01*
X378174Y1081068D01*
X378116Y1081034D01*
G02X375948Y1081068I-1054J1961D01*
G03X374474I-737J-1277D01*
G01X374416Y1081034D01*
G02X372248Y1081068I-1054J1961D01*
G03X370774I-737J-1277D01*
G01X370716Y1081034D01*
G02X368548Y1081068I-1054J1961D01*
G03X367074I-737J-1277D01*
G01X367016Y1081034D01*
G02X364848Y1081068I-1054J1961D01*
G03X363374I-737J-1277D01*
G02X361190Y1081044I-1113J1927D01*
G01X361149Y1081068D01*
G03X359675I-737J-1277D01*
G01X359634Y1081044D01*
G02X357448Y1081068I-1072J1951D01*
G03X355974I-737J-1277D01*
G02X353748I-1113J1927D01*
G02X352636Y1082956I1113J1927D01*
G01Y1082995D01*
G03X351933Y1084252I-1475J0D01*
G01X351901Y1084270D01*
X351898Y1084272D01*
G02X350786Y1086127I1113J1928D01*
G01Y1086200D01*
G03X350083Y1087457I-1475J0D01*
G01X350048Y1087477D01*
G03X348574I-737J-1277D01*
G01X348533Y1087453D01*
G02X346347Y1087477I-1072J1951D01*
G03X344873I-737J-1277D01*
G01X344815Y1087443D01*
G02X342647Y1087477I-1054J1961D01*
G02X341536Y1089343I1114J1927D01*
G01Y1089404D01*
G03X340833Y1090661I-1475J0D01*
G01X340798Y1090681D01*
G03X339324I-737J-1277D01*
G02X336732Y1090944I-1114J1928D01*
G02X336637Y1091033I1473J1668D01*
G01X335462Y1092209D01*
Y1093831D01*
X331101Y1098192D01*
Y1100867D01*
X330170Y1101798D01*
X329055D01*
X328819Y1101562D01*
X328727D01*
G01X380762Y1089404D02*
X379531D01*
X379272Y1089145D01*
G02X378198Y1087491I-2210J259D01*
G01X378174Y1087477D01*
X378116Y1087443D01*
G02X375948Y1087477I-1054J1961D01*
G02X374837Y1089343I1114J1927D01*
G01Y1089404D01*
G03X374134Y1090661I-1475J0D01*
G01X374099Y1090681D01*
G03X372625I-737J-1277D01*
G02X370457Y1090647I-1114J1927D01*
G01X370399Y1090681D01*
G03X368925I-737J-1277D01*
G02X366757Y1090647I-1114J1927D01*
G01X366699Y1090681D01*
G03X365225I-737J-1277D01*
G02X363057Y1090647I-1114J1927D01*
G01X362999Y1090681D01*
G03X361525I-737J-1277D01*
G02X359339Y1090657I-1114J1927D01*
G01X359298Y1090681D01*
G02X358186Y1092569I1113J1927D01*
G01Y1092642D01*
G03X357449Y1093885I-1474J-34D01*
G02X356336Y1095757I1112J1928D01*
G01Y1095813D01*
G03X355633Y1097070I-1475J0D01*
G01X355598Y1097090D01*
G02X354486Y1098978I1113J1927D01*
G01Y1099017D01*
G03X353783Y1100274I-1475J0D01*
G01X353748Y1100294D01*
G03X352274I-737J-1277D01*
G02X350048I-1113J1927D01*
G03X348574I-737J-1277D01*
G02X346348I-1113J1927D01*
G03X344874I-737J-1277D01*
G02X342648I-1113J1927D01*
G02X341536Y1102182I1113J1927D01*
G01Y1102221D01*
G03X340833Y1103478I-1475J0D01*
G01X340798Y1103498D01*
G02X339686Y1105353I1113J1928D01*
G01Y1105426D01*
G03X338983Y1106683I-1475J0D01*
G01X338948Y1106703D01*
G02X337836Y1108591I1113J1927D01*
G01Y1108630D01*
G03X337133Y1109887I-1475J0D01*
G01X337098Y1109907D01*
G02X335985Y1111797I1112J1928D01*
G01X335986Y1111836D01*
Y1111961D01*
X334262Y1113685D01*
X331141D01*
G01X382611Y1086200D02*
G03X381295Y1085854I-1J-2670D01*
G01X379626Y1084910D01*
G02X378174Y1084923I-715J1290D01*
G03X375972Y1084936I-1112J-1927D01*
G01X375926Y1084910D01*
G02X374474Y1084923I-715J1290D01*
G02X373736Y1085489I1782J3087D01*
G02X373451Y1085915I929J930D01*
G01X373339Y1086186D01*
G03X373081Y1086809I-881J0D01*
G01X372956Y1086935D01*
G03X372251Y1087476I-2405J-2405D01*
G01X372249Y1087477D01*
G03X370775I-737J-1277D01*
G01X370734Y1087453D01*
G02X368548Y1087477I-1072J1951D01*
G03X367074I-737J-1277D01*
G01X367016Y1087443D01*
G02X364848Y1087477I-1054J1961D01*
G03X363374I-737J-1277D01*
G01X363316Y1087443D01*
G02X361148Y1087477I-1054J1961D01*
G03X359674I-737J-1277D01*
G02X357448I-1113J1927D01*
G02X356336Y1089365I1113J1927D01*
G01Y1089404D01*
G03X355633Y1090661I-1475J0D01*
G01X355598Y1090681D01*
X355574Y1090695D01*
G02X354486Y1092608I1138J1913D01*
G03X353783Y1093865I-1475J0D01*
G01X353748Y1093885D01*
G02X352636Y1095740I1113J1928D01*
G01Y1095813D01*
G03X351933Y1097070I-1475J0D01*
G01X351898Y1097090D01*
G03X350424I-737J-1277D01*
G02X348198I-1113J1927D01*
G03X346724I-737J-1277D01*
G02X344498I-1113J1927D01*
G03X343024I-737J-1277D01*
G02X340798I-1113J1927D01*
G02X339686Y1098978I1113J1927D01*
G01Y1099017D01*
G03X338983Y1100274I-1475J0D01*
G01X338948Y1100294D01*
G02X337836Y1102182I1113J1927D01*
G01Y1102221D01*
G03X337133Y1103478I-1475J0D01*
G01X337098Y1103498D01*
G02X336637Y1103852I1114J1928D01*
G01X335558Y1104931D01*
Y1107458D01*
X334832Y1108184D01*
X332923D01*
G01X384462Y1082995D02*
X381617Y1084204D01*
X381507Y1084268D01*
X381499Y1084272D01*
G03X380025I-737J-1277D01*
G01X379990Y1084252D01*
G03X379287Y1082995I772J-1257D01*
G01Y1082611D01*
X379205Y1082532D01*
X377901Y1081777D01*
X377812Y1081726D01*
X377806Y1081722D01*
X377798Y1081718D01*
X377799D01*
G02X376325I-737J1277D01*
G03X374157Y1081752I-1114J-1927D01*
G01X374099Y1081718D01*
G02X372625I-737J1277D01*
G03X370457Y1081752I-1114J-1927D01*
G01X370399Y1081718D01*
G02X368925I-737J1277D01*
G03X366757Y1081752I-1114J-1927D01*
G01X366699Y1081718D01*
G02X365225I-737J1277D01*
G03X363039Y1081742I-1114J-1927D01*
G01X362998Y1081718D01*
G02X361524I-737J1277D01*
G01X361483Y1081742D01*
G03X359299Y1081718I-1071J-1951D01*
G02X357825I-737J1277D01*
G03X355639Y1081742I-1114J-1927D01*
G01X355598Y1081718D01*
G02X354124I-737J1277D01*
G01X354089Y1081738D01*
G02X353386Y1082995I772J1257D01*
G01Y1083068D01*
G03X352274Y1084923I-2225J-73D01*
G01X352239Y1084943D01*
G02X351536Y1086200I772J1257D01*
G01Y1086239D01*
G03X350424Y1088127I-2225J-39D01*
G03X348198I-1113J-1927D01*
G02X346724I-737J1277D01*
G03X344556Y1088161I-1114J-1927D01*
G01X344498Y1088127D01*
G02X343024I-737J1277D01*
G01X342989Y1088147D01*
G02X342286Y1089404I772J1257D01*
G01Y1089460D01*
G03X341173Y1091332I-2225J-56D01*
G01X341115Y1091366D01*
G03X338947Y1091332I-1053J-1962D01*
G02X337473I-737J1277D01*
G02X337166Y1091565I731J1282D01*
G01X336211Y1092520D01*
Y1094142D01*
X331850Y1098503D01*
Y1101178D01*
X330481Y1102547D01*
X329054D01*
X328819Y1102782D01*
X328727D01*
G01X375211Y1002888D02*
X372740Y1004749D01*
X372624Y1004815D01*
X372625Y1004816D01*
G03X370457Y1004850I-1115J-1928D01*
G01X370399Y1004816D01*
G02X368925I-737J1277D01*
G03X366757Y1004850I-1115J-1928D01*
G01X366699Y1004816D01*
G02X365225I-737J1277D01*
G03X363039Y1004840I-1114J-1928D01*
G01X362998Y1004816D01*
G02X361524I-737J1277D01*
G01X361483Y1004840D01*
G03X359299Y1004816I-1071J-1952D01*
G02X357825I-737J1277D01*
G03X355639Y1004840I-1114J-1928D01*
G01X355598Y1004816D01*
G02X354124I-737J1277D01*
G03X351940Y1004840I-1113J-1928D01*
G01X351899Y1004816D01*
G02X350425I-737J1277D01*
G03X348239Y1004840I-1114J-1928D01*
G01X348198Y1004816D01*
G02X346724I-737J1277D01*
G03X344498I-1113J-1928D01*
G02X343024I-737J1277D01*
G03X340798I-1113J-1928D01*
G02X339324I-737J1277D01*
G03X336637Y1004462I-1113J-1928D01*
G01X333701Y1001526D01*
X332421D01*
G01X382611Y1002888D02*
G02X380025Y1000961I-9545J10110D01*
G02X377857Y1000927I-1114J1927D01*
G01X377799Y1000961D01*
G03X376325I-737J-1277D01*
G02X374099I-1113J1927D01*
G01Y1000962D01*
G02X372986Y1002888I1112J1927D01*
G03X372249Y1004164I-1473J0D01*
G01X372248Y1004165D01*
G03X370774I-737J-1277D01*
G01X370716Y1004131D01*
G02X368548Y1004165I-1053J1962D01*
G03X367074I-737J-1277D01*
G01X367016Y1004131D01*
G02X364848Y1004165I-1053J1962D01*
G03X363374I-737J-1277D01*
G02X361190Y1004141I-1113J1928D01*
G01X361149Y1004165D01*
G03X359675I-737J-1277D01*
G01X359634Y1004141D01*
G02X357448Y1004165I-1072J1952D01*
G03X355974I-737J-1277D01*
G02X353748I-1113J1928D01*
G03X352274I-737J-1277D01*
G01X352216Y1004131D01*
G02X350048Y1004165I-1053J1962D01*
G03X348574I-737J-1277D01*
G02X346348I-1113J1928D01*
G03X344874I-737J-1277D01*
G02X342648I-1113J1928D01*
G03X341174I-737J-1277D01*
G02X338948I-1113J1928D01*
G03X337474I-737J-1277D01*
G03X337167Y1003932I731J-1282D01*
G01X334002Y1000767D01*
Y1000512D01*
X333046Y999556D01*
X332421D01*
G01X371078Y893036D02*
X372309D01*
X372535Y892810D01*
G02X371850Y891779I-1458J225D01*
G01X371815Y891759D01*
G02X370341I-737J1277D01*
G01X370283Y891793D01*
G03X368115Y891759I-1054J-1961D01*
G01X368116D01*
G03X367004Y889871I1113J-1927D01*
G01Y889832D01*
G02X366301Y888575I-1475J0D01*
G01X366266Y888555D01*
G02X364792I-737J1277D01*
G03X362624Y888589I-1115J-1928D01*
G01X362566Y888555D01*
G02X361092I-737J1277D01*
G03X358906Y888579I-1114J-1928D01*
G01X358865Y888555D01*
G02X357391I-737J1277D01*
G03X355207Y888579I-1113J-1928D01*
G01X355166Y888555D01*
G02X353692I-737J1277D01*
G03X351524Y888589I-1115J-1928D01*
G01X351466Y888555D01*
G03X350353Y886683I1112J-1928D01*
G01Y886593D01*
G02X349616Y885350I-1474J34D01*
G03X348504Y883462I1113J-1927D01*
G01Y883423D01*
G02X347801Y882166I-1475J0D01*
G01X347766Y882146D01*
G02X346292I-737J1277D01*
G03X344066I-1113J-1927D01*
G02X342592I-737J1277D01*
G03X340366I-1113J-1927D01*
G02X338892I-737J1277D01*
G01X338851Y882170D01*
G03X336665Y882146I-1072J-1951D01*
G02X335191I-737J1277D01*
G03X333009Y882170I-1112J-1927D01*
G01X332968Y882146D01*
G03X332506Y881792I1110J-1927D01*
G01X330005Y879291D01*
Y875805D01*
X327417Y873217D01*
X324723D01*
G01X382178Y893036D02*
G02X379896Y891284I-7800J7797D01*
G01X379592Y891109D01*
G02X377366I-1113J1927D01*
G03X375892I-737J-1277D01*
G01X375857Y891089D01*
G03X375154Y889832I772J-1257D01*
G01Y889776D01*
G02X374041Y887904I-2225J56D01*
G01X373983Y887870D01*
G02X371815Y887904I-1053J1962D01*
G03X370341I-737J-1277D01*
G01X370306Y887884D01*
G03X369603Y886627I772J-1257D01*
G01Y886566D01*
G02X368492Y884700I-2225J61D01*
G01X368457Y884680D01*
G03X367754Y883423I772J-1257D01*
G01Y883384D01*
G02X366642Y881496I-2225J39D01*
G01X366601Y881472D01*
G02X364415Y881496I-1072J1951D01*
G02X363304Y883362I1114J1927D01*
G01Y883423D01*
G03X362601Y884680I-1475J0D01*
G01X362566Y884700D01*
G03X361092I-737J-1277D01*
G01X361057Y884680D01*
G03X360354Y883423I772J-1257D01*
G01Y883384D01*
G02X359242Y881496I-2225J39D01*
G01X359201Y881472D01*
G02X357015Y881496I-1072J1951D01*
G02X355904Y883362I1114J1927D01*
G01Y883423D01*
G03X355201Y884680I-1475J0D01*
G01X355166Y884700D01*
G03X353692I-737J-1277D01*
G01X353657Y884680D01*
G03X352954Y883423I772J-1257D01*
G01Y883384D01*
G02X351842Y881496I-2225J39D01*
G01X351807Y881476D01*
G03X351104Y880219I772J-1257D01*
G01Y880163D01*
G02X349992Y878291I-2226J56D01*
G02X347824Y878257I-1115J1928D01*
G01X347766Y878291D01*
X347733Y878310D01*
G03X346293Y878291I-703J-1296D01*
G02X344107Y878267I-1114J1928D01*
G01X344066Y878291D01*
G03X342592I-737J-1277D01*
G02X340366I-1113J1928D01*
G03X338892I-737J-1277D01*
G01X338851Y878267D01*
G02X336665Y878291I-1072J1952D01*
G03X334453Y877014I-737J-1277D01*
G01Y871004D01*
X328458Y865009D01*
G01X372929Y896240D02*
X372804Y896696D01*
X372651Y896783D01*
G03X372042Y896944I-609J-1071D01*
G01X370965D01*
X369968Y897518D01*
X369967Y897517D01*
G03X368493I-737J-1277D01*
G01X368492D01*
G02X366324Y897483I-1115J1928D01*
G01X366266Y897517D01*
G03X364792I-737J-1277D01*
G01X364757Y897497D01*
G03X364054Y896240I772J-1257D01*
G02X362966Y894327I-2226J0D01*
G01X362942Y894313D01*
G02X360774Y894279I-1114J1927D01*
G01X360716Y894313D01*
G03X359242I-737J-1277D01*
G01X359201Y894289D01*
G02X357015Y894313I-1072J1951D01*
G03X355541I-737J-1277D01*
G01X355483Y894279D01*
G02X353315Y894313I-1054J1961D01*
G03X351841I-737J-1277D01*
G01X351783Y894279D01*
G02X349615Y894313I-1054J1961D01*
G03X348141I-737J-1277D01*
G03X347404Y893070I737J-1277D01*
G01Y892997D01*
G02X346292Y891109I-2225J39D01*
G01X346257Y891089D01*
G03X345554Y889832I772J-1257D01*
G01Y889776D01*
G02X344442Y887904I-2226J56D01*
G02X342274Y887870I-1115J1928D01*
G01X342216Y887904D01*
G03X340742I-737J-1277D01*
G02X338516I-1113J1928D01*
G03X337042I-737J-1277D01*
G02X334874Y887870I-1115J1928D01*
G01X334777Y887927D01*
X334769Y887931D01*
G03X333340Y887904I-690J-1304D01*
G03X333287Y887872I736J-1280D01*
G03X333033Y887671I784J-1252D01*
G01X327757Y882395D01*
Y879845D01*
X326533Y878621D01*
X325050D01*
X324815Y878386D01*
X324723D01*
G01X376629Y902649D02*
G02X373706Y903902I3540J12294D01*
G01X373665Y903926D01*
G03X372191I-737J-1277D01*
G02X370007Y903902I-1113J1927D01*
G01X369966Y903926D01*
G03X368492I-737J-1277D01*
G02X366324Y903892I-1114J1927D01*
G01X366266Y903926D01*
G03X364792I-737J-1277D01*
G02X362624Y903892I-1114J1927D01*
G01X362566Y903926D01*
G03X361092I-737J-1277D01*
G01X361057Y903906D01*
G03X360354Y902649I772J-1257D01*
G01Y902610D01*
G02X359242Y900722I-2225J39D01*
G01X359201Y900698D01*
G02X357015Y900722I-1072J1951D01*
G03X355541I-737J-1277D01*
G01X355483Y900688D01*
G02X353315Y900722I-1054J1961D01*
G03X351841I-737J-1277D01*
G01X351783Y900688D01*
G02X349615Y900722I-1054J1961D01*
G03X348141I-737J-1277D01*
G01X348100Y900698D01*
G02X345916Y900722I-1071J1951D01*
G03X344442I-737J-1277D01*
G01X344407Y900702D01*
G03X343704Y899445I772J-1257D01*
G01X343703Y899389D01*
G02X342591Y897518I-2225J56D01*
G03X341854Y896301I737J-1278D01*
G01Y896240D01*
G02X340765Y894327I-2225J0D01*
G01X340741Y894313D01*
X340700Y894289D01*
G02X338516Y894313I-1071J1951D01*
G03X337042I-737J-1277D01*
G02X334856Y894289I-1114J1927D01*
G01X334815Y894313D01*
G03X333375Y894332I-737J-1277D01*
G01X333342Y894313D01*
G03X333035Y894079I733J-1279D01*
G01X330239Y891283D01*
Y890070D01*
X325655Y885486D01*
X324723D01*
G01X374778Y899445D02*
G03X372191Y901372I-9531J-10095D01*
G03X370007Y901396I-1113J-1927D01*
G01X369966Y901372D01*
G02X368492I-737J1277D01*
G03X366324Y901406I-1114J-1927D01*
G01X366266Y901372D01*
G02X364792I-737J1277D01*
G03X362624Y901406I-1114J-1927D01*
G01X362566Y901372D01*
X362542Y901358D01*
G03X361453Y899445I1136J-1913D01*
G01Y899411D01*
G02X360716Y898168I-1474J34D01*
G02X359242I-737J1277D01*
G01X359201Y898192D01*
G03X357015Y898168I-1072J-1952D01*
G02X355541I-737J1277D01*
G01X355483Y898202D01*
G03X353315Y898168I-1053J-1962D01*
G02X351841I-737J1277D01*
G01X351783Y898202D01*
G03X349615Y898168I-1053J-1962D01*
G02X348141I-737J1277D01*
G01X348100Y898192D01*
G03X345916Y898168I-1071J-1952D01*
G03X344803Y896270I1113J-1928D01*
G01Y896240D01*
G02X344100Y894983I-1475J0D01*
G01X344065Y894963D01*
X344041Y894949D01*
G03X342953Y893036I1138J-1913D01*
G02X342250Y891779I-1475J0D01*
G01X342215Y891759D01*
G02X340741I-737J1277D01*
G01X340700Y891783D01*
G03X338516Y891759I-1071J-1951D01*
G02X337042I-737J1277D01*
G03X334856Y891783I-1114J-1927D01*
G02X334078Y891560I-780J1252D01*
G01X332665D01*
X331200Y890095D01*
Y889126D01*
X325600Y883526D01*
X324723D01*
G01X376629Y896240D02*
G02X375289Y896594I-1J2708D01*
G01X373615Y897546D01*
G03X372810Y897710I-648J-1121D01*
G01X372585Y897683D01*
X372566Y897693D01*
X371166D01*
X370286Y898200D01*
G03X368116Y898167I-1055J-1960D01*
G01X368115Y898168D01*
G02X366641I-737J1277D01*
G01X366583Y898202D01*
G03X364415Y898168I-1053J-1962D01*
G03X363303Y896296I1114J-1928D01*
G01Y896240D01*
G02X362600Y894983I-1475J0D01*
G01X362565Y894963D01*
G02X361091I-737J1277D01*
G01X361050Y894987D01*
G03X358866Y894963I-1071J-1951D01*
G02X357392I-737J1277D01*
G03X355224Y894997I-1114J-1927D01*
G01X355166Y894963D01*
G02X353692I-737J1277D01*
G03X351524Y894997I-1114J-1927D01*
G01X351466Y894963D01*
G02X349992I-737J1277D01*
G03X347824Y894997I-1114J-1927D01*
G01X347766Y894963D01*
X347742Y894949D01*
G03X346653Y893036I1136J-1913D01*
G01Y893002D01*
G02X345916Y891759I-1474J34D01*
G01X345868Y891731D01*
G03X344803Y889832I1161J-1899D01*
G02X344100Y888575I-1475J0D01*
G01X344065Y888555D01*
G02X342591I-737J1277D01*
G01X342550Y888579D01*
G03X340366Y888555I-1071J-1952D01*
G02X338892I-737J1277D01*
G01X338851Y888579D01*
G03X336665Y888555I-1072J-1952D01*
G02X335191I-737J1277D01*
G01X335175Y888565D01*
X335120Y888596D01*
G03X332964Y888552I-1038J-1969D01*
G03X332889Y888507I1108J-1931D01*
G03X332504Y888203I1179J-1889D01*
G01X332503Y888201D01*
X327008Y882706D01*
Y880156D01*
X326222Y879370D01*
X325051D01*
X324815Y879606D01*
X324723D01*
G01X376629Y928283D02*
G02X374533Y927292I-2488J2550D01*
G03X373724Y927040I245J-2213D01*
G01X373666Y927006D01*
G02X372192I-737J1277D01*
G03X370024Y927040I-1114J-1927D01*
G01X369966Y927006D01*
G02X368492I-737J1277D01*
G03X366324Y927040I-1114J-1927D01*
G01X366266Y927006D01*
G02X364792I-737J1277D01*
G03X362624Y927040I-1114J-1927D01*
G01X362566Y927006D01*
G02X361092I-737J1277D01*
G03X358906Y927030I-1114J-1927D01*
G01X358865Y927006D01*
G02X357391I-737J1277D01*
G01X357350Y927030D01*
G03X355166Y927006I-1071J-1951D01*
G02X353692I-737J1277D01*
G03X351524Y927040I-1114J-1927D01*
G01X351466Y927006D01*
G02X349992I-737J1277D01*
G03X347824Y927040I-1114J-1927D01*
G01X347766Y927006D01*
G02X346335Y926982I-737J1277D01*
G01X346292Y927007D01*
G03X344066I-1113J-1927D01*
G01X344018Y926979D01*
G03X342953Y925079I1161J-1899D01*
G02X342271Y923835I-1476J0D01*
G01X342215Y923803D01*
X342172Y923778D01*
G02X340741Y923802I-694J1301D01*
G01X340706Y923823D01*
G03X338516Y923803I-1077J-1948D01*
G01X338483Y923784D01*
G02X337043Y923803I-703J1296D01*
G01X337002Y923827D01*
G03X334816Y923803I-1072J-1951D01*
G02X333374Y923784I-738J1277D01*
G01X333270Y923844D01*
G03X330654Y923450I-1041J-1969D01*
G01X330287Y923083D01*
X329795Y921895D01*
Y920137D01*
X326584Y916926D01*
X325324D01*
G01X374778Y931488D02*
G03X371816Y930211I3980J-13306D01*
G02X370342I-737J1277D01*
G01X370301Y930235D01*
G03X368115Y930211I-1072J-1952D01*
G02X366641I-737J1277D01*
G01X366583Y930245D01*
G03X364415Y930211I-1053J-1962D01*
G02X362941I-737J1277D01*
G01X362883Y930245D01*
G03X360715Y930211I-1053J-1962D01*
G02X359241I-737J1277D01*
G03X357015I-1113J-1928D01*
G02X355541I-737J1277D01*
G01X355483Y930245D01*
G03X353315Y930211I-1053J-1962D01*
G02X351841I-737J1277D01*
G01X351800Y930235D01*
G03X349616Y930211I-1071J-1952D01*
G02X348142I-737J1277D01*
G03X345916I-1113J-1928D01*
G02X344442I-737J1277D01*
G03X342216I-1113J-1927D01*
G03X341104Y928323I1113J-1927D01*
G01Y928284D01*
G02X340379Y927014I-1475J0D01*
G01X340366Y927007D01*
X340333Y926988D01*
G02X338893Y927007I-703J1296D01*
G03X336667I-1113J-1927D01*
G01X336634Y926988D01*
G02X335192Y927007I-704J1296D01*
G03X333006Y927031I-1114J-1927D01*
G02X332228Y926808I-780J1252D01*
G01X331423D01*
X328873Y924258D01*
Y923756D01*
X327944Y921513D01*
X327277Y920846D01*
X325324D01*
G01X372929Y934691D02*
X372804Y935147D01*
X372651Y935234D01*
G03X372042Y935395I-609J-1071D01*
G01X370965D01*
X369968Y935969D01*
X369967Y935968D01*
G03X368493I-737J-1277D01*
G01X368492D01*
G02X366324Y935934I-1115J1928D01*
G01X366266Y935968D01*
G03X364792I-737J-1277D01*
G02X362606Y935944I-1114J1928D01*
G01X362565Y935968D01*
Y935969D01*
G03X361091I-737J-1277D01*
G01X361050Y935945D01*
G02X358866Y935969I-1071J1951D01*
G03X357392I-737J-1277D01*
G02X355224Y935935I-1114J1927D01*
G01X355166Y935969D01*
G03X353692I-737J-1277D01*
G01Y935968D01*
G02X351524Y935934I-1115J1928D01*
G01X351466Y935968D01*
G03X349992I-737J-1277D01*
G02X347824Y935934I-1115J1928D01*
G01X347766Y935968D01*
G03X346292I-737J-1277D01*
G02X344100Y935948I-1114J1928D01*
G01X344065Y935969D01*
G03X342591I-737J-1277D01*
G02X340407Y935945I-1113J1927D01*
G01X340366Y935969D01*
G03X338154Y934692I-737J-1277D01*
G02X337103Y932802I-2225J0D01*
G01X337042Y932765D01*
G02X334874Y932731I-1114J1927D01*
G01X334816Y932765D01*
G03X333342I-737J-1277D01*
G02X331158Y932741I-1113J1927D01*
G01X331159Y932742D01*
G03X331008Y932814I-710J-1295D01*
G01X330861D01*
X329494Y931447D01*
Y930077D01*
X329183Y929766D01*
Y927967D01*
X327459Y926243D01*
X326451D01*
X326216Y926008D01*
X326124D01*
G01X376629Y934691D02*
G02X375289Y935045I-1J2708D01*
G01X373615Y935997D01*
G03X372810Y936161I-648J-1121D01*
G01X372585Y936134D01*
X372566Y936144D01*
X371166D01*
X370286Y936651D01*
G03X368116Y936618I-1055J-1960D01*
G01X368115Y936619D01*
G02X366641I-737J1277D01*
G01X366583Y936653D01*
G03X364415Y936619I-1053J-1962D01*
G02X362941I-737J1277D01*
G03X360757Y936643I-1113J-1927D01*
G01X360716Y936619D01*
G02X359242I-737J1277D01*
G01X359201Y936643D01*
G03X357015Y936619I-1072J-1951D01*
G02X355541I-737J1277D01*
G01X355483Y936653D01*
G03X353315Y936619I-1054J-1961D01*
G02X351841I-737J1277D01*
G01X351783Y936653D01*
G03X349615Y936619I-1053J-1962D01*
G02X348141I-737J1277D01*
G01X348100Y936643D01*
G03X345916Y936619I-1071J-1952D01*
G02X344442I-737J1277D01*
G03X342256Y936643I-1114J-1927D01*
G01X342215Y936619D01*
G02X340741I-737J1277D01*
G03X337403Y934692I-1113J-1927D01*
G02X335191Y933415I-1475J0D01*
G01X335133Y933449D01*
G03X332965Y933415I-1054J-1961D01*
G02X331519Y933399I-737J1277D01*
G03X331141Y933563I-1071J-1951D01*
G01X330550D01*
X328745Y931758D01*
Y930388D01*
X328434Y930077D01*
Y928278D01*
X327148Y926992D01*
X326452D01*
X326216Y927228D01*
X326124D01*
G01X376629Y947509D02*
X377860D01*
X378086Y947283D01*
G02X377401Y946252I-1458J225D01*
G01X377366Y946232D01*
G02X375892I-737J1277D01*
G03X373724Y946266I-1115J-1928D01*
G01X373666Y946232D01*
G02X372192I-737J1277D01*
G03X370024Y946266I-1115J-1928D01*
G01X369966Y946232D01*
G02X368492I-737J1277D01*
G03X366324Y946266I-1115J-1928D01*
G01X366266Y946232D01*
G02X364792I-737J1277D01*
G03X362624Y946266I-1115J-1928D01*
G01X362566Y946232D01*
G02X361092I-737J1277D01*
G03X358906Y946256I-1114J-1928D01*
G01X358865Y946232D01*
G02X357391I-737J1277D01*
G01X357350Y946256D01*
G03X355166Y946232I-1071J-1952D01*
G02X353692I-737J1277D01*
G03X351524Y946266I-1115J-1928D01*
G01X351466Y946232D01*
G02X349992I-737J1277D01*
G03X347824Y946266I-1115J-1928D01*
G01X347766Y946232D01*
X347733Y946213D01*
G02X346291Y946232I-704J1296D01*
G03X344103Y946256I-1115J-1928D01*
G01X344062Y946232D01*
G02X342622Y946213I-737J1277D01*
G01X342589Y946232D01*
X342507Y946280D01*
G03X340363Y946232I-1028J-1976D01*
G02X338934Y946205I-739J1277D01*
G01X338887Y946232D01*
X338846Y946256D01*
G03X336660Y946232I-1072J-1952D01*
G02X335186I-737J1277D01*
G01X335145Y946256D01*
G03X332959Y946232I-1072J-1952D01*
G03X332498Y945879I1112J-1930D01*
G01X330794Y944175D01*
X330026Y942322D01*
X327866Y940162D01*
X327124D01*
G01X376629Y941100D02*
G03X374089Y942999I-9569J-10151D01*
G01X374041Y943027D01*
G03X371815I-1113J-1927D01*
G02X370341I-737J1277D01*
G01X370283Y943061D01*
G03X368115Y943027I-1054J-1961D01*
G02X366641I-737J1277D01*
G01X366583Y943061D01*
G03X364415Y943027I-1054J-1961D01*
G02X362941I-737J1277D01*
G01X362883Y943061D01*
G03X360715Y943027I-1054J-1961D01*
G02X359241I-737J1277D01*
G01X359200Y943051D01*
G03X357016Y943027I-1071J-1951D01*
G02X355542I-737J1277D01*
G01X355501Y943051D01*
G03X353315Y943027I-1072J-1951D01*
G02X351841I-737J1277D01*
G01X351783Y943061D01*
G03X349615Y943027I-1054J-1961D01*
G02X348141I-737J1277D01*
G01X348083Y943061D01*
G03X345915Y943027I-1054J-1961D01*
G02X344441I-737J1277D01*
G01X344383Y943061D01*
G03X342215Y943027I-1054J-1961D01*
G02X340741I-737J1277D01*
G01X340683Y943061D01*
G03X338515Y943027I-1054J-1961D01*
G02X337041I-737J1277D01*
G01X336983Y943061D01*
G03X334815Y943027I-1054J-1961D01*
G03X333704Y941161I1114J-1927D01*
G01Y941100D01*
X333705D01*
Y941069D01*
G02X332229Y939625I-1476J32D01*
G01X330305D01*
X327347Y936667D01*
Y935417D01*
X326998Y935068D01*
X326124D01*
G01X374778Y937896D02*
G03X372191Y939823I-9531J-10095D01*
G03X370007Y939847I-1113J-1927D01*
G01X369966Y939823D01*
G02X368492I-737J1277D01*
G03X366324Y939857I-1114J-1927D01*
G01X366266Y939823D01*
G02X364792I-737J1277D01*
G03X362624Y939857I-1114J-1927D01*
G01X362566Y939823D01*
G02X361092I-737J1277D01*
G03X358866I-1113J-1927D01*
G02X357392I-737J1277D01*
G03X355224Y939857I-1114J-1927D01*
G01X355166Y939823D01*
G02X353692I-737J1277D01*
G03X351524Y939857I-1114J-1927D01*
G01X351466Y939823D01*
G02X349992I-737J1277D01*
G03X347824Y939857I-1114J-1927D01*
G01X347766Y939823D01*
G02X346292I-737J1277D01*
G03X344066I-1113J-1927D01*
G02X342592I-737J1277D01*
G01X342534Y939857D01*
G03X340366Y939823I-1054J-1961D01*
G02X338892I-737J1277D01*
G01X338834Y939857D01*
G03X336666Y939823I-1054J-1961D01*
G03X335555Y937957I1114J-1927D01*
G01Y937896D01*
G02X334865Y936647I-1475J0D01*
G01X334816Y936619D01*
X334769Y936592D01*
G02X333342Y936619I-689J1304D01*
G03X332228Y936918I-1114J-1926D01*
G01X329971D01*
X329020Y935967D01*
Y934184D01*
X327164Y932328D01*
Y931497D01*
X326815Y931148D01*
X326124D01*
G01X374778Y950713D02*
G02X372753Y949729I-2435J2435D01*
G01X372663Y949718D01*
G03X371816Y949436I265J-2209D01*
G02X370342I-737J1277D01*
G01X370301Y949460D01*
G03X368115Y949436I-1072J-1951D01*
G02X366641I-737J1277D01*
G01X366583Y949470D01*
G03X364415Y949436I-1054J-1961D01*
G02X362941I-737J1277D01*
G01X362883Y949470D01*
G03X360715Y949436I-1054J-1961D01*
G02X359241I-737J1277D01*
G03X357015I-1113J-1927D01*
G02X355541I-737J1277D01*
G01X355483Y949470D01*
G03X353315Y949436I-1054J-1961D01*
G02X351841I-737J1277D01*
G01X351783Y949470D01*
G03X349615Y949436I-1054J-1961D01*
G02X348141I-737J1277D01*
G01X348100Y949460D01*
G03X345916Y949436I-1071J-1951D01*
G02X344442I-737J1277D01*
G03X342216I-1113J-1927D01*
G02X340742I-737J1277D01*
G01X340701Y949460D01*
G03X338515Y949436I-1072J-1951D01*
G02X337041I-737J1277D01*
G01X336983Y949470D01*
G03X334815Y949436I-1054J-1961D01*
G02X334079Y949237I-740J1277D01*
G01X332982D01*
X329016Y945271D01*
Y944845D01*
X328296Y944125D01*
X327124D01*
G01X372929Y953917D02*
X372804Y954373D01*
X372651Y954460D01*
G03X372042Y954621I-609J-1071D01*
G01X370965D01*
X369968Y955195D01*
X369967Y955194D01*
G03X368493I-737J-1277D01*
G01X368492D01*
G02X366324Y955160I-1115J1928D01*
G01X366266Y955194D01*
G03X364792I-737J-1277D01*
G02X362624Y955160I-1115J1928D01*
G01X362566Y955194D01*
Y955195D01*
G03X361127Y955215I-737J-1277D01*
G01X361093Y955196D01*
G02X358864I-1114J1926D01*
G01X358832Y955215D01*
G03X357390Y955195I-703J-1297D01*
G02X355163Y955196I-1113J1927D01*
G01X355117Y955224D01*
G03X353691Y955195I-687J-1306D01*
G02X351463Y955196I-1113J1927D01*
G01X351417Y955224D01*
G03X349991Y955195I-687J-1306D01*
G02X347763Y955196I-1113J1927D01*
G01X347731Y955215D01*
G03X346291Y955195I-702J-1297D01*
G01X346293Y955194D01*
G02X344065I-1114J1928D01*
G03X342591I-737J-1277D01*
G01X342550Y955170D01*
G02X340366Y955194I-1071J1952D01*
G03X338892I-737J-1277D01*
G01X338851Y955170D01*
G02X336665Y955194I-1072J1952D01*
G03X335191I-737J-1277D01*
G01X335133Y955160D01*
G02X332965Y955194I-1053J1962D01*
G03X331491I-737J-1277D01*
G03X331184Y954961I731J-1282D01*
G01X330725Y954502D01*
Y951845D01*
X328433Y949553D01*
X327451D01*
X327216Y949318D01*
X327124D01*
G01X376629Y953917D02*
G02X375289Y954271I-1J2708D01*
G01X373615Y955223D01*
G03X372810Y955387I-648J-1121D01*
G01X372585Y955360D01*
X372566Y955370D01*
X371166D01*
X370286Y955877D01*
G03X368116Y955844I-1055J-1960D01*
G01X368115Y955845D01*
G02X366641I-737J1277D01*
G01X366583Y955879D01*
G03X364415Y955845I-1053J-1962D01*
G02X362941I-737J1277D01*
G03X360757Y955869I-1113J-1927D01*
G01X360716Y955845D01*
G02X359242I-737J1277D01*
G01X359201Y955869D01*
G03X357015Y955845I-1072J-1951D01*
G02X355541I-737J1277D01*
G01X355483Y955879D01*
G03X353315Y955845I-1054J-1961D01*
G02X351841I-737J1277D01*
G01X351783Y955879D01*
G03X349615Y955845I-1054J-1961D01*
G02X348141I-737J1277D01*
G01X348100Y955869D01*
G03X345916Y955845I-1071J-1951D01*
G02X344442I-737J1277D01*
G03X342274Y955879I-1115J-1928D01*
G01X342216Y955845D01*
G02X340742I-737J1277D01*
G03X338516I-1113J-1928D01*
G02X337042I-737J1277D01*
G03X334874Y955879I-1115J-1928D01*
G01X334816Y955845D01*
G02X333342I-737J1277D01*
G03X330654Y955491I-1113J-1928D01*
G01X329976Y954813D01*
Y952156D01*
X328122Y950302D01*
X327452D01*
X327216Y950538D01*
X327124D01*
G01X376629Y960326D02*
X376470Y960167D01*
X375313D01*
X375154Y960326D01*
G03X374089Y962225I-2226J0D01*
G01X374041Y962253D01*
G03X371815I-1113J-1927D01*
G02X370341I-737J1277D01*
G01X370283Y962287D01*
G03X368115Y962253I-1054J-1961D01*
G02X366641I-737J1277D01*
G01X366600Y962277D01*
G03X364416Y962253I-1071J-1951D01*
G02X362942I-737J1277D01*
G01X362901Y962277D01*
G03X360715Y962253I-1072J-1951D01*
G02X359241I-737J1277D01*
G01X359200Y962277D01*
G03X357016Y962253I-1071J-1951D01*
G02X355542I-737J1277D01*
G01X355501Y962277D01*
G03X353315Y962253I-1072J-1951D01*
G02X351841I-737J1277D01*
G01X351783Y962287D01*
G03X349615Y962253I-1054J-1961D01*
G02X348141I-737J1277D01*
G01X348083Y962287D01*
G03X345915Y962253I-1054J-1961D01*
G02X344441I-737J1277D01*
G03X342215I-1113J-1927D01*
G02X340741I-737J1277D01*
G03X338515I-1113J-1927D01*
G02X337041I-737J1277D01*
G03X334815I-1113J-1927D01*
G02X333341I-737J1277D01*
G03X331592Y962459I-1114J-1927D01*
G01X327124D01*
G01X374778Y957122D02*
X374777D01*
G03X372602Y958807I-7720J-7719D01*
G01X372191Y959049D01*
X372168Y959062D01*
G03X369966Y959049I-1090J-1940D01*
G02X368514Y959036I-737J1277D01*
G01X368468Y959062D01*
G03X366266Y959049I-1090J-1940D01*
G02X364814Y959036I-737J1277D01*
G01X364768Y959062D01*
G03X362566Y959049I-1090J-1940D01*
G02X361114Y959036I-737J1277D01*
G01X361068Y959062D01*
G03X358866Y959049I-1090J-1940D01*
G02X357414Y959036I-737J1277D01*
G01X357368Y959062D01*
G03X355166Y959049I-1090J-1940D01*
G02X353714Y959036I-737J1277D01*
G01X353668Y959062D01*
G03X351466Y959049I-1090J-1940D01*
G02X350014Y959036I-737J1277D01*
G01X349991Y959049D01*
X349973Y959059D01*
G03X347766Y959049I-1095J-1937D01*
G02X346292I-737J1277D01*
G01X346251Y959073D01*
G03X344065Y959049I-1072J-1951D01*
G02X342591I-737J1277D01*
G01X342533Y959083D01*
G03X340365Y959049I-1054J-1961D01*
G02X338891I-737J1277D01*
G01X338833Y959083D01*
G03X336665Y959049I-1054J-1961D01*
G02X335191I-737J1277D01*
G01X335133Y959083D01*
G03X332965Y959049I-1054J-1961D01*
G02X331491I-737J1277D01*
G01X331138Y959253D01*
X330596D01*
X329760Y958417D01*
X327124D01*
G01X377062Y999684D02*
X378294D01*
X378519Y999459D01*
G02X377847Y998435I-1458J224D01*
G01X377798Y998407D01*
X377751Y998380D01*
G02X376324Y998407I-689J1304D01*
G03X374156Y998441I-1114J-1927D01*
G01X374098Y998407D01*
G02X372624I-737J1277D01*
G02X371887Y999650I737J1277D01*
G01Y999684D01*
G03X370798Y1001597I-2225J0D01*
G01X370774Y1001611D01*
X370716Y1001645D01*
G03X368548Y1001611I-1054J-1961D01*
G02X367074I-737J1277D01*
G01X367016Y1001645D01*
G03X364848Y1001611I-1054J-1961D01*
G02X363374I-737J1277D01*
G01X363333Y1001635D01*
G03X361149Y1001611I-1071J-1951D01*
G02X359675I-737J1277D01*
G01X359634Y1001635D01*
G03X357448Y1001611I-1072J-1951D01*
G02X355974I-737J1277D01*
G03X353748I-1113J-1927D01*
G02X352274I-737J1277D01*
G03X350048I-1113J-1927D01*
G02X348574I-737J1277D01*
G03X346348I-1113J-1927D01*
G02X344874I-737J1277D01*
G03X342648I-1113J-1927D01*
G02X341174I-737J1277D01*
G03X338948I-1113J-1927D01*
G03X338695Y1001441I1112J-1928D01*
G03X337665Y1000535I6487J-8413D01*
G01X334703Y997571D01*
X332421D01*
G01X380762Y999684D02*
X379530D01*
X379272Y999426D01*
G02X378198Y997771I-2210J258D01*
G01X378174Y997757D01*
X378116Y997723D01*
G02X375948Y997757I-1054J1961D01*
G03X374506Y997776I-738J-1277D01*
G01X374473Y997757D01*
X374415Y997723D01*
G02X372247Y997757I-1054J1961D01*
G02X371136Y999623I1114J1927D01*
G01Y999718D01*
G03X370399Y1000961I-1474J-34D01*
G03X368925I-737J-1277D01*
G02X366757Y1000927I-1114J1927D01*
G01X366699Y1000961D01*
G03X365225I-737J-1277D01*
G02X363057Y1000927I-1114J1927D01*
G01X362999Y1000961D01*
G03X361525I-737J-1277D01*
G02X359299I-1113J1927D01*
G03X357825I-737J-1277D01*
G02X355639Y1000937I-1114J1927D01*
G01X355598Y1000961D01*
G03X354124I-737J-1277D01*
G02X351898I-1113J1927D01*
G03X350424I-737J-1277D01*
G02X348198I-1113J1927D01*
G03X346724I-737J-1277D01*
G02X344498I-1113J1927D01*
G03X343024I-737J-1277D01*
G02X340798I-1113J1927D01*
G03X339324I-737J-1277D01*
G03X339017Y1000728I731J-1282D01*
G01X333894Y995605D01*
X332421D01*
G01X375211Y1022114D02*
X372987Y1020399D01*
X372624Y1020187D01*
G02X370440Y1020163I-1113J1927D01*
G01X370399Y1020187D01*
G03X368925I-737J-1277D01*
G02X366757Y1020153I-1114J1927D01*
G01X366699Y1020187D01*
G03X365225I-737J-1277D01*
G02X363057Y1020153I-1114J1927D01*
G01X362999Y1020187D01*
G03X361525I-737J-1277D01*
G02X359299I-1113J1927D01*
G03X357825I-737J-1277D01*
G02X355639Y1020163I-1114J1927D01*
G01X355598Y1020187D01*
G03X354124I-737J-1277D01*
G02X351898I-1113J1927D01*
G03X350424I-737J-1277D01*
G02X348198I-1113J1927D01*
G03X346724I-737J-1277D01*
G02X344498I-1113J1927D01*
G03X343024I-737J-1277D01*
G02X340798I-1113J1927D01*
G03X339324I-737J-1277D01*
G02X337098I-1113J1927D01*
G03X335624I-737J-1277D01*
G02X333398I-1113J1927D01*
G03X332399Y1020361I-737J-1277D01*
G01X330259D01*
X327944Y1022676D01*
X327121D01*
G01X377062Y1018910D02*
X378293D01*
X378519Y1019136D01*
G03X377834Y1020167I-1458J-225D01*
G01X377799Y1020187D01*
G03X376325I-737J-1277D01*
G01X376290Y1020167D01*
G03X375587Y1018910I772J-1257D01*
G01Y1018880D01*
G02X374474Y1016982I-2226J30D01*
G02X372248I-1113J1928D01*
G03X370774I-737J-1277D01*
G01X370716Y1016948D01*
G02X368548Y1016982I-1053J1962D01*
G03X367074I-737J-1277D01*
G01X367033Y1016958D01*
G02X364849Y1016982I-1071J1952D01*
G03X363375I-737J-1277D01*
G01X363334Y1016958D01*
G02X361148Y1016982I-1072J1952D01*
G03X359674I-737J-1277D01*
G01X359633Y1016958D01*
G02X357449Y1016982I-1071J1952D01*
G03X355975I-737J-1277D01*
G02X353789Y1016958I-1114J1928D01*
G01X353748Y1016982D01*
G03X352274I-737J-1277D01*
G02X350048I-1113J1928D01*
G03X348574I-737J-1277D01*
G02X346348I-1113J1928D01*
G03X344874I-737J-1277D01*
G02X342648I-1113J1928D01*
G03X341174I-737J-1277D01*
G02X338948I-1113J1928D01*
G03X337474I-737J-1277D01*
G02X335248I-1113J1928D01*
G03X333774I-737J-1277D01*
G02X331548I-1113J1928D01*
G03X330811Y1017182I-742J-1276D01*
G01X330343D01*
X328888Y1018637D01*
X327121D01*
G01X375211Y1028523D02*
G02X372248Y1029800I3974J13297D01*
G03X370774I-737J-1277D01*
G01X370716Y1029766D01*
G02X368548Y1029800I-1054J1961D01*
G03X367074I-737J-1277D01*
G01X367016Y1029766D01*
G02X364848Y1029800I-1054J1961D01*
G03X363374I-737J-1277D01*
G01X363316Y1029766D01*
G02X361148Y1029800I-1054J1961D01*
G03X359674I-737J-1277D01*
G02X357448I-1113J1927D01*
G03X355974I-737J-1277D01*
G02X353748I-1113J1927D01*
G03X352317Y1029824I-737J-1277D01*
G01X352274Y1029799D01*
X352216Y1029765D01*
G02X350048Y1029799I-1054J1961D01*
G01X350005Y1029824D01*
G03X348574Y1029800I-694J-1301D01*
G02X346348I-1113J1927D01*
G03X344874I-737J-1277D01*
G02X342648I-1113J1927D01*
G03X341174I-737J-1277D01*
G02X338948I-1113J1927D01*
G03X337474I-737J-1277D01*
G02X335248I-1113J1927D01*
G03X333774I-737J-1277D01*
G02X331548I-1113J1927D01*
G03X330811Y1029999I-740J-1276D01*
G01X329917D01*
X326855Y1033061D01*
X325426D01*
G01X377062Y1025318D02*
G03X375720Y1024964I0J-2721D01*
G01X374046Y1024012D01*
G02X373241Y1023848I-648J1121D01*
G01X373016Y1023875D01*
X372997Y1023865D01*
X371597D01*
X370717Y1023358D01*
G02X368547Y1023391I-1055J1960D01*
G01X368548D01*
G03X367074I-737J-1277D01*
G01X367016Y1023357D01*
G02X364848Y1023391I-1054J1961D01*
G03X363374I-737J-1277D01*
G02X361190Y1023367I-1113J1927D01*
G01X361149Y1023391D01*
G03X359675I-737J-1277D01*
G01X359634Y1023367D01*
G02X357448Y1023391I-1072J1951D01*
G03X355974I-737J-1277D01*
G01X355916Y1023357D01*
G02X353748Y1023391I-1054J1961D01*
G03X352274I-737J-1277D01*
G01X352216Y1023357D01*
G02X350048Y1023391I-1054J1961D01*
G03X348574I-737J-1277D01*
G02X346348I-1113J1927D01*
G03X344874I-737J-1277D01*
G02X342648I-1113J1927D01*
G03X341174I-737J-1277D01*
G02X338948I-1113J1927D01*
G03X337474I-737J-1277D01*
G02X335248I-1113J1927D01*
G03X333774I-737J-1277D01*
G02X331548I-1113J1927D01*
G02X331295Y1023561I1112J1928D01*
G02X331088Y1023742I1359J1763D01*
G01X330685Y1024141D01*
X330002D01*
X327245Y1026898D01*
X325753D01*
X325517Y1026662D01*
X325425D01*
G01X373360Y1025318D02*
X373235Y1024862D01*
X373082Y1024775D01*
G02X372473Y1024614I-609J1071D01*
G01X371396D01*
X370399Y1024040D01*
X370398Y1024041D01*
G02X368924I-737J1277D01*
G01X368925D01*
G03X366757Y1024075I-1114J-1927D01*
G01X366699Y1024041D01*
G02X365225I-737J1277D01*
G03X363039Y1024065I-1114J-1927D01*
G01X362998Y1024041D01*
G02X361524I-737J1277D01*
G01X361483Y1024065D01*
G03X359299Y1024041I-1071J-1951D01*
G02X357825I-737J1277D01*
G03X355657Y1024075I-1114J-1927D01*
G01X355599Y1024041D01*
G02X354125I-737J1277D01*
G03X351957Y1024075I-1114J-1927D01*
G01X351899Y1024041D01*
G02X350425I-737J1277D01*
G03X348239Y1024065I-1114J-1927D01*
G01X348198Y1024041D01*
G02X346724I-737J1277D01*
G03X344498I-1113J-1927D01*
G02X343024I-737J1277D01*
G03X340798I-1113J-1927D01*
G02X339324I-737J1277D01*
G03X337098I-1113J-1927D01*
G02X335624I-737J1277D01*
G03X333398I-1113J-1927D01*
G02X331924I-737J1277D01*
G02X331617Y1024274I731J1282D01*
G01X331615Y1024275D01*
X330994Y1024890D01*
X330313D01*
X327556Y1027647D01*
X325752D01*
X325517Y1027882D01*
X325425D01*
G01X377062Y1031727D02*
X378293D01*
X378519Y1031953D01*
G03X377834Y1032984I-1458J-225D01*
G01X377799Y1033004D01*
G03X376325I-737J-1277D01*
G02X374157Y1032970I-1114J1927D01*
G01X374099Y1033004D01*
G03X372625I-737J-1277D01*
G02X370457Y1032970I-1114J1927D01*
G01X370399Y1033004D01*
G03X368925I-737J-1277D01*
G02X366757Y1032970I-1114J1927D01*
G01X366699Y1033004D01*
G03X365225I-737J-1277D01*
G02X363057Y1032970I-1114J1927D01*
G01X362999Y1033004D01*
G03X361525I-737J-1277D01*
G02X359339Y1032980I-1114J1927D01*
G01X359298Y1033004D01*
G03X357824I-737J-1277D01*
G01X357766Y1032970D01*
G02X355598Y1033004I-1054J1961D01*
G03X354124I-737J-1277D01*
G02X351898I-1113J1927D01*
G03X350424I-737J-1277D01*
G01X350425D01*
G02X348239Y1032980I-1114J1927D01*
G01X348198Y1033004D01*
G03X346724I-737J-1277D01*
G02X344498I-1113J1927D01*
G03X343024I-737J-1277D01*
G02X340798I-1113J1927D01*
G03X339324I-737J-1277D01*
G02X337098I-1113J1927D01*
G03X335624I-737J-1277D01*
G02X333398I-1113J1927D01*
G03X332733Y1033200I-738J-1277D01*
G02X331761Y1033630I70J1473D01*
G01X328357Y1037034D01*
X325426D01*
G01X375211Y1041340D02*
X373750Y1040943D01*
X372248Y1040063D01*
G02X370774I-737J1277D01*
G01X370716Y1040097D01*
G03X368548Y1040063I-1054J-1961D01*
G02X367074I-737J1277D01*
G01X367016Y1040097D01*
G03X364848Y1040063I-1054J-1961D01*
G02X363374I-737J1277D01*
G01X363333Y1040087D01*
G03X361149Y1040063I-1071J-1951D01*
G02X359675I-737J1277D01*
G01X359634Y1040087D01*
G03X357448Y1040063I-1072J-1951D01*
G02X355974I-737J1277D01*
G03X353748I-1113J-1927D01*
G02X352274I-737J1277D01*
G03X350048I-1113J-1927D01*
G02X348574I-737J1277D01*
G03X346348I-1113J-1927D01*
G02X344874I-737J1277D01*
G03X342648I-1113J-1927D01*
G02X341174I-737J1277D01*
G03X338948I-1113J-1927D01*
G02X337474I-737J1277D01*
G03X335248I-1113J-1927D01*
G02X333774I-737J1277D01*
G02X333467Y1040296I731J1282D01*
G01X332731Y1041032D01*
Y1042339D01*
X331143Y1043927D01*
Y1046341D01*
X328910Y1048574D01*
X326926D01*
G01X377062Y1038136D02*
X378293D01*
X378519Y1037909D01*
G02X377799Y1036858I-1458J226D01*
G02X376347Y1036845I-737J1277D01*
G01X376324Y1036858D01*
X376301Y1036872D01*
G03X374099Y1036858I-1089J-1941D01*
G02X372647Y1036845I-737J1277D01*
G01X372624Y1036858D01*
X372601Y1036872D01*
G03X370399Y1036858I-1089J-1941D01*
G02X368947Y1036845I-737J1277D01*
G01X368924Y1036858D01*
X368901Y1036872D01*
G03X366699Y1036858I-1089J-1941D01*
G02X365247Y1036845I-737J1277D01*
G01X365224Y1036858D01*
X365201Y1036872D01*
G03X362999Y1036858I-1089J-1941D01*
G02X361547Y1036845I-737J1277D01*
G01X361524Y1036858D01*
X361501Y1036872D01*
G03X359299Y1036858I-1089J-1941D01*
G02X357847Y1036845I-737J1277D01*
G01X357824Y1036858D01*
X357801Y1036872D01*
G03X355599Y1036858I-1089J-1941D01*
G02X354141Y1036848I-738J1277D01*
G01X354124Y1036858D01*
G03X351899I-1112J-1927D01*
G02X350439Y1036850I-737J1278D01*
G01X350424Y1036858D01*
X350401Y1036872D01*
G03X348199Y1036858I-1089J-1941D01*
G01X348198Y1036859D01*
G02X346724I-737J1277D01*
G03X344498I-1113J-1928D01*
G02X343024I-737J1277D01*
G03X340798I-1113J-1928D01*
G02X339324I-737J1277D01*
G03X337098I-1113J-1928D01*
G02X335624I-737J1277D01*
G03X334035Y1037106I-1113J-1928D01*
G02X331986Y1037707I-475J2175D01*
G01X331573Y1038120D01*
Y1039831D01*
X329339Y1042065D01*
Y1043396D01*
X328513Y1044222D01*
X326926D01*
G01X375211Y1047749D02*
X375210D01*
X374547Y1048412D01*
G03X373746Y1049027I-2740J-2740D01*
G01X372625Y1049675D01*
Y1049676D01*
G03X370457Y1049710I-1114J-1927D01*
G01X370399Y1049676D01*
G02X368925I-737J1276D01*
G03X366757Y1049710I-1114J-1927D01*
G01X366699Y1049676D01*
G02X365225I-737J1276D01*
G03X363057Y1049710I-1114J-1927D01*
G01X362999Y1049676D01*
G02X361525I-737J1276D01*
G03X359339Y1049700I-1114J-1927D01*
G01X359298Y1049676D01*
G02X357824I-737J1276D01*
G03X355598I-1113J-1927D01*
G02X354124I-737J1276D01*
G03X351898I-1113J-1927D01*
G02X350424I-737J1276D01*
G03X348198I-1113J-1927D01*
G02X346724I-737J1276D01*
G03X344498I-1113J-1927D01*
G02X343024I-737J1276D01*
G03X340798I-1113J-1927D01*
G02X339324I-737J1276D01*
G03X337098I-1113J-1927D01*
G02X335624I-737J1276D01*
G01X335568Y1049708D01*
G02X334886Y1050952I794J1244D01*
G01Y1051025D01*
G03X333774Y1052880I-2225J-73D01*
G02X333467Y1053113I731J1282D01*
G01Y1055415D01*
X329526Y1059356D01*
X326926D01*
G01X373362Y1044544D02*
X373237Y1045000D01*
X373084Y1045087D01*
G03X372475Y1045248I-609J-1071D01*
G01X371398D01*
X370401Y1045822D01*
X370400Y1045821D01*
G03X368926I-737J-1277D01*
G01X368925D01*
G02X366757Y1045787I-1115J1928D01*
G01X366699Y1045821D01*
G03X365225I-737J-1277D01*
G02X363039Y1045797I-1114J1927D01*
G01X362998Y1045821D01*
G03X361524I-737J-1277D01*
G02X359340Y1045797I-1113J1927D01*
G01X359299Y1045821D01*
G03X357825I-737J-1277D01*
G02X355639Y1045797I-1114J1927D01*
G01X355598Y1045821D01*
G03X354124I-737J-1277D01*
G02X351898I-1113J1927D01*
G03X350424I-737J-1277D01*
G02X348198I-1113J1927D01*
G03X346724I-737J-1277D01*
G02X344498I-1113J1928D01*
G03X343024I-737J-1277D01*
G02X340798I-1113J1928D01*
G03X339324I-737J-1277D01*
G02X336637Y1046175I-1113J1928D01*
G01X335792Y1047020D01*
X334510D01*
X330907Y1050623D01*
Y1052614D01*
X329542Y1053979D01*
X327253D01*
X327018Y1053744D01*
X326926D01*
G01X377062Y1044544D02*
G02X375722Y1044898I-1J2708D01*
G01X374048Y1045850D01*
G03X373243Y1046014I-648J-1121D01*
G01X373018Y1045987D01*
X372999Y1045997D01*
X371599D01*
X370719Y1046504D01*
G03X368549Y1046471I-1055J-1960D01*
G01X368548Y1046472D01*
G02X367074I-737J1277D01*
G01X367016Y1046506D01*
G03X364848Y1046472I-1053J-1962D01*
G01Y1046471D01*
G02X363374I-737J1277D01*
G03X361148I-1113J-1927D01*
G02X359674I-737J1277D01*
G01X359616Y1046505D01*
G03X357448Y1046471I-1054J-1961D01*
G02X355974I-737J1277D01*
G03X353748I-1113J-1927D01*
G02X352274I-737J1277D01*
G03X350048I-1113J-1927D01*
G02X348574I-737J1277D01*
G01Y1046472D01*
G03X346348I-1113J-1928D01*
G02X344874I-737J1277D01*
G03X342648I-1113J-1928D01*
G02X341174I-737J1277D01*
G03X338948I-1113J-1928D01*
G02X337474I-737J1277D01*
G02X337167Y1046705I731J1282D01*
G01X336103Y1047769D01*
X334821D01*
X331656Y1050934D01*
Y1052925D01*
X329853Y1054728D01*
X327254D01*
X327018Y1054964D01*
X326926D01*
G01X377062Y1050952D02*
G03X376264Y1052399I-1709J1D01*
G01X376250Y1052408D01*
G03X375918Y1052522I-407J-646D01*
G01X375191Y1052594D01*
G02X374853Y1052688I101J1017D01*
G01X374588Y1052815D01*
X374474Y1052880D01*
X374416Y1052914D01*
G03X372248Y1052880I-1053J-1962D01*
G02X370774I-737J1277D01*
G01X370716Y1052914D01*
G03X368548Y1052880I-1053J-1962D01*
G02X367074I-737J1277D01*
G01X367016Y1052914D01*
G03X364848Y1052880I-1053J-1962D01*
G02X363374I-737J1277D01*
G01X363316Y1052914D01*
G03X361148Y1052880I-1053J-1962D01*
G02X359674I-737J1277D01*
G03X357490Y1052904I-1113J-1928D01*
G01X357449Y1052880D01*
G02X355975I-737J1277D01*
G03X353789Y1052904I-1114J-1928D01*
G01X353748Y1052880D01*
G02X352274I-737J1277D01*
G03X350048I-1113J-1928D01*
G02X348574I-737J1277D01*
G03X346348I-1113J-1928D01*
G02X344874I-737J1277D01*
G03X342648I-1113J-1928D01*
G02X341174I-737J1277D01*
G03X338948I-1113J-1928D01*
G02X337474I-737J1277D01*
G01X337439Y1052900D01*
G02X336736Y1054157I772J1257D01*
G01Y1054196D01*
G03X335624Y1056084I-2225J-39D01*
G02X335317Y1056317I731J1282D01*
G01X330441Y1061193D01*
Y1062942D01*
X329903Y1063480D01*
X328122D01*
G01X377062Y1057361D02*
X378293D01*
X378519Y1057135D01*
G02X377834Y1056104I-1458J225D01*
G01X377799Y1056084D01*
G02X376325I-737J1277D01*
G03X374139Y1056108I-1114J-1927D01*
G01X374098Y1056084D01*
G02X372624I-737J1277D01*
G03X370440Y1056108I-1113J-1927D01*
G01X370399Y1056084D01*
G02X368925I-737J1277D01*
G03X366757Y1056118I-1114J-1927D01*
G01X366699Y1056084D01*
G02X365225I-737J1277D01*
G03X363057Y1056118I-1114J-1927D01*
G01X362999Y1056084D01*
G02X361525I-737J1277D01*
G03X359357Y1056118I-1114J-1927D01*
G01X359299Y1056084D01*
G02X357825I-737J1277D01*
G01X357784Y1056108D01*
G03X355598Y1056084I-1072J-1951D01*
G02X354124I-737J1277D01*
G03X351898I-1113J-1927D01*
G02X350424I-737J1277D01*
G03X348198I-1113J-1927D01*
G02X346724I-737J1277D01*
G03X344498I-1113J-1927D01*
G02X343024I-737J1277D01*
G03X340798I-1113J-1927D01*
G02X339324I-737J1277D01*
G01X339289Y1056104D01*
G02X338586Y1057361I772J1257D01*
G01Y1057400D01*
G03X337474Y1059288I-2225J-39D01*
G02X337167Y1059521I731J1282D01*
G01X335419Y1061269D01*
X333081D01*
X332235Y1062115D01*
Y1064811D01*
X329306Y1067740D01*
Y1068293D01*
X328957Y1068642D01*
X328122D01*
G01X375211Y1060565D02*
X373750Y1060168D01*
X372248Y1059288D01*
G02X370774I-737J1277D01*
G01X370716Y1059322D01*
G03X368548Y1059288I-1054J-1961D01*
G02X367074I-737J1277D01*
G01X367016Y1059322D01*
G03X364848Y1059288I-1054J-1961D01*
G02X363374I-737J1277D01*
G01X363333Y1059312D01*
G03X361149Y1059288I-1071J-1951D01*
G02X359675I-737J1277D01*
G01X359634Y1059312D01*
G03X357448Y1059288I-1072J-1951D01*
G02X355974I-737J1277D01*
G03X353748I-1113J-1927D01*
G02X352274I-737J1277D01*
G03X350048I-1113J-1927D01*
G02X348574I-737J1277D01*
G03X346348I-1113J-1927D01*
G02X344874I-737J1277D01*
G03X342648I-1113J-1927D01*
G02X341174I-737J1277D01*
G01X341139Y1059308D01*
G02X340436Y1060565I772J1257D01*
G01Y1060638D01*
G03X339324Y1062493I-2225J-73D01*
G02X339017Y1062726I731J1282D01*
G01X338074Y1063669D01*
X336681D01*
X334922Y1065428D01*
X333930D01*
X330883Y1068475D01*
Y1070775D01*
X328818Y1072840D01*
X328122D01*
G01X373362Y1063770D02*
X373237Y1064226D01*
X373084Y1064313D01*
G03X372475Y1064474I-609J-1071D01*
G01X371398D01*
X370401Y1065048D01*
X370400Y1065047D01*
G03X368926I-737J-1277D01*
G01X368925D01*
G02X366757Y1065013I-1114J1927D01*
G01X366699Y1065047D01*
G03X365225I-737J-1277D01*
G02X363039Y1065023I-1114J1927D01*
G01X362998Y1065047D01*
G03X361524I-737J-1277D01*
G02X359340Y1065023I-1113J1927D01*
G01X359299Y1065047D01*
G03X357825I-737J-1277D01*
G02X355639Y1065023I-1114J1927D01*
G01X355598Y1065047D01*
G03X354124I-737J-1277D01*
G02X351898I-1113J1927D01*
G03X350424I-737J-1277D01*
G02X348198I-1113J1927D01*
G03X346724I-737J-1277D01*
G02X343430Y1066528I-1114J1927D01*
G01X343386Y1066743D01*
Y1066974D01*
G03X342683Y1068231I-1475J0D01*
G01X342648Y1068251D01*
G03X341174I-737J-1277D01*
G01X341116Y1068217D01*
G02X338948Y1068251I-1054J1961D01*
G02X337837Y1070117I1114J1927D01*
G01Y1070178D01*
G03X337134Y1071435I-1475J0D01*
G03X336458Y1071626I-676J-1100D01*
G01X335227D01*
X332587Y1074266D01*
Y1076135D01*
X330443Y1078279D01*
X328449D01*
X328214Y1078044D01*
X328122D01*
G01X377062Y1070178D02*
G03X376264Y1071625I-1709J1D01*
G01X376250Y1071634D01*
G03X375918Y1071748I-407J-646D01*
G01X375191Y1071820D01*
G02X374853Y1071914I101J1017D01*
G01X374588Y1072041D01*
X374474Y1072106D01*
X374416Y1072140D01*
G03X372248Y1072106I-1053J-1962D01*
G02X370774I-737J1277D01*
G01X370716Y1072140D01*
G03X368548Y1072106I-1053J-1962D01*
G02X367074I-737J1277D01*
G01X367016Y1072140D01*
G03X364848Y1072106I-1053J-1962D01*
G02X363374I-737J1277D01*
G01X363316Y1072140D01*
G03X361148Y1072106I-1053J-1962D01*
G02X359674I-737J1277D01*
G03X357490Y1072130I-1113J-1928D01*
G01X357449Y1072106D01*
G02X355975I-737J1277D01*
G03X353789Y1072130I-1114J-1928D01*
G01X353748Y1072106D01*
G02X352274I-737J1277D01*
G01X352233Y1072130D01*
G03X350049Y1072106I-1071J-1952D01*
G02X348575I-737J1277D01*
G01X348540Y1072126D01*
G02X347837Y1073383I772J1257D01*
G03X346772Y1075282I-2226J0D01*
G01X346724Y1075310D01*
G03X344498I-1113J-1927D01*
G02X343024I-737J1277D01*
G02X342287Y1076553I737J1277D01*
G01Y1076587D01*
G03X341198Y1078500I-2225J0D01*
G01X341174Y1078514D01*
X341116Y1078548D01*
G03X338948Y1078514I-1054J-1961D01*
G02X337474I-737J1277D01*
G02X337168Y1078748I735J1278D01*
G01X336652Y1079264D01*
Y1080521D01*
X334047Y1083126D01*
X333238D01*
X328722Y1087642D01*
X328122D01*
G01X375211Y1066974D02*
X372975Y1068694D01*
X372625Y1068901D01*
G03X370399I-1113J-1927D01*
G02X368925I-737J1277D01*
G03X366757Y1068935I-1114J-1927D01*
G01X366699Y1068901D01*
G02X365225I-737J1277D01*
G03X363057Y1068935I-1114J-1927D01*
G01X362999Y1068901D01*
G02X361525I-737J1277D01*
G03X359339Y1068925I-1114J-1927D01*
G01X359298Y1068901D01*
G02X357824I-737J1277D01*
G03X355598I-1113J-1927D01*
G02X354124I-737J1277D01*
G03X351940Y1068925I-1113J-1927D01*
G01X351899Y1068901D01*
G02X350425I-737J1277D01*
G03X348239Y1068925I-1114J-1927D01*
G01X348198Y1068901D01*
G02X346724I-737J1277D01*
G01X346689Y1068921D01*
G02X345986Y1070178I772J1257D01*
G01Y1070251D01*
G03X344874Y1072106I-2225J-73D01*
G03X342690Y1072130I-1113J-1928D01*
G01X342649Y1072106D01*
G02X341175I-737J1277D01*
G01X341140Y1072126D01*
G02X340437Y1073383I772J1257D01*
G03X339349Y1075296I-2226J0D01*
G01X339325Y1075310D01*
G03X337157Y1075344I-1114J-1927D01*
G01X337099Y1075310D01*
G02X335625I-737J1277D01*
G02X335345Y1075795I280J485D01*
G01Y1077506D01*
G03X335215Y1077820I-444J0D01*
G01X329501Y1083534D01*
X328122D01*
G01X377062Y1063770D02*
G02X375722Y1064124I-1J2708D01*
G01X374048Y1065076D01*
G03X373243Y1065240I-648J-1121D01*
G01X373018Y1065213D01*
X372999Y1065223D01*
X371599D01*
X370719Y1065730D01*
G03X368549Y1065697I-1055J-1960D01*
G01X368548D01*
G02X367074I-737J1277D01*
G01X367016Y1065731D01*
G03X364848Y1065697I-1054J-1961D01*
G02X363374I-737J1277D01*
G03X361148I-1113J-1927D01*
G02X359674I-737J1277D01*
G01X359616Y1065731D01*
G03X357448Y1065697I-1054J-1961D01*
G02X355974I-737J1277D01*
G03X353748I-1113J-1927D01*
G02X352274I-737J1277D01*
G03X350048I-1113J-1927D01*
G02X348574I-737J1277D01*
G03X346348I-1113J-1927D01*
G02X344164Y1066680I-738J1278D01*
G01X344136Y1066817D01*
Y1067013D01*
G03X343024Y1068901I-2225J-39D01*
G03X340840Y1068925I-1113J-1927D01*
G01X340799Y1068901D01*
G02X339325I-737J1277D01*
G01X339290Y1068921D01*
G02X338587Y1070178I772J1257D01*
G01Y1070239D01*
G03X337527Y1072073I-2224J-62D01*
G03X336457Y1072375I-1068J-1738D01*
G01X335538D01*
X333336Y1074577D01*
Y1076446D01*
X330754Y1079028D01*
X328450D01*
X328214Y1079264D01*
X328122D01*
G01X385878Y893036D02*
G02X384478Y893411I0J2801D01*
G01X382915Y894313D01*
G03X381441I-737J-1277D01*
G01X381075Y894099D01*
G03X380831Y893853I343J-585D01*
G01X380176Y892718D01*
G02X379216Y891759I-2271J1313D01*
G02X377742I-737J1277D01*
G01X377701Y891783D01*
G03X375515Y891759I-1072J-1951D01*
G03X374404Y889893I1114J-1927D01*
G01Y889832D01*
G02X373701Y888575I-1475J0D01*
G01X373666Y888555D01*
G02X372192I-737J1277D01*
G03X370024Y888589I-1115J-1928D01*
G01X369966Y888555D01*
G03X368853Y886683I1112J-1928D01*
G01Y886627D01*
G02X368150Y885370I-1475J0D01*
G01X368115Y885350D01*
G03X367004Y883484I1114J-1927D01*
G01Y883423D01*
G02X366301Y882166I-1475J0D01*
G01X366266Y882146D01*
G02X364792I-737J1277D01*
G01X364757Y882166D01*
G02X364054Y883423I772J1257D01*
G03X362965Y885336I-2225J0D01*
G01X362941Y885350D01*
X362883Y885384D01*
G03X360715Y885350I-1054J-1961D01*
G03X359604Y883484I1114J-1927D01*
G01Y883423D01*
G02X358901Y882166I-1475J0D01*
G01X358866Y882146D01*
G02X357392I-737J1277D01*
G01X357357Y882166D01*
G02X356654Y883423I772J1257D01*
G03X355565Y885336I-2225J0D01*
G01X355541Y885350D01*
X355483Y885384D01*
G03X353315Y885350I-1054J-1961D01*
G03X352204Y883484I1114J-1927D01*
G01Y883423D01*
G02X351501Y882166I-1475J0D01*
G01X351466Y882146D01*
X351418Y882118D01*
G03X350353Y880219I1161J-1899D01*
G02X349650Y878962I-1475J0D01*
G01X349615Y878942D01*
G02X348175Y878923I-737J1277D01*
G01X348142Y878942D01*
X348084Y878976D01*
G03X345916Y878942I-1053J-1962D01*
G02X344442I-737J1277D01*
G03X342216I-1113J-1928D01*
G02X340742I-737J1277D01*
G03X338516I-1113J-1928D01*
G02X337042I-737J1277D01*
G03X334874Y878976I-1115J-1928D01*
G01X334816Y878942D01*
G03X333703Y877070I1112J-1928D01*
G01Y873090D01*
X327040Y866427D01*
G01X374778Y893036D02*
X373547D01*
X373289Y892778D01*
G02X372192Y891109I-2211J258D01*
G02X370024Y891075I-1114J1927D01*
G01X369966Y891109D01*
G03X368492I-737J-1277D01*
G01X368457Y891089D01*
G03X367754Y889832I772J-1257D01*
G01Y889776D01*
G02X366641Y887904I-2225J56D01*
G01X366583Y887870D01*
G02X364415Y887904I-1053J1962D01*
G03X362941I-737J-1277D01*
G01X362883Y887870D01*
G02X360715Y887904I-1053J1962D01*
G03X359241I-737J-1277D01*
G02X357015I-1113J1928D01*
G03X355541I-737J-1277D01*
G01X355483Y887870D01*
G02X353315Y887904I-1053J1962D01*
G03X351841I-737J-1277D01*
G03X351104Y886661I737J-1277D01*
G01Y886588D01*
G02X349992Y884700I-2225J39D01*
G01X349957Y884680D01*
G03X349254Y883423I772J-1257D01*
G02X348165Y881510I-2225J0D01*
G01X348141Y881496D01*
X348100Y881472D01*
G02X345916Y881496I-1071J1951D01*
G03X344442I-737J-1277D01*
G02X342216I-1113J1927D01*
G03X340742I-737J-1277D01*
G02X338516I-1113J1927D01*
G03X337042I-737J-1277D01*
G02X334874Y881462I-1114J1927D01*
G01X334816Y881496D01*
G03X333376Y881515I-737J-1277D01*
G01X333343Y881496D01*
G03X333036Y881262I733J-1279D01*
G01X330754Y878980D01*
Y874347D01*
X326674Y870267D01*
X324723D01*
G01X380329Y896240D02*
X380204Y895784D01*
X380051Y895697D01*
G02X379442Y895536I-609J1071D01*
G01X378365D01*
X377366Y894963D01*
G02X375892I-737J1277D01*
G03X373724Y894997I-1114J-1927D01*
G01X373666Y894963D01*
G02X372192I-737J1277D01*
G03X370024Y894997I-1114J-1927D01*
G01X369966Y894963D01*
G02X368492I-737J1277D01*
G03X366324Y894997I-1114J-1927D01*
G01X366266Y894963D01*
G03X365154Y893075I1113J-1927D01*
G01Y893036D01*
G02X364451Y891779I-1475J0D01*
G01X364416Y891759D01*
G02X362942I-737J1277D01*
G03X360716I-1113J-1927D01*
G02X359242I-737J1277D01*
G03X357056Y891783I-1114J-1927D01*
G01X357015Y891759D01*
G02X355541I-737J1277D01*
G01X355483Y891793D01*
G03X353315Y891759I-1054J-1961D01*
G02X351841I-737J1277D01*
G01X351783Y891793D01*
G03X349615Y891759I-1054J-1961D01*
G03X348504Y889893I1114J-1927D01*
G01Y889832D01*
G02X347801Y888575I-1475J0D01*
G01X347766Y888555D01*
G03X346654Y886700I1113J-1928D01*
G01Y886627D01*
G02X345951Y885370I-1475J0D01*
G01X345916Y885350D01*
G02X344442I-737J1277D01*
G03X342216I-1113J-1927D01*
G02X340742I-737J1277D01*
G03X338516I-1113J-1927D01*
G02X337042I-737J1277D01*
G03X334874Y885384I-1114J-1927D01*
G01X334816Y885350D01*
G02X334173Y885154I-740J1276D01*
G02X334080Y885151I-94J1472D01*
G01X333275D01*
X328507Y880383D01*
Y877170D01*
X327499Y876162D01*
X325050D01*
X324815Y876397D01*
X324723D01*
G01X384029Y896240D02*
G03X382689Y895886I-1J-2708D01*
G01X381015Y894934D01*
G02X380210Y894770I-648J1121D01*
G01X379985Y894797D01*
X379966Y894787D01*
X378566D01*
X377701Y894289D01*
G02X375515Y894313I-1072J1951D01*
G03X374041I-737J-1277D01*
G01X373983Y894279D01*
G02X371815Y894313I-1054J1961D01*
G03X370341I-737J-1277D01*
G01X370283Y894279D01*
G02X368115Y894313I-1054J1961D01*
G03X366641I-737J-1277D01*
G01X366642D01*
X366607Y894293D01*
G03X365904Y893036I772J-1257D01*
G01Y892997D01*
G02X364792Y891109I-2225J39D01*
G02X362566I-1113J1927D01*
G03X361092I-737J-1277D01*
G01X361051Y891085D01*
G02X358865Y891109I-1072J1951D01*
G03X357391I-737J-1277D01*
G02X355207Y891085I-1113J1927D01*
G01X355166Y891109D01*
G03X353692I-737J-1277D01*
G02X351524Y891075I-1114J1927D01*
G01X351466Y891109D01*
G03X349992I-737J-1277D01*
G01X349957Y891089D01*
G03X349254Y889832I772J-1257D01*
G01Y889759D01*
G02X348142Y887904I-2225J73D01*
G01X348107Y887884D01*
G03X347404Y886627I772J-1257D01*
G01Y886588D01*
G02X346292Y884700I-2225J39D01*
G02X344066I-1113J1927D01*
G03X342592I-737J-1277D01*
G02X340366I-1113J1927D01*
G03X338892I-737J-1277D01*
G01X338851Y884676D01*
G02X336665Y884700I-1072J1951D01*
G03X335191I-737J-1277D01*
G02X334223Y884406I-1114J1926D01*
G01X334220D01*
G02X334080Y884402I-133J2220D01*
G01X333586D01*
X329256Y880072D01*
Y876859D01*
X327810Y875413D01*
X325051D01*
X324815Y875177D01*
X324723D01*
G01X380329Y902649D02*
G03X377519Y904219I-2668J-1476D01*
G02X374533Y904399I-653J14026D01*
G02X374041Y904576I245J1454D01*
G03X371815I-1113J-1927D01*
G02X370341I-737J1277D01*
G01X370283Y904610D01*
G03X368115Y904576I-1054J-1961D01*
G02X366641I-737J1277D01*
G01X366583Y904610D01*
G03X364415Y904576I-1054J-1961D01*
G02X362941I-737J1277D01*
G01X362883Y904610D01*
G03X360715Y904576I-1054J-1961D01*
G03X359604Y902710I1114J-1927D01*
G01Y902649D01*
G02X358901Y901392I-1475J0D01*
G01X358866Y901372D01*
G02X357392I-737J1277D01*
G03X355224Y901406I-1114J-1927D01*
G01X355166Y901372D01*
G02X353692I-737J1277D01*
G03X351524Y901406I-1114J-1927D01*
G01X351466Y901372D01*
G02X349992I-737J1277D01*
G03X347824Y901406I-1114J-1927D01*
G01X347766Y901372D01*
G02X346292I-737J1277D01*
G01X346251Y901396D01*
G03X344065Y901372I-1072J-1951D01*
G03X342955Y899507I1115J-1926D01*
G01X342954Y899446D01*
Y899418D01*
G02X342216Y898168I-1475J28D01*
G03X341103Y896296I1112J-1928D01*
G01Y896206D01*
G02X340366Y894963I-1474J34D01*
G02X338892I-737J1277D01*
G01X338851Y894987D01*
G03X336665Y894963I-1072J-1951D01*
G02X335191I-737J1277D01*
G03X333007Y894987I-1113J-1927D01*
G01X332966Y894963D01*
G03X332505Y894609I1113J-1926D01*
G01X325342Y887446D01*
X324723D01*
G01X382178Y899445D02*
X379328Y900657D01*
X379216Y900722D01*
G03X377742I-737J-1276D01*
G01X376615Y900071D01*
G03X376253Y899445I360J-626D01*
G02X375516Y898169I-1473J0D01*
G01X375515Y898168D01*
G02X374042I-737J1276D01*
G01X374041D01*
X372916Y898818D01*
G02X372553Y899445I361J628D01*
G03X371816Y900721I-1473J0D01*
G01X371815Y900722D01*
G03X370341I-737J-1277D01*
G01X370283Y900688D01*
G02X368115Y900722I-1054J1961D01*
G03X366641I-737J-1277D01*
G01X366583Y900688D01*
G02X364415Y900722I-1054J1961D01*
G03X362941I-737J-1277D01*
G03X362204Y899479I737J-1277D01*
G01Y899389D01*
G02X361091Y897517I-2225J56D01*
G01X361050Y897493D01*
G02X358866Y897517I-1071J1952D01*
G03X357392I-737J-1277D01*
G02X355224Y897483I-1115J1928D01*
G01X355166Y897517D01*
G03X353692I-737J-1277D01*
G02X351524Y897483I-1115J1928D01*
G01X351466Y897517D01*
G03X349992I-737J-1277D01*
G02X347824Y897483I-1115J1928D01*
G01X347766Y897517D01*
G03X346292I-737J-1277D01*
G01X346257Y897497D01*
G03X345554Y896240I772J-1257D01*
G02X344466Y894327I-2226J0D01*
G01X344442Y894313D01*
X344407Y894293D01*
G03X343704Y893036I772J-1257D01*
G02X342639Y891137I-2226J0D01*
G01X342591Y891109D01*
G02X340407Y891085I-1113J1927D01*
G01X340366Y891109D01*
G03X338892I-737J-1277D01*
G01X338851Y891085D01*
G02X336665Y891109I-1072J1951D01*
G03X335191I-737J-1277D01*
G02X334078Y890811I-1112J1927D01*
G01X332976D01*
X331949Y889784D01*
Y888717D01*
X326259Y883027D01*
Y882164D01*
X325661Y881566D01*
X324723D01*
G01X382178Y931488D02*
G02X378390Y929919I-3788J3788D01*
G03X374519Y929819I0J-74973D01*
G03X372192Y929560I-868J-2787D01*
G02X369966I-1113J1928D01*
G03X368492I-737J-1277D01*
G02X366324Y929526I-1115J1928D01*
G01X366266Y929560D01*
G03X364792I-737J-1277D01*
G02X362624Y929526I-1115J1928D01*
G01X362566Y929560D01*
G03X361092I-737J-1277D01*
G02X358906Y929536I-1114J1928D01*
G01X358865Y929560D01*
G03X357391I-737J-1277D01*
G02X355207Y929536I-1113J1928D01*
G01X355166Y929560D01*
G03X353692I-737J-1277D01*
G02X351524Y929526I-1115J1928D01*
G01X351466Y929560D01*
G03X349992I-737J-1277D01*
G02X347766I-1113J1928D01*
G03X346292I-737J-1277D01*
G02X344120Y929529I-1114J1928D01*
G01X344066Y929561D01*
G03X342592I-737J-1277D01*
G03X341855Y928318I737J-1277D01*
G01Y928228D01*
G02X340742Y926356I-2225J56D01*
G02X338552Y926336I-1113J1928D01*
G01X338517Y926357D01*
G03X337043I-737J-1277D01*
G01X337002Y926333D01*
G02X334816Y926357I-1072J1951D01*
G03X333374Y926376I-738J-1277D01*
G01X333341Y926357D01*
G02X332228Y926059I-1112J1927D01*
G01X331734D01*
X329622Y923947D01*
Y923546D01*
X328515Y920872D01*
X326529Y918886D01*
X325324D01*
G01X380329Y928283D02*
G02X375021Y926533I-4318J4173D01*
G03X374041Y926356I-243J-1454D01*
G01X373983Y926322D01*
G02X371815Y926356I-1054J1961D01*
G03X370341I-737J-1277D01*
G01X370283Y926322D01*
G02X368115Y926356I-1054J1961D01*
G03X366641I-737J-1277D01*
G01X366583Y926322D01*
G02X364415Y926356I-1054J1961D01*
G03X362941I-737J-1277D01*
G01X362883Y926322D01*
G02X360715Y926356I-1054J1961D01*
G03X359241I-737J-1277D01*
G02X357057Y926332I-1113J1927D01*
G01X357016Y926356D01*
G03X355542I-737J-1277D01*
G01X355501Y926332D01*
G02X353315Y926356I-1072J1951D01*
G03X351841I-737J-1277D01*
G01X351783Y926322D01*
G02X349615Y926356I-1054J1961D01*
G03X348141I-737J-1277D01*
G01X348100Y926332D01*
G02X345916Y926356I-1071J1951D01*
G01X345873Y926381D01*
G03X344442Y926357I-694J-1301D01*
G01X344407Y926337D01*
G03X343704Y925080I772J-1257D01*
G02X342616Y923166I-2226J-1D01*
G01X342592Y923152D01*
G02X340406Y923128I-1114J1927D01*
G01X340365Y923152D01*
G03X338925Y923171I-737J-1277D01*
G01X338892Y923152D01*
G02X336702Y923132I-1113J1928D01*
G01X336667Y923153D01*
X336634Y923172D01*
G03X335192Y923153I-704J-1296D01*
G02X332988Y923139I-1114J1927D01*
G01X332966Y923152D01*
X332933Y923171D01*
G03X331491Y923152I-704J-1296D01*
G03X331184Y922920I729J-1284D01*
G01X330944Y922680D01*
X330544Y921714D01*
Y919553D01*
X325957Y914966D01*
X325324D01*
G01X382178Y937896D02*
G03X380782Y937522I0J-2792D01*
G01X379193Y936605D01*
G02X377741Y936618I-715J1291D01*
G03X375619Y936419I-921J-1596D01*
G02X374065Y936605I-562J1886D01*
G01X373983Y936653D01*
G02X373119Y937719I984J1680D01*
G03X371815Y939173I-2873J-1265D01*
G03X370341I-737J-1277D01*
G01X370283Y939139D01*
G02X368115Y939173I-1054J1961D01*
G03X366641I-737J-1277D01*
G01X366583Y939139D01*
G02X364415Y939173I-1054J1961D01*
G03X362941I-737J-1277D01*
G01X362900Y939149D01*
G02X360716Y939173I-1071J1951D01*
G03X359242I-737J-1277D01*
G01X359201Y939149D01*
G02X357015Y939173I-1072J1951D01*
G03X355541I-737J-1277D01*
G01X355483Y939139D01*
G02X353315Y939173I-1054J1961D01*
G03X351841I-737J-1277D01*
G01X351783Y939139D01*
G02X349615Y939173I-1054J1961D01*
G03X348141I-737J-1277D01*
G01X348100Y939149D01*
G02X345916Y939173I-1071J1951D01*
G03X344442I-737J-1277D01*
G02X342258Y939149I-1113J1927D01*
G01X342217Y939173D01*
G03X340743I-737J-1277D01*
G02X338575Y939139I-1114J1927D01*
G01X338517Y939173D01*
G03X337043I-737J-1277D01*
G01X337008Y939153D01*
G03X336305Y937896I772J-1257D01*
G02X335216Y935983I-2225J0D01*
G01X335192Y935969D01*
X335134Y935935D01*
G02X332966Y935969I-1054J1961D01*
G03X332228Y936169I-742J-1276D01*
G01X330282D01*
X329769Y935656D01*
Y933867D01*
X327925Y932023D01*
Y931074D01*
X327584Y930733D01*
Y929783D01*
X326989Y929188D01*
X326124D01*
G01X380329Y934691D02*
X381561D01*
X381786Y934466D01*
G02X379592Y933415I-1457J225D01*
G03X377424Y933449I-1114J-1927D01*
G01X377366Y933415D01*
G02X375892I-737J1276D01*
G03X373724Y933449I-1114J-1927D01*
G01X373666Y933415D01*
G02X372192I-737J1276D01*
G03X369966I-1113J-1927D01*
G02X368492I-737J1276D01*
G03X366324Y933449I-1114J-1927D01*
G01X366266Y933415D01*
G02X364792I-737J1276D01*
G03X362606Y933439I-1114J-1927D01*
G01X362565Y933415D01*
G02X361091I-737J1276D01*
G03X358907Y933439I-1113J-1927D01*
G01X358866Y933415D01*
G02X357392I-737J1276D01*
G03X355224Y933449I-1114J-1927D01*
G01X355166Y933415D01*
G02X353692I-737J1276D01*
G03X351524Y933449I-1114J-1927D01*
G01X351466Y933415D01*
G02X349992I-737J1276D01*
G03X347766I-1113J-1927D01*
G02X346292I-737J1276D01*
G01X346251Y933439D01*
G03X344065Y933415I-1072J-1951D01*
G02X342591I-737J1277D01*
G01X342550Y933439D01*
G03X339254Y931527I-1071J-1951D01*
G01Y931488D01*
G02X337042Y930211I-1475J0D01*
G01X336984Y930245D01*
G03X334816Y930211I-1054J-1961D01*
G02X333342I-737J1277D01*
G03X332228Y930510I-1114J-1926D01*
G01X331423D01*
X330120Y929207D01*
Y927781D01*
X327319Y924980D01*
Y924199D01*
X326911Y923791D01*
X326451D01*
X326216Y924026D01*
X326124D01*
G01X384029Y934691D02*
X382797D01*
X382539Y934433D01*
G02X381465Y932778I-2210J258D01*
G01X381441Y932764D01*
X381383Y932730D01*
G02X379215Y932764I-1054J1961D01*
G03X377741I-737J-1276D01*
G01X377683Y932730D01*
G02X375515Y932764I-1054J1961D01*
G03X374041I-737J-1276D01*
G01X374000Y932740D01*
G02X371816Y932764I-1071J1951D01*
G03X370342I-737J-1276D01*
G01X370301Y932740D01*
G02X368115Y932764I-1072J1951D01*
G03X366641I-737J-1276D01*
G01X366583Y932730D01*
G02X364415Y932764I-1054J1961D01*
G03X362941I-737J-1276D01*
G02X360715I-1113J1927D01*
G03X359241I-737J-1276D01*
G01X359183Y932730D01*
G02X357015Y932764I-1054J1961D01*
G03X355541I-737J-1276D01*
G01X355483Y932730D01*
G02X353315Y932764I-1054J1961D01*
G03X351841I-737J-1276D01*
G01X351800Y932740D01*
G02X349616Y932764I-1071J1951D01*
G03X348142I-737J-1276D01*
G02X345916I-1113J1927D01*
G01X345873Y932789D01*
G03X344442Y932765I-694J-1301D01*
G02X342274Y932731I-1114J1927D01*
G01X342216Y932765D01*
G03X340004Y931488I-737J-1277D01*
G01Y931449D01*
G02X336725Y929527I-2225J38D01*
G01X336667Y929561D01*
G03X335193I-737J-1277D01*
G02X332965I-1114J1927D01*
G03X332228Y929761I-742J-1276D01*
G01X331734D01*
X330869Y928896D01*
Y927470D01*
X328068Y924669D01*
Y923888D01*
X327222Y923042D01*
X326452D01*
X326216Y922806D01*
X326124D01*
G01X380329Y941100D02*
G02X377022Y939540I-2877J1813D01*
G01X375619Y939719D01*
G02X374403Y941100I176J1381D01*
G03X373700Y942357I-1475J0D01*
G01X373665Y942377D01*
G03X372191I-737J-1277D01*
G02X370007Y942353I-1113J1927D01*
G01X369966Y942377D01*
G03X368492I-737J-1277D01*
G02X366324Y942343I-1114J1927D01*
G01X366266Y942377D01*
G03X364792I-737J-1277D01*
G02X362624Y942343I-1114J1927D01*
G01X362566Y942377D01*
G03X361092I-737J-1277D01*
G02X358924Y942343I-1114J1927D01*
G01X358866Y942377D01*
G03X357392I-737J-1277D01*
G02X355166I-1113J1927D01*
G03X353692I-737J-1277D01*
G02X351524Y942343I-1114J1927D01*
G01X351466Y942377D01*
G03X349992I-737J-1277D01*
G02X347824Y942343I-1114J1927D01*
G01X347766Y942377D01*
G03X346292I-737J-1277D01*
G02X344124Y942343I-1114J1927D01*
G01X344066Y942377D01*
G03X342592I-737J-1277D01*
G02X340424Y942343I-1114J1927D01*
G01X340366Y942377D01*
G03X338892I-737J-1277D01*
G02X336724Y942343I-1114J1927D01*
G01X336666Y942377D01*
G03X335192I-737J-1277D01*
G01X335157Y942357D01*
G03X334454Y941100I772J-1257D01*
G01Y941061D01*
G02X332229Y938875I-2225J39D01*
G01X332228Y938876D01*
X330616D01*
X328096Y936356D01*
Y934340D01*
X326864Y933108D01*
X326124D01*
G01X380329Y947509D02*
X379098D01*
X378840Y947251D01*
G02X377741Y945581I-2211J258D01*
G01X377683Y945547D01*
G02X375515Y945581I-1053J1962D01*
G03X374041I-737J-1277D01*
G01X373983Y945547D01*
G02X371815Y945581I-1053J1962D01*
G03X370341I-737J-1277D01*
G01X370283Y945547D01*
G02X368115Y945581I-1053J1962D01*
G03X366641I-737J-1277D01*
G01X366583Y945547D01*
G02X364415Y945581I-1053J1962D01*
G03X362941I-737J-1277D01*
G01X362883Y945547D01*
G02X360715Y945581I-1053J1962D01*
G03X359241I-737J-1277D01*
G02X357057Y945557I-1113J1928D01*
G01X357016Y945581D01*
G03X355542I-737J-1277D01*
G01X355501Y945557D01*
G02X353315Y945581I-1072J1952D01*
G03X351841I-737J-1277D01*
G01X351783Y945547D01*
G02X349615Y945581I-1053J1962D01*
G03X348141I-737J-1277D01*
G01X348070Y945540D01*
G02X345914Y945581I-1041J1969D01*
G03X344472Y945600I-738J-1277D01*
G01X344439Y945581D01*
G02X342285Y945540I-1114J1928D01*
G01X342214Y945581D01*
X342157Y945614D01*
G03X340739Y945581I-679J-1310D01*
G02X338569Y945547I-1115J1928D01*
G01X338511Y945581D01*
G03X337037I-737J-1277D01*
G02X334851Y945557I-1114J1928D01*
G01X334810Y945581D01*
G03X333336I-737J-1277D01*
G03X333028Y945349I726J-1285D01*
G01Y945348D01*
X331943Y944263D01*
X331012Y942016D01*
X327184Y938188D01*
X326124D01*
G01X382178Y950713D02*
X380947D01*
X380689Y950455D01*
G02X379592Y948786I-2211J258D01*
G02X377424Y948752I-1114J1927D01*
G01X377366Y948786D01*
G03X375892I-737J-1277D01*
G02X373724Y948752I-1114J1927D01*
G01X373666Y948786D01*
G03X372192I-737J-1277D01*
G02X369966I-1113J1927D01*
G03X368492I-737J-1277D01*
G02X366324Y948752I-1114J1927D01*
G01X366266Y948786D01*
G03X364792I-737J-1277D01*
G02X362624Y948752I-1114J1927D01*
G01X362566Y948786D01*
G03X361092I-737J-1277D01*
G02X358906Y948762I-1114J1927D01*
G01X358865Y948786D01*
G03X357391I-737J-1277D01*
G02X355207Y948762I-1113J1927D01*
G01X355166Y948786D01*
G03X353692I-737J-1277D01*
G02X351524Y948752I-1114J1927D01*
G01X351466Y948786D01*
G03X349992I-737J-1277D01*
G02X347824Y948752I-1114J1927D01*
G01X347766Y948786D01*
G03X346292I-737J-1277D01*
G02X344066I-1113J1927D01*
G03X342592I-737J-1277D01*
G02X340366I-1113J1927D01*
G03X338892I-737J-1277D01*
G02X336724Y948752I-1114J1927D01*
G01X336666Y948786D01*
G03X335192I-737J-1277D01*
G02X334079Y948488I-1113J1928D01*
G01X333293D01*
X329856Y945051D01*
Y944174D01*
X329530Y943387D01*
X328294Y942151D01*
X327124D01*
G01X380329Y953917D02*
X381561D01*
X381786Y953692D01*
X381787D01*
G02X381088Y952652I-1458J225D01*
G01X381066Y952640D01*
G02X379592I-737J1277D01*
G01X379591D01*
X379590Y952639D01*
G03X377364Y952638I-1112J-1926D01*
G01X377317Y952610D01*
G02X375890Y952639I-687J1307D01*
G03X373664Y952638I-1112J-1926D01*
G01X373631Y952619D01*
G02X372191Y952639I-702J1298D01*
G03X369965Y952638I-1112J-1926D01*
G01X369932Y952619D01*
G02X368490Y952639I-703J1298D01*
G03X366264Y952638I-1112J-1926D01*
G01X366217Y952610D01*
G02X364790Y952639I-687J1307D01*
G03X362564Y952638I-1112J-1926D01*
G01X362517Y952610D01*
G02X361090Y952639I-687J1307D01*
G03X358864Y952638I-1112J-1926D01*
G01X358817Y952610D01*
G02X357390Y952639I-687J1307D01*
G03X355164Y952638I-1112J-1926D01*
G01X355117Y952610D01*
G02X353690Y952639I-687J1307D01*
G03X351464Y952638I-1112J-1926D01*
G01X351417Y952610D01*
G02X349990Y952639I-687J1307D01*
G03X347806Y952662I-1112J-1926D01*
G01X347719Y952611D01*
G02X346291Y952639I-689J1306D01*
G03X344067I-1112J-1926D01*
G02X342640Y952610I-740J1278D01*
G01X342593Y952638D01*
G03X340365I-1114J-1925D01*
G01X340318Y952610D01*
G02X338889Y952639I-688J1307D01*
G03X336734Y952680I-1115J-1926D01*
G01X336590Y952596D01*
G02X335524Y952495I-663J1321D01*
G03X332607Y951736I-812J-2863D01*
G01X332133Y951262D01*
G03X331555Y950401I1904J-1903D01*
G02X331297Y950018I-1100J463D01*
G01X328360Y947081D01*
X327451D01*
X327216Y947316D01*
X327124D01*
G01X384029Y953917D02*
X382797D01*
X382539Y953659D01*
G02X381465Y952004I-2210J258D01*
G01X381441Y951990D01*
X381383Y951956D01*
G02X379215Y951990I-1054J1961D01*
G03X377741I-737J-1277D01*
G01X377683Y951956D01*
G02X375515Y951990I-1054J1961D01*
G03X374041I-737J-1277D01*
G01X374000Y951966D01*
G02X371816Y951990I-1071J1951D01*
G03X370342I-737J-1277D01*
G01X370301Y951966D01*
G02X368115Y951990I-1072J1951D01*
G03X366641I-737J-1277D01*
G01X366583Y951956D01*
G02X364415Y951990I-1054J1961D01*
G03X362941I-737J-1277D01*
G01X362883Y951956D01*
G02X360715Y951990I-1054J1961D01*
G03X359241I-737J-1277D01*
G01X359183Y951956D01*
G02X357015Y951990I-1054J1961D01*
G03X355541I-737J-1277D01*
G01X355483Y951956D01*
G02X353315Y951990I-1054J1961D01*
G03X351841I-737J-1277D01*
G01X351783Y951956D01*
G02X349615Y951990I-1054J1961D01*
G03X348175Y952009I-737J-1277D01*
G01X348084Y951956D01*
G02X345916Y951990I-1054J1961D01*
G03X344442I-737J-1277D01*
G02X342274Y951956I-1114J1927D01*
G01X342216Y951990D01*
G03X340742I-737J-1277D01*
G01X340684Y951956D01*
G02X338514Y951990I-1055J1961D01*
G03X337096Y952023I-739J-1277D01*
G01X336947Y951937D01*
G02X335320Y951774I-1020J1980D01*
G03X333137Y951206I-608J-2142D01*
G01X332663Y950732D01*
G03X332245Y950109I1374J-1374D01*
G02X331827Y949488I-1791J754D01*
G01X328671Y946332D01*
X327452D01*
X327216Y946096D01*
X327124D01*
G01X380329Y960326D02*
X380328D01*
X379707Y959705D01*
G02X376967Y958570I-2740J2740D01*
G01X376823D01*
G02X375054Y959303I0J2501D01*
G01X374403Y959954D01*
Y960326D01*
G03X373700Y961583I-1475J0D01*
G01X373665Y961603D01*
G03X372191I-737J-1277D01*
G02X370007Y961579I-1113J1927D01*
G01X369966Y961603D01*
G03X368492I-737J-1277D01*
G02X366324Y961569I-1114J1927D01*
G01X366266Y961603D01*
G03X364792I-737J-1277D01*
G02X362566I-1113J1927D01*
G03X361092I-737J-1277D01*
G02X358924Y961569I-1114J1927D01*
G01X358866Y961603D01*
G03X357392I-737J-1277D01*
G02X355166I-1113J1927D01*
G03X353692I-737J-1277D01*
G02X351524Y961569I-1114J1927D01*
G01X351466Y961603D01*
G03X349992I-737J-1277D01*
G02X347824Y961569I-1114J1927D01*
G01X347766Y961603D01*
G03X346292I-737J-1277D01*
G02X344106Y961579I-1114J1927D01*
G01X344065Y961603D01*
G03X342591I-737J-1277D01*
G02X340365I-1113J1927D01*
G03X338891I-737J-1277D01*
G02X336665I-1113J1927D01*
G03X335191I-737J-1277D01*
G02X333306Y961441I-1115J1926D01*
G01X331690D01*
X330748Y960499D01*
X327124D01*
G01X382178Y957122D02*
G03X380782Y956748I0J-2792D01*
G01X379193Y955831D01*
G02X377741Y955844I-715J1291D01*
G03X375539Y955858I-1113J-1927D01*
G01X375516Y955844D01*
X375493Y955831D01*
G02X374041Y955844I-715J1291D01*
G02X373644Y956149I960J1661D01*
G01X373250Y956543D01*
G02X372598Y957416I2693J2691D01*
G01X372374Y957827D01*
G03X371836Y958388I-1296J-704D01*
G01X371793Y958412D01*
G03X370341Y958399I-715J-1290D01*
G02X368139Y958386I-1112J1927D01*
G01X368093Y958412D01*
G03X366641Y958399I-715J-1290D01*
G02X364439Y958386I-1112J1927D01*
G01X364393Y958412D01*
G03X362941Y958399I-715J-1290D01*
G02X360739Y958386I-1112J1927D01*
G01X360693Y958412D01*
G03X359241Y958399I-715J-1290D01*
G02X357039Y958386I-1112J1927D01*
G01X356993Y958412D01*
G03X355541Y958399I-715J-1290D01*
G02X353339Y958386I-1112J1927D01*
G01X353293Y958412D01*
G03X351841Y958399I-715J-1290D01*
G02X349639Y958386I-1112J1927D01*
G01X349616Y958399D01*
X349601Y958408D01*
G03X348141Y958399I-722J-1286D01*
G01X348100Y958375D01*
G02X345916Y958399I-1071J1951D01*
G03X344442I-737J-1277D01*
G02X342274Y958365I-1114J1927D01*
G01X342216Y958399D01*
G03X340742I-737J-1277D01*
G02X338574Y958365I-1114J1927D01*
G01X338516Y958399D01*
G03X337042I-737J-1277D01*
G02X334874Y958365I-1114J1927D01*
G01X334816Y958399D01*
G03X333342I-737J-1277D01*
G02X331174Y958365I-1114J1927D01*
G01X330841D01*
X328281Y955805D01*
X327124D01*
G01X380762Y1018910D02*
X379531D01*
X379272Y1019169D01*
G03X378198Y1020823I-2210J-259D01*
G01X378174Y1020837D01*
X378116Y1020871D01*
G03X375948Y1020837I-1054J-1961D01*
G01X375924Y1020823D01*
G03X374836Y1018910I1138J-1913D01*
G02X374133Y1017653I-1475J0D01*
G01X374098Y1017633D01*
G02X372624I-737J1277D01*
G03X370440Y1017657I-1113J-1928D01*
G01X370399Y1017633D01*
G02X368925I-737J1277D01*
G03X366757Y1017667I-1115J-1928D01*
G01X366699Y1017633D01*
G02X365225I-737J1277D01*
G03X362999I-1113J-1928D01*
G02X361525I-737J1277D01*
G03X359357Y1017667I-1115J-1928D01*
G01X359299Y1017633D01*
G02X357825I-737J1277D01*
G01X357784Y1017657D01*
G03X355598Y1017633I-1072J-1952D01*
G02X354124I-737J1277D01*
G03X351898I-1113J-1928D01*
G02X350424I-737J1277D01*
G03X348198I-1113J-1928D01*
G02X346724I-737J1277D01*
G03X344498I-1113J-1928D01*
G02X343024I-737J1277D01*
G03X340798I-1113J-1928D01*
G02X339324I-737J1277D01*
G03X337098I-1113J-1928D01*
G02X335624I-737J1277D01*
G03X333398I-1113J-1928D01*
G02X331924I-737J1277D01*
G03X330811Y1017931I-1113J-1928D01*
G01X328135Y1020607D01*
X327121D01*
G01X382611Y1022114D02*
G03X379513Y1023519I-3211J-2962D01*
G02X379231Y1023553I35J1473D01*
G03X378165Y1023387I-322J-1439D01*
G02X377851Y1023235I-1060J1789D01*
G02X375948Y1023391I-787J2082D01*
G03X374474I-737J-1277D01*
G03X373636Y1022394I953J-1652D01*
G02X373412Y1022068I-6075J3934D01*
G01X373200Y1021685D01*
X372712Y1021162D01*
X372414Y1020938D01*
X372248Y1020837D01*
G02X370774I-737J1277D01*
G01X370716Y1020871D01*
G03X368548Y1020837I-1054J-1961D01*
G02X367074I-737J1277D01*
G01X367016Y1020871D01*
G03X364848Y1020837I-1054J-1961D01*
G02X363374I-737J1277D01*
G01X363333Y1020861D01*
G03X361149Y1020837I-1071J-1951D01*
G02X359675I-737J1277D01*
G01X359634Y1020861D01*
G03X357448Y1020837I-1072J-1951D01*
G02X355974I-737J1277D01*
G03X353748I-1113J-1927D01*
G02X352274I-737J1277D01*
G03X350048I-1113J-1927D01*
G02X348574I-737J1277D01*
G03X346348I-1113J-1927D01*
G02X344874I-737J1277D01*
G03X342648I-1113J-1927D01*
G02X341174I-737J1277D01*
G03X338948I-1113J-1927D01*
G02X337474I-737J1277D01*
G03X335248I-1113J-1927D01*
G02X333774I-737J1277D01*
G03X332478Y1021128I-1113J-1927D01*
G01X330592D01*
X327043Y1024677D01*
X325425D01*
G01X380760Y1025318D02*
X381993D01*
X382218Y1025543D01*
G03X381556Y1026561I-1459J-224D01*
G01X381497Y1026595D01*
G03X380023I-737J-1277D01*
G02X377799I-1112J1928D01*
G03X376325I-737J-1277D01*
G02X374097I-1114J1928D01*
G03X372623I-737J-1277D01*
G02X370399I-1112J1928D01*
G03X368925I-737J-1277D01*
G02X366757Y1026561I-1115J1928D01*
G01X366699Y1026595D01*
G03X365225I-737J-1277D01*
G02X363039Y1026571I-1114J1928D01*
G01X362998Y1026595D01*
G03X361524I-737J-1277D01*
G02X359340Y1026571I-1113J1928D01*
G01X359299Y1026595D01*
G03X357825I-737J-1277D01*
G02X355657Y1026561I-1115J1928D01*
G01X355599Y1026595D01*
G03X354125I-737J-1277D01*
G02X351957Y1026561I-1115J1928D01*
G01X351899Y1026595D01*
G03X350425I-737J-1277D01*
G02X348239Y1026571I-1114J1928D01*
G01X348198Y1026595D01*
G03X346724I-737J-1277D01*
G02X344498I-1113J1928D01*
G03X343024I-737J-1277D01*
G02X340798I-1113J1928D01*
G03X339324I-737J-1277D01*
G02X337098I-1113J1928D01*
G03X335624I-737J-1277D01*
G02X333398I-1113J1928D01*
G03X332197Y1026721I-741J-1277D01*
G02X330613Y1026641I-937J2824D01*
G02X329940Y1027011I299J1341D01*
G01X326844Y1030108D01*
X325752D01*
X325517Y1029873D01*
X325425D01*
G01X380762Y1031727D02*
X379531D01*
X379272Y1031986D01*
G03X378198Y1033640I-2210J-259D01*
G01X378174Y1033654D01*
X378116Y1033688D01*
G03X375948Y1033654I-1054J-1961D01*
G02X374474I-737J1277D01*
G01X374416Y1033688D01*
G03X372248Y1033654I-1054J-1961D01*
G02X370774I-737J1277D01*
G01X370716Y1033688D01*
G03X368548Y1033654I-1054J-1961D01*
G02X367074I-737J1277D01*
G01X367016Y1033688D01*
G03X364848Y1033654I-1054J-1961D01*
G02X363374I-737J1277D01*
G01X363316Y1033688D01*
G03X361148Y1033654I-1054J-1961D01*
G02X359674I-737J1277D01*
G03X357490Y1033678I-1113J-1927D01*
G01X357449Y1033654D01*
G02X355975I-737J1277D01*
G03X353789Y1033678I-1114J-1927D01*
G01X353748Y1033654D01*
G02X352274I-737J1277D01*
G03X350048I-1113J-1927D01*
G02X348574I-737J1277D01*
G03X346348I-1113J-1927D01*
G02X344874I-737J1277D01*
G03X342648I-1113J-1927D01*
G02X341174I-737J1277D01*
G03X338948I-1113J-1927D01*
G02X337474I-737J1277D01*
G03X335248I-1113J-1927D01*
G02X333774I-737J1277D01*
G03X333152Y1033899I-1117J-1925D01*
G02X332069Y1034495I489J2170D01*
G01X327512Y1039052D01*
X325426D01*
G01X382611Y1028523D02*
G03X380025Y1030450I-9545J-10110D01*
G03X377857Y1030484I-1114J-1927D01*
G01X377799Y1030450D01*
G02X376325I-737J1277D01*
G03X374157Y1030484I-1114J-1927D01*
G01X374099Y1030450D01*
G02X372625I-737J1277D01*
G03X370457Y1030484I-1114J-1927D01*
G01X370399Y1030450D01*
G02X368925I-737J1277D01*
G03X366757Y1030484I-1114J-1927D01*
G01X366699Y1030450D01*
G02X365225I-737J1277D01*
G03X363057Y1030484I-1114J-1927D01*
G01X362999Y1030450D01*
G02X361525I-737J1277D01*
G03X359339Y1030474I-1114J-1927D01*
G01X359298Y1030450D01*
G02X357824I-737J1277D01*
G03X355598I-1113J-1927D01*
G02X354124I-737J1277D01*
G03X351940Y1030474I-1113J-1927D01*
G01X351899Y1030450D01*
G02X350425I-737J1276D01*
G03X348239Y1030474I-1114J-1927D01*
G01X348198Y1030450D01*
G02X346724I-737J1277D01*
G03X344498I-1113J-1927D01*
G02X343024I-737J1277D01*
G03X340798I-1113J-1927D01*
G02X339324I-737J1277D01*
G03X337098I-1113J-1927D01*
G02X335624I-737J1277D01*
G03X333398I-1113J-1927D01*
G02X331924I-737J1277D01*
G03X330811Y1030748I-1112J-1927D01*
G01X330369D01*
X329472Y1031645D01*
Y1033504D01*
X327948Y1035028D01*
X325426D01*
G01X384462Y1025318D02*
X383229D01*
X382972Y1025575D01*
G03X382961Y1025658I-2213J-251D01*
G03X381874Y1027246I-2201J-340D01*
G03X379706Y1027280I-1115J-1928D01*
G01X379648Y1027246D01*
G02X378174I-737J1277D01*
G01X378116Y1027280D01*
G03X375948Y1027246I-1053J-1962D01*
G02X374474I-737J1277D01*
G03X372306Y1027280I-1115J-1928D01*
G01X372248Y1027246D01*
G02X370774I-737J1277D01*
G01X370716Y1027280D01*
G03X368548Y1027246I-1053J-1962D01*
G02X367074I-737J1277D01*
G01X367016Y1027280D01*
G03X364848Y1027246I-1053J-1962D01*
G02X363374I-737J1277D01*
G03X361148I-1113J-1928D01*
G02X359674I-737J1277D01*
G01X359616Y1027280D01*
G03X357448Y1027246I-1053J-1962D01*
G02X355974I-737J1277D01*
G01X355916Y1027280D01*
G03X353748Y1027246I-1053J-1962D01*
G02X352274I-737J1277D01*
G01X352216Y1027280D01*
G03X350048Y1027246I-1053J-1962D01*
G02X348574I-737J1277D01*
G03X346348I-1113J-1928D01*
G02X344874I-737J1277D01*
G03X342648I-1113J-1928D01*
G02X341174I-737J1277D01*
G03X338948I-1113J-1928D01*
G02X337474I-737J1277D01*
G03X335248I-1113J-1928D01*
G02X333774I-737J1277D01*
G03X331961Y1027432I-1114J-1928D01*
G02X330777Y1027372I-701J2113D01*
G02X330471Y1027541I137J609D01*
G01X327155Y1030857D01*
X325753D01*
X325517Y1031093D01*
X325425D01*
G01X382611Y1041340D02*
X380413Y1039641D01*
X380086Y1039449D01*
G02X377846Y1039443I-1125J1921D01*
G03X376367Y1039438I-735J-1274D01*
G01X376266Y1039379D01*
G02X374098Y1039413I-1054J1961D01*
G03X372624I-737J-1277D01*
G02X370440Y1039389I-1113J1927D01*
G01X370399Y1039413D01*
G03X368925I-737J-1277D01*
G02X366757Y1039379I-1114J1927D01*
G01X366699Y1039413D01*
G03X365225I-737J-1277D01*
G02X363057Y1039379I-1114J1927D01*
G01X362999Y1039413D01*
G03X361525I-737J-1277D01*
G02X359299I-1113J1927D01*
G03X357825I-737J-1277D01*
G02X355639Y1039389I-1114J1927D01*
G01X355598Y1039413D01*
G03X354124I-737J-1277D01*
G02X351898I-1113J1927D01*
G03X350424I-737J-1277D01*
G02X348198I-1113J1927D01*
G03X346724I-737J-1277D01*
G02X344498I-1113J1927D01*
G03X343024I-737J-1277D01*
G02X340798I-1113J1927D01*
G03X339324I-737J-1277D01*
G02X337098I-1113J1927D01*
G03X335624I-737J-1277D01*
G02X333398I-1113J1927D01*
G02X332937Y1039766I1111J1928D01*
G01X331921Y1040782D01*
Y1042089D01*
X330283Y1043727D01*
Y1045316D01*
X329094Y1046505D01*
X326926D01*
G01X380762Y1038136D02*
X379530D01*
X379271Y1037877D01*
G02X378174Y1036209I-2210J259D01*
G02X375972Y1036195I-1113J1927D01*
G01X375949Y1036208D01*
X375926Y1036222D01*
G03X374474Y1036209I-715J-1291D01*
G02X372272Y1036195I-1113J1927D01*
G01X372249Y1036208D01*
X372226Y1036222D01*
G03X370774Y1036209I-715J-1291D01*
G02X368572Y1036195I-1113J1927D01*
G01X368549Y1036208D01*
X368526Y1036222D01*
G03X367074Y1036209I-715J-1291D01*
G02X364872Y1036195I-1113J1927D01*
G01X364849Y1036208D01*
X364826Y1036222D01*
G03X363374Y1036209I-715J-1291D01*
G02X361172Y1036195I-1113J1927D01*
G01X361149Y1036208D01*
X361126Y1036222D01*
G03X359674Y1036209I-715J-1291D01*
G02X357472Y1036195I-1113J1927D01*
G01X357449Y1036208D01*
X357426Y1036222D01*
G03X355974Y1036209I-715J-1291D01*
G02X353763Y1036200I-1113J1927D01*
G01X353749Y1036208D01*
G03X352274I-738J-1277D01*
G02X350067Y1036198I-1112J1927D01*
G01X350049Y1036208D01*
X350026Y1036222D01*
G03X348574Y1036209I-715J-1291D01*
G01Y1036208D01*
G02X346348I-1113J1928D01*
G03X344874I-737J-1277D01*
G02X342648I-1113J1928D01*
G03X341174I-737J-1277D01*
G02X338948I-1113J1928D01*
G03X337474I-737J-1277D01*
G02X335248I-1113J1928D01*
G03X333886Y1036267I-738J-1277D01*
G02X332703Y1036239I-623J1335D01*
G01X331952Y1036546D01*
G02X331663Y1036738I332J813D01*
G01X330729Y1037672D01*
Y1039445D01*
X327974Y1042200D01*
X326926D01*
G01X382611Y1047749D02*
G03X381298Y1047404I-1J-2666D01*
G01X379626Y1046458D01*
G02X378174Y1046471I-715J1290D01*
G03X375972Y1046484I-1112J-1927D01*
G01X375926Y1046458D01*
G02X374474Y1046471I-715J1290D01*
G02X373736Y1047037I1782J3087D01*
G02X373451Y1047463I929J930D01*
G01X373339Y1047734D01*
G03X372766Y1048726I-1145J0D01*
G01X372248Y1049025D01*
G03X370774I-737J-1276D01*
G01X370716Y1048991D01*
G02X368548Y1049025I-1054J1961D01*
G03X367074I-737J-1276D01*
G01X367016Y1048991D01*
G02X364848Y1049025I-1054J1961D01*
G03X363374I-737J-1276D01*
G01X363316Y1048991D01*
G02X361148Y1049025I-1054J1961D01*
G03X359674I-737J-1276D01*
G02X357448I-1113J1927D01*
G03X355974I-737J-1276D01*
G02X353748I-1113J1927D01*
G03X352274I-737J-1276D01*
G02X350048I-1113J1927D01*
G03X348574I-737J-1276D01*
G02X346348I-1113J1927D01*
G03X344874I-737J-1276D01*
G02X342648I-1113J1927D01*
G03X341174I-737J-1276D01*
G02X338948I-1113J1927D01*
G03X337474I-737J-1276D01*
G02X335248I-1113J1927D01*
G02X334136Y1050913I1113J1927D01*
G01Y1050952D01*
G03X333433Y1052209I-1475J0D01*
G02X332937Y1052583I1079J1947D01*
G01X332483Y1053037D01*
Y1054778D01*
X330255Y1057006D01*
X326926D01*
G01X380762Y1044544D02*
X381993D01*
X382219Y1044318D01*
G02X380025Y1043267I-1457J225D01*
G03X377857Y1043301I-1114J-1927D01*
G01X377799Y1043267D01*
G02X376325I-737J1277D01*
G03X374157Y1043301I-1114J-1927D01*
G01X374099Y1043267D01*
G02X372625I-737J1277D01*
G03X370457Y1043301I-1114J-1927D01*
G01X370399Y1043267D01*
G02X368925I-737J1277D01*
G03X366757Y1043301I-1114J-1927D01*
G01X366699Y1043267D01*
G02X365225I-737J1277D01*
G03X363039Y1043291I-1114J-1927D01*
G01X362998Y1043267D01*
G02X361524I-737J1277D01*
G01X361483Y1043291D01*
G03X359299Y1043267I-1071J-1951D01*
G02X357825I-737J1277D01*
G03X355639Y1043291I-1114J-1927D01*
G01X355598Y1043267D01*
G02X354124I-737J1277D01*
G03X351898I-1113J-1927D01*
G02X350424I-737J1277D01*
G03X348198I-1113J-1927D01*
G02X346724I-737J1277D01*
G03X344498I-1113J-1927D01*
G02X343024I-737J1277D01*
G03X340798I-1113J-1927D01*
G02X339324I-737J1277D01*
G03X337098I-1113J-1927D01*
G02X334886Y1044544I-737J1277D01*
G01Y1044583D01*
G03X333774Y1046471I-2225J-39D01*
G02X333467Y1046705I733J1281D01*
G01X328653Y1051519D01*
X327254D01*
X327018Y1051755D01*
X326926D01*
G01X384462Y1044544D02*
X383231D01*
X382972Y1044285D01*
G02X382961Y1044203I-2210J255D01*
G02X381898Y1042631I-2199J341D01*
G01X381877Y1042619D01*
X381874Y1042617D01*
X381816Y1042583D01*
G02X379648Y1042617I-1054J1961D01*
G03X378174I-737J-1277D01*
G01X378116Y1042583D01*
G02X375948Y1042617I-1054J1961D01*
G03X374474I-737J-1277D01*
G01X374416Y1042583D01*
G02X372248Y1042617I-1054J1961D01*
G03X370774I-737J-1277D01*
G01X370716Y1042583D01*
G02X368548Y1042617I-1054J1961D01*
G03X367074I-737J-1277D01*
G01X367016Y1042583D01*
G02X364848Y1042617I-1054J1961D01*
G03X363374I-737J-1277D01*
G02X361190Y1042593I-1113J1927D01*
G01X361149Y1042617D01*
G03X359675I-737J-1277D01*
G01X359634Y1042593D01*
G02X357448Y1042617I-1072J1951D01*
G03X355974I-737J-1277D01*
G02X353748I-1113J1927D01*
G03X352274I-737J-1277D01*
G02X350048I-1113J1927D01*
G03X348574I-737J-1277D01*
G02X346348I-1113J1927D01*
G03X344874I-737J-1277D01*
G02X342648I-1113J1927D01*
G03X341174I-737J-1277D01*
G02X338948I-1113J1927D01*
G03X337474I-737J-1277D01*
G02X334136Y1044505I-1113J1927D01*
G01Y1044544D01*
G03X333433Y1045801I-1475J0D01*
G01X333398Y1045821D01*
G02X332937Y1046175I1114J1928D01*
G01X328342Y1050770D01*
X327253D01*
X327018Y1050535D01*
X326926D01*
G01X380762Y1050952D02*
X378293Y1049093D01*
X378174Y1049025D01*
X378116Y1048991D01*
G02X375948Y1049025I-1054J1961D01*
G02X374837Y1050891I1114J1927D01*
G01Y1050952D01*
G03X374134Y1052209I-1475J0D01*
G01X374099Y1052229D01*
G03X372625I-737J-1277D01*
G02X370457Y1052195I-1115J1928D01*
G01X370399Y1052229D01*
G03X368925I-737J-1277D01*
G02X366757Y1052195I-1115J1928D01*
G01X366699Y1052229D01*
G03X365225I-737J-1277D01*
G02X363057Y1052195I-1115J1928D01*
G01X362999Y1052229D01*
G03X361525I-737J-1277D01*
G02X359339Y1052205I-1114J1928D01*
G01X359298Y1052229D01*
G03X357824I-737J-1277D01*
G01X357766Y1052195D01*
G02X355598Y1052229I-1053J1962D01*
G03X354124I-737J-1277D01*
G02X351940Y1052205I-1113J1928D01*
G01X351898Y1052229D01*
G03X350424I-737J-1277D01*
G02X348198I-1113J1928D01*
G03X346724I-737J-1277D01*
G02X344498I-1113J1928D01*
G03X343024I-737J-1277D01*
G02X340798I-1113J1928D01*
G03X339324I-737J-1277D01*
G02X337098I-1113J1928D01*
G02X335986Y1054084I1113J1928D01*
G01Y1054157D01*
G03X335283Y1055414I-1475J0D01*
G02X334787Y1055787I1077J1948D01*
G01X329248Y1061326D01*
X326926D01*
G01X380762Y1057361D02*
X379531D01*
X379272Y1057102D01*
G02X378198Y1055448I-2210J259D01*
G01X378174Y1055434D01*
X378116Y1055400D01*
G02X375948Y1055434I-1054J1961D01*
G03X374474I-737J-1277D01*
G02X372248I-1113J1927D01*
G03X370774I-737J-1277D01*
G01X370716Y1055400D01*
G02X368548Y1055434I-1054J1961D01*
G03X367074I-737J-1277D01*
G01X367016Y1055400D01*
G02X364848Y1055434I-1054J1961D01*
G03X363374I-737J-1277D01*
G01X363316Y1055400D01*
G02X361148Y1055434I-1054J1961D01*
G03X359674I-737J-1277D01*
G01X359633Y1055410D01*
G02X357449Y1055434I-1071J1951D01*
G03X355975I-737J-1277D01*
G02X353789Y1055410I-1114J1927D01*
G01X353748Y1055434D01*
G03X352274I-737J-1277D01*
G02X350048I-1113J1927D01*
G03X348574I-737J-1277D01*
G02X346348I-1113J1927D01*
G03X344874I-737J-1277D01*
G02X342648I-1113J1927D01*
G03X341174I-737J-1277D01*
G02X338948I-1113J1927D01*
G02X337836Y1057322I1113J1927D01*
G01Y1057361D01*
G03X337133Y1058618I-1475J0D01*
G02X336637Y1058991I1077J1948D01*
G01X335108Y1060520D01*
X332770D01*
X331425Y1061865D01*
Y1064381D01*
X329128Y1066678D01*
X328122D01*
G01X382611Y1060565D02*
X380413Y1058866D01*
X380086Y1058674D01*
G02X377846Y1058668I-1125J1921D01*
G03X376367Y1058663I-735J-1274D01*
G01X376266Y1058604D01*
G02X374098Y1058638I-1054J1961D01*
G03X372624I-737J-1277D01*
G02X370440Y1058614I-1113J1927D01*
G01X370399Y1058638D01*
G03X368925I-737J-1277D01*
G02X366757Y1058604I-1114J1927D01*
G01X366699Y1058638D01*
G03X365225I-737J-1277D01*
G02X363057Y1058604I-1114J1927D01*
G01X362999Y1058638D01*
G03X361525I-737J-1277D01*
G02X359299I-1113J1927D01*
G03X357825I-737J-1277D01*
G02X355639Y1058614I-1114J1927D01*
G01X355598Y1058638D01*
G03X354124I-737J-1277D01*
G02X351898I-1113J1927D01*
G03X350424I-737J-1277D01*
G02X348198I-1113J1927D01*
G03X346724I-737J-1277D01*
G02X344498I-1113J1927D01*
G03X343024I-737J-1277D01*
G02X340798I-1113J1927D01*
G02X339686Y1060526I1113J1927D01*
G01Y1060565D01*
G03X338983Y1061822I-1475J0D01*
G02X338487Y1062196I1079J1947D01*
G01X337763Y1062920D01*
X336370D01*
X334622Y1064668D01*
X333597D01*
X330105Y1068160D01*
Y1069662D01*
X329040Y1070727D01*
X328122D01*
G01X384462Y1063770D02*
X381617Y1064979D01*
X381507Y1065043D01*
X381499Y1065047D01*
G03X380025I-737J-1277D01*
G01X379990Y1065027D01*
G03X379287Y1063770I772J-1257D01*
G01Y1063384D01*
X379206Y1063306D01*
X377798Y1062493D01*
X377799D01*
G02X376325I-737J1277D01*
G03X374157Y1062527I-1115J-1928D01*
G01X374099Y1062493D01*
G02X372625I-737J1277D01*
G03X370457Y1062527I-1115J-1928D01*
G01X370399Y1062493D01*
G02X368925I-737J1277D01*
G03X366757Y1062527I-1115J-1928D01*
G01X366699Y1062493D01*
G02X365225I-737J1277D01*
G03X363039Y1062517I-1114J-1928D01*
G01X362998Y1062493D01*
G02X361524I-737J1277D01*
G01X361483Y1062517D01*
G03X359299Y1062493I-1071J-1952D01*
G02X357825I-737J1277D01*
G03X355639Y1062517I-1114J-1928D01*
G01X355598Y1062493D01*
G02X354124I-737J1277D01*
G03X351898I-1113J-1928D01*
G02X350424I-737J1277D01*
G03X348198I-1113J-1928D01*
G02X346724I-737J1277D01*
G03X344498I-1113J-1928D01*
G02X343024I-737J1277D01*
G01X342989Y1062513D01*
G02X342286Y1063770I772J1257D01*
G01Y1063809D01*
G03X341174Y1065697I-2225J-39D01*
G03X338948I-1113J-1927D01*
G02X337474I-737J1277D01*
G01X337439Y1065717D01*
G02X336736Y1066974I772J1257D01*
G01Y1066993D01*
X336735Y1066994D01*
G03X334513Y1069199I-2225J-20D01*
G01X333721D01*
X332398Y1070522D01*
Y1071414D01*
X330641Y1073171D01*
Y1074695D01*
X329540Y1075796D01*
X328450D01*
X328214Y1076032D01*
X328122D01*
G01X380762Y1063770D02*
X379662Y1062703D01*
X378186Y1061850D01*
X378183Y1061848D01*
X378116Y1061809D01*
G02X375948Y1061843I-1054J1961D01*
G01Y1061842D01*
G03X374474I-737J-1277D01*
G01X374416Y1061808D01*
G02X372248Y1061842I-1053J1962D01*
G03X370774I-737J-1277D01*
G01X370716Y1061808D01*
G02X368548Y1061842I-1053J1962D01*
G03X367074I-737J-1277D01*
G01X367016Y1061808D01*
G02X364848Y1061842I-1053J1962D01*
G03X363374I-737J-1277D01*
G02X361190Y1061818I-1113J1928D01*
G01X361149Y1061842D01*
G03X359675I-737J-1277D01*
G01X359634Y1061818D01*
G02X357448Y1061842I-1072J1952D01*
G03X355974I-737J-1277D01*
G02X353748I-1113J1928D01*
G03X352274I-737J-1277D01*
G02X350048I-1113J1928D01*
G03X348574I-737J-1277D01*
G02X346348I-1113J1928D01*
G03X344874I-737J-1277D01*
G02X342648I-1113J1928D01*
G02X341536Y1063697I1113J1928D01*
G01Y1063770D01*
G03X340833Y1065027I-1475J0D01*
G01X340798Y1065047D01*
G03X339324I-737J-1277D01*
G02X337098I-1113J1927D01*
G02X335986Y1066935I1113J1927D01*
G01Y1066974D01*
G03X334512Y1068450I-1476J0D01*
G01X333410D01*
X331649Y1070211D01*
Y1071103D01*
X329892Y1072860D01*
Y1074384D01*
X329229Y1075047D01*
X328449D01*
X328214Y1074812D01*
X328122D01*
G01X380762Y1070178D02*
X378293Y1068319D01*
X378174Y1068251D01*
X378116Y1068217D01*
G02X375948Y1068251I-1054J1961D01*
G02X374837Y1070117I1114J1927D01*
G01Y1070178D01*
G03X374134Y1071435I-1475J0D01*
G01X374099Y1071455D01*
G03X372625I-737J-1277D01*
G02X370457Y1071421I-1115J1928D01*
G01X370399Y1071455D01*
G03X368925I-737J-1277D01*
G02X366757Y1071421I-1115J1928D01*
G01X366699Y1071455D01*
G03X365225I-737J-1277D01*
G02X363057Y1071421I-1115J1928D01*
G01X362999Y1071455D01*
G03X361525I-737J-1277D01*
G02X359339Y1071431I-1114J1928D01*
G01X359298Y1071455D01*
G03X357824I-737J-1277D01*
G01X357766Y1071421D01*
G02X355598Y1071455I-1053J1962D01*
G03X354124I-737J-1277D01*
G02X351940Y1071431I-1113J1928D01*
G01X351899Y1071455D01*
G03X350425I-737J-1277D01*
G01X350384Y1071431D01*
G02X348198Y1071455I-1072J1952D01*
G02X347086Y1073327I1114J1928D01*
G01Y1073383D01*
G03X346383Y1074640I-1475J0D01*
G01X346348Y1074660D01*
G03X344874I-737J-1277D01*
G02X342690Y1074636I-1113J1927D01*
G01X342649Y1074660D01*
X342625Y1074674D01*
G02X341536Y1076587I1136J1913D01*
G01Y1076621D01*
G03X340799Y1077864I-1474J-34D01*
G03X339325I-737J-1277D01*
G02X337157Y1077830I-1114J1927D01*
G01X337099Y1077864D01*
G02X335999Y1078635I3860J6678D01*
G01X335775Y1078859D01*
Y1080106D01*
X333946Y1081935D01*
X332657D01*
X329034Y1085558D01*
X328122D01*
G01X382611Y1066974D02*
G03X381295Y1066628I-1J-2670D01*
G01X379626Y1065684D01*
G02X378174Y1065697I-715J1290D01*
G03X375972Y1065710I-1112J-1927D01*
G01X375926Y1065684D01*
G02X374474Y1065697I-715J1290D01*
G02X373736Y1066263I1782J3087D01*
G02X373451Y1066689I929J930D01*
G01X373339Y1066960D01*
G03X373081Y1067583I-881J0D01*
G01X372956Y1067709D01*
G03X372251Y1068250I-2405J-2405D01*
G01X372249Y1068251D01*
G03X370775I-737J-1277D01*
G01X370734Y1068227D01*
G02X368548Y1068251I-1072J1951D01*
G03X367074I-737J-1277D01*
G01X367016Y1068217D01*
G02X364848Y1068251I-1054J1961D01*
G03X363374I-737J-1277D01*
G01X363316Y1068217D01*
G02X361148Y1068251I-1054J1961D01*
G03X359674I-737J-1277D01*
G02X357448I-1113J1927D01*
G03X355974I-737J-1277D01*
G02X353748I-1113J1927D01*
G03X352274I-737J-1277D01*
G01X352216Y1068217D01*
G02X350048Y1068251I-1054J1961D01*
G03X348574I-737J-1277D01*
G02X346348I-1113J1927D01*
G02X345236Y1070139I1113J1927D01*
G01Y1070178D01*
G03X344533Y1071435I-1475J0D01*
G01X344498Y1071455D01*
G03X343024I-737J-1277D01*
G01X342966Y1071421D01*
G02X340798Y1071455I-1053J1962D01*
G02X339686Y1073327I1114J1928D01*
G01Y1073383D01*
G03X338983Y1074640I-1475J0D01*
G01X338948Y1074660D01*
G03X337474I-737J-1277D01*
G01X337433Y1074636D01*
G02X335249Y1074660I-1071J1951D01*
G02X334788Y1075013I1111J1928D01*
G01X334518Y1075665D01*
Y1077376D01*
X330323Y1081571D01*
X328122D01*
G01X390011Y1002888D02*
X387268Y1001727D01*
X387126Y1001654D01*
X387025Y1001597D01*
X386892Y1001515D01*
X386698Y1001365D01*
X386522Y1001194D01*
X386366Y1001004D01*
X386232Y1000798D01*
X386121Y1000579D01*
X386035Y1000349D01*
X385975Y1000112D01*
X385941Y999868D01*
X385937Y999715D01*
Y998287D01*
X383970Y996320D01*
Y995202D01*
G01X393711Y1002888D02*
X391779Y1002019D01*
G02X388979Y1001189I-2131J2051D01*
G03X387424Y1000961I-487J-2098D01*
G01X387389Y1000941D01*
G03X386686Y999684I772J-1257D01*
G01Y997636D01*
X385952Y996902D01*
Y995202D01*
G01X388162Y999684D02*
X388161Y996189D01*
Y995202D01*
G01X395562Y999684D02*
X394170Y998292D01*
Y995202D01*
G01X398829Y973143D02*
X396109Y975015D01*
G02X395840Y975238I1083J1580D01*
G01X395452Y975626D01*
G02X395259Y975915I634J632D01*
G03X394015Y977624I-2545J-545D01*
G03X392541I-737J-1277D01*
G01X392483Y977590D01*
G02X390315Y977624I-1053J1962D01*
G03X388841I-737J-1277D01*
G01X388800Y977600D01*
G02X386616Y977624I-1071J1952D01*
G03X385142I-737J-1277D01*
G01X385101Y977600D01*
G02X382915Y977624I-1072J1952D01*
G03X381441I-737J-1277D01*
G01X381400Y977600D01*
G02X379216Y977624I-1071J1952D01*
G03X377742I-737J-1277D01*
G01X377701Y977600D01*
G02X375515Y977624I-1072J1952D01*
G03X374041I-737J-1277D01*
G02X371815I-1113J1928D01*
G03X370341I-737J-1277D01*
G01X370283Y977590D01*
G02X368115Y977624I-1053J1962D01*
G03X366641I-737J-1277D01*
G01X366583Y977590D01*
G02X364415Y977624I-1053J1962D01*
G03X362941I-737J-1277D01*
G01X362900Y977600D01*
G02X360716Y977624I-1071J1952D01*
G03X359242I-737J-1277D01*
G01X359201Y977600D01*
G02X357015Y977624I-1072J1952D01*
G03X355541I-737J-1277D01*
G01X355500Y977600D01*
G02X353316Y977624I-1071J1952D01*
G03X351842I-737J-1277D01*
G01X351801Y977600D01*
G02X349615Y977624I-1072J1952D01*
G03X348141I-737J-1277D01*
G01X348100Y977600D01*
G02X345916Y977624I-1071J1952D01*
G03X344442I-737J-1277D01*
G02X342216I-1113J1928D01*
G02X341104Y979479I1113J1928D01*
G01Y979552D01*
G03X340401Y980809I-1475J0D01*
G01X340366Y980829D01*
G03X338892I-737J-1277D01*
G02X336724Y980795I-1114J1927D01*
G01X336666Y980829D01*
G02X336205Y981183I1113J1926D01*
G01X335902Y981486D01*
X328821D01*
G01X402529Y979552D02*
X399879Y978455D01*
X399877D01*
X399565Y978275D01*
G02X398091I-737J1277D01*
G03X395907Y978299I-1113J-1928D01*
G01X395866Y978275D01*
G02X394392I-737J1277D01*
G03X392224Y978309I-1115J-1928D01*
G01X392166Y978275D01*
G02X390692I-737J1277D01*
G03X388524Y978309I-1115J-1928D01*
G01X388497Y978293D01*
X388466Y978275D01*
G02X386992I-737J1277D01*
G03X384766I-1113J-1928D01*
G02X383292I-737J1277D01*
G03X381124Y978309I-1115J-1928D01*
G01X381066Y978275D01*
G02X379592I-737J1277D01*
G03X377366I-1113J-1928D01*
G02X375892I-737J1277D01*
G03X373706Y978299I-1114J-1928D01*
G01X373665Y978275D01*
G02X372191I-737J1277D01*
G03X370007Y978299I-1113J-1928D01*
G01X369966Y978275D01*
G02X368492I-737J1277D01*
G03X366324Y978309I-1115J-1928D01*
G01X366266Y978275D01*
G02X364792I-737J1277D01*
G03X362624Y978309I-1115J-1928D01*
G01X362566Y978275D01*
G02X361092I-737J1277D01*
G03X358866I-1113J-1928D01*
G02X357392I-737J1277D01*
G03X355224Y978309I-1115J-1928D01*
G01X355166Y978275D01*
G02X353692I-737J1277D01*
G03X351466I-1113J-1928D01*
G02X349992I-737J1277D01*
G03X347824Y978309I-1115J-1928D01*
G01X347766Y978275D01*
G02X346292I-737J1277D01*
G03X344066I-1113J-1928D01*
G02X342592I-737J1277D01*
G01X342557Y978295D01*
G02X341854Y979552I772J1257D01*
G03X340765Y981465I-2225J0D01*
G01X340741Y981479D01*
X340683Y981513D01*
G03X338515Y981479I-1054J-1961D01*
G02X337041I-737J1277D01*
G02X336735Y981713I735J1278D01*
G01X334492Y983956D01*
X328821D01*
G01X400678Y976347D02*
X401294Y975280D01*
X401199Y974929D01*
G03X400304Y973204I1330J-1785D01*
G01Y973143D01*
G02X399601Y971886I-1475J0D01*
G01X399566Y971866D01*
G02X398092I-737J1277D01*
G03X395866I-1113J-1927D01*
G02X394392I-737J1277D01*
G01X394357Y971886D01*
G02X393654Y973143I772J1257D01*
G03X392565Y975056I-2225J0D01*
G01X392541Y975070D01*
X392483Y975104D01*
G03X390315Y975070I-1054J-1961D01*
G02X388841I-737J1277D01*
G03X386657Y975094I-1113J-1927D01*
G01X386616Y975070D01*
G02X385142I-737J1277D01*
G01X385101Y975094D01*
G03X382915Y975070I-1072J-1951D01*
G02X381441I-737J1277D01*
G03X379257Y975094I-1113J-1927D01*
G01X379216Y975070D01*
G02X377742I-737J1277D01*
G01X377701Y975094D01*
G03X375515Y975070I-1072J-1951D01*
G02X374041I-737J1277D01*
G01X373983Y975104D01*
G03X371815Y975070I-1054J-1961D01*
G02X370341I-737J1277D01*
G01X370283Y975104D01*
G03X368115Y975070I-1054J-1961D01*
G02X366641I-737J1277D01*
G01X366583Y975104D01*
G03X364415Y975070I-1054J-1961D01*
G02X362941I-737J1277D01*
G03X360757Y975094I-1113J-1927D01*
G01X360716Y975070D01*
G02X359242I-737J1277D01*
G01X359201Y975094D01*
G03X357015Y975070I-1072J-1951D01*
G02X355541I-737J1277D01*
G03X353357Y975094I-1113J-1927D01*
G01X353316Y975070D01*
G02X351842I-737J1277D01*
G01X351801Y975094D01*
G03X349615Y975070I-1072J-1951D01*
G02X348141I-737J1277D01*
G01X348100Y975094D01*
G03X345916Y975070I-1071J-1951D01*
G02X344442I-737J1277D01*
G03X342216I-1113J-1927D01*
G02X340742I-737J1277D01*
G03X338516I-1113J-1927D01*
G02X337042I-737J1277D01*
G03X334816I-1113J-1927D01*
G02X333342I-737J1277D01*
G02X333035Y975303I731J1282D01*
G01X331174Y977164D01*
X330141Y977592D01*
X328821D01*
G01X402529Y973143D02*
X401913Y974210D01*
X401605Y974292D01*
G03X401054Y973143I924J-1150D01*
G02X399965Y971230I-2225J0D01*
G01X399941Y971216D01*
X399900Y971192D01*
G02X397716Y971216I-1071J1951D01*
G03X396242I-737J-1277D01*
G01X396201Y971192D01*
G02X394015Y971216I-1072J1951D01*
G02X392904Y973082I1114J1927D01*
G01Y973143D01*
G03X392201Y974400I-1475J0D01*
G01X392166Y974420D01*
G03X390692I-737J-1277D01*
G02X388506Y974396I-1114J1927D01*
G01X388497Y974401D01*
X388465Y974420D01*
G03X386991I-737J-1277D01*
G01X386950Y974396D01*
G02X384766Y974420I-1071J1951D01*
G03X383292I-737J-1277D01*
G02X381106Y974396I-1114J1927D01*
G01X381065Y974420D01*
G03X379591I-737J-1277D01*
G01X379550Y974396D01*
G02X377366Y974420I-1071J1951D01*
G03X375892I-737J-1277D01*
G02X373724Y974386I-1114J1927D01*
G01X373666Y974420D01*
G03X372192I-737J-1277D01*
G02X370024Y974386I-1114J1927D01*
G01X369966Y974420D01*
G03X368492I-737J-1277D01*
G02X366324Y974386I-1114J1927D01*
G01X366266Y974420D01*
G03X364792I-737J-1277D01*
G02X362606Y974396I-1114J1927D01*
G01X362565Y974420D01*
G03X361091I-737J-1277D01*
G01X361050Y974396D01*
G02X358866Y974420I-1071J1951D01*
G03X357392I-737J-1277D01*
G02X355206Y974396I-1114J1927D01*
G01X355165Y974420D01*
G03X353691I-737J-1277D01*
G01X353650Y974396D01*
G02X351466Y974420I-1071J1951D01*
G03X349992I-737J-1277D01*
G02X347824Y974386I-1114J1927D01*
G01X347766Y974420D01*
G03X346292I-737J-1277D01*
G02X344066I-1113J1927D01*
G03X342592I-737J-1277D01*
G02X340366I-1113J1927D01*
G03X338892I-737J-1277D01*
G02X336666I-1113J1927D01*
G03X335192I-737J-1277D01*
G02X332966I-1113J1927D01*
G02X332505Y974773I1111J1928D01*
G01X331118Y976160D01*
X328821D01*
G01X548867Y883785D02*
X546813Y885839D01*
Y886949D01*
X545668Y888094D01*
Y888095D01*
X539153Y894610D01*
G03X538692Y894963I-1572J-1575D01*
G03X536466I-1113J-1927D01*
G02X534992I-737J1277D01*
G03X532766I-1113J-1927D01*
G02X531292I-737J1277D01*
G03X529124Y894997I-1114J-1927D01*
G01X529066Y894963D01*
G02X527592I-737J1277D01*
G03X525366I-1113J-1927D01*
G02X523892I-737J1277D01*
G03X521724Y894997I-1114J-1927D01*
G01X521666Y894963D01*
G02X520192I-737J1277D01*
G03X518024Y894997I-1114J-1927D01*
G01X517966Y894963D01*
G02X516492I-737J1277D01*
G03X514266I-1113J-1927D01*
G02X512792I-737J1277D01*
G03X510624Y894997I-1114J-1927D01*
G01X510566Y894963D01*
G02X509092I-737J1277D01*
G01X509057Y894983D01*
G02X508354Y896240I772J1257D01*
G01Y896270D01*
G03X507241Y898168I-2226J-30D01*
G01X507206Y898188D01*
G02X506503Y899445I772J1257D01*
G01Y899506D01*
G03X505392Y901372I-2225J-61D01*
G03X502995Y901235I-1094J-1893D01*
G01X500578Y899445D01*
G01X551423Y904731D02*
X550604D01*
X550226Y905109D01*
Y906516D01*
X549351Y907391D01*
X547943D01*
X544703Y910631D01*
G03X542016Y910985I-1574J-1574D01*
G02X540542I-737J1277D01*
G03X538316I-1113J-1928D01*
G02X536842I-737J1277D01*
G03X534616I-1113J-1928D01*
G02X533142I-737J1277D01*
G03X530916I-1113J-1928D01*
G02X529442I-737J1277D01*
G03X527216I-1113J-1928D01*
G02X525742I-737J1277D01*
G01X525701Y911009D01*
G03X523515Y910985I-1072J-1952D01*
G02X522041I-737J1277D01*
G03X519815I-1113J-1928D01*
G02X518341I-737J1277D01*
G01X518306Y911005D01*
G02X517603Y912262I772J1257D01*
G01Y912323D01*
G03X516492Y914189I-2225J-61D01*
G03X514324Y914223I-1114J-1927D01*
G01X514266Y914189D01*
G02X512792I-737J1277D01*
G03X510624Y914223I-1114J-1927D01*
G01X510566Y914189D01*
G02X509092I-737J1277D01*
G03X506866I-1113J-1927D01*
G02X505392I-737J1277D01*
G03X503224Y914223I-1114J-1927D01*
G01X503166Y914189D01*
X503047Y914121D01*
X500578Y912262D01*
G01X548323Y900764D02*
X547774D01*
X547161Y901377D01*
Y903119D01*
X542853Y907427D01*
G03X542392Y907780I-1572J-1575D01*
G03X540166I-1113J-1927D01*
G02X538692I-737J1277D01*
G03X536466I-1113J-1927D01*
G02X534992I-737J1277D01*
G03X532766I-1113J-1927D01*
G02X531292I-737J1277D01*
G03X529066I-1113J-1927D01*
G02X527592I-737J1277D01*
G03X525366I-1113J-1927D01*
G02X523892I-737J1277D01*
G03X521706Y907804I-1114J-1927D01*
G01X521665Y907780D01*
G02X520191I-737J1277D01*
G01X520150Y907804D01*
G03X517966Y907780I-1071J-1951D01*
G02X516492I-737J1277D01*
G01X516457Y907800D01*
G02X515754Y909057I772J1257D01*
G01Y909113D01*
G03X514641Y910985I-2225J-56D01*
G01X514583Y911019D01*
G03X512415Y910985I-1053J-1962D01*
G02X510941I-737J1277D01*
G01X510900Y911009D01*
G03X508716Y910985I-1071J-1952D01*
G02X507242I-737J1277D01*
G01X507201Y911009D01*
G03X505015Y910985I-1072J-1952D01*
G02X503541I-737J1277D01*
G01X503483Y911019D01*
G03X501315Y910985I-1053J-1962D01*
G01X501206Y910923D01*
X498989Y909253D01*
X498729Y909057D01*
G01X550847Y887795D02*
X550352Y888290D01*
X549922D01*
X545818Y892394D01*
X545389Y893428D01*
X541003Y897814D01*
G03X540542Y898168I-1575J-1574D01*
G03X538316I-1113J-1928D01*
G02X536842I-737J1277D01*
G03X534616I-1113J-1928D01*
G02X533142I-737J1277D01*
G01X533101Y898192D01*
G03X530915Y898168I-1072J-1952D01*
G02X529441I-737J1277D01*
G01X529400Y898192D01*
G03X527216Y898168I-1071J-1952D01*
G02X525742I-737J1277D01*
G03X523516I-1113J-1928D01*
G02X522042I-737J1277D01*
G01X522001Y898192D01*
G03X519815Y898168I-1072J-1952D01*
G02X518341I-737J1277D01*
G01X518283Y898202D01*
G03X516115Y898168I-1053J-1962D01*
G02X514641I-737J1277D01*
G01X514583Y898202D01*
G03X512415Y898168I-1053J-1962D01*
G02X510941I-737J1277D01*
G01X510906Y898188D01*
G02X510203Y899445I772J1257D01*
G01Y899484D01*
G03X509091Y901372I-2225J-39D01*
G02X508427Y902190I737J1277D01*
G01X507543Y903151D01*
G03X506866Y903926I-1509J-635D01*
G03X505392I-737J-1277D01*
G02X503224Y903892I-1114J1927D01*
G01X503166Y903926D01*
G03X501692I-737J-1277D01*
G01X501579Y903860D01*
X498729Y902649D01*
G01X548323Y895563D02*
X548231D01*
X547996Y895798D01*
X547181D01*
X543986Y898993D01*
Y901702D01*
X542061Y903627D01*
X541279D01*
G02X541086Y903635I-4J2226D01*
G02X540166Y903926I195J2218D01*
G03X538692I-737J-1277D01*
G02X536466I-1113J1927D01*
G03X534992I-737J-1277D01*
G02X532766I-1113J1927D01*
G03X531292I-737J-1277D01*
G02X529066I-1113J1927D01*
G03X527592I-737J-1277D01*
G02X525366I-1113J1927D01*
G03X523892I-737J-1277D01*
G02X521724Y903892I-1114J1927D01*
G01X521666Y903926D01*
G03X520192I-737J-1277D01*
G02X517966I-1113J1927D01*
G03X516492I-737J-1277D01*
G02X514324Y903892I-1114J1927D01*
G01X514266Y903926D01*
X514263Y903928D01*
X514242Y903940D01*
G02X513153Y905853I1136J1913D01*
G03X512450Y907110I-1475J0D01*
G01X512415Y907130D01*
G03X510941I-737J-1277D01*
G01X510883Y907096D01*
G02X508715Y907130I-1054J1961D01*
G03X507241I-737J-1277D01*
G01X507183Y907096D01*
G02X505015Y907130I-1054J1961D01*
G03X503541I-737J-1277D01*
G01X503483Y907096D01*
G02X501315Y907130I-1054J1961D01*
G03X499841I-737J-1277D01*
G01X499835Y907127D01*
X499806Y907110D01*
G03X499121Y906078I773J-1256D01*
G01X499346Y905853D01*
X500578D01*
G01X548323Y896783D02*
X548231D01*
X547995Y896547D01*
X547492D01*
X544735Y899304D01*
Y902013D01*
X542372Y904376D01*
X541279D01*
G02X541153Y904382I7J1476D01*
G02X540542Y904576I130J1470D01*
G03X538316I-1113J-1927D01*
G02X536842I-737J1277D01*
G03X534616I-1113J-1927D01*
G02X533142I-737J1277D01*
G03X530916I-1113J-1927D01*
G02X529442I-737J1277D01*
G03X527216I-1113J-1927D01*
G02X525742I-737J1277D01*
G01X525701Y904600D01*
G03X523515Y904576I-1072J-1951D01*
G02X522041I-737J1277D01*
G01X522000Y904600D01*
G03X519816Y904576I-1071J-1951D01*
G02X518342I-737J1277D01*
G01X518301Y904600D01*
G03X516115Y904576I-1072J-1951D01*
G02X514641I-737J1277D01*
G01X514635Y904579D01*
X514606Y904596D01*
G02X513903Y905853I772J1257D01*
G01Y905914D01*
G03X512792Y907780I-2225J-61D01*
G03X510624Y907814I-1114J-1927D01*
G01X510566Y907780D01*
G02X509092I-737J1277D01*
G03X506924Y907814I-1114J-1927D01*
G01X506866Y907780D01*
G02X505392I-737J1277D01*
G03X503224Y907814I-1114J-1927D01*
G01X503166Y907780D01*
G02X501692I-737J1277D01*
G03X499524Y907814I-1114J-1927D01*
G01X499466Y907780D01*
X499463Y907778D01*
X499442Y907766D01*
G03X498368Y906111I1136J-1913D01*
G01X498110Y905853D01*
X496878D01*
G01X552057Y926926D02*
X551184D01*
X548868Y929242D01*
X548678D01*
X548462Y929272D01*
G02X547566Y929560I218J2215D01*
G02X546453Y931432I1112J1928D01*
G01Y931488D01*
G03X545771Y932732I-1476J0D01*
G01X545715Y932764D01*
G03X544241I-737J-1276D01*
G01X544183Y932730D01*
G02X542015Y932764I-1054J1961D01*
G03X540541I-737J-1276D01*
G01X540483Y932730D01*
G02X538315Y932764I-1054J1961D01*
G03X536841I-737J-1276D01*
G01X536783Y932730D01*
G02X534615Y932764I-1054J1961D01*
G03X533141I-737J-1276D01*
G01X533100Y932740D01*
G02X530916Y932764I-1071J1951D01*
G03X529442I-737J-1276D01*
G02X527216I-1113J1927D01*
G03X525742I-737J-1276D01*
G02X523556Y932740I-1114J1927D01*
G01X523515Y932764D01*
G03X522041I-737J-1276D01*
G01X521983Y932730D01*
G02X519815Y932764I-1054J1961D01*
G03X518341I-737J-1276D01*
G01X518283Y932730D01*
G02X516115Y932764I-1054J1961D01*
G03X514641I-737J-1276D01*
G01X514583Y932730D01*
G02X512415Y932764I-1054J1961D01*
G03X510941I-737J-1276D01*
G01X510900Y932740D01*
G02X508716Y932764I-1071J1951D01*
G03X507242I-737J-1276D01*
G01X507186Y932732D01*
G03X506504Y931488I794J-1244D01*
G01Y931230D01*
X505711Y930437D01*
G02X501894Y930376I-1940J1939D01*
G01X500578Y931488D01*
G01X551867Y912518D02*
X551342D01*
X550907Y912953D01*
Y913366D01*
X548679Y915594D01*
X547838Y916499D01*
G03X546771Y916940I-1013J-941D01*
G03X546092Y916743I59J-1473D01*
G02X543866I-1113J1927D01*
G03X542392I-737J-1277D01*
G02X540166I-1113J1927D01*
G02X539054Y918631I1113J1927D01*
G01Y918670D01*
G03X538351Y919927I-1475J0D01*
G01X538316Y919947D01*
G03X536842I-737J-1277D01*
G02X534616I-1113J1928D01*
G03X533142I-737J-1277D01*
G02X530916I-1113J1928D01*
G03X529442I-737J-1277D01*
G02X527216I-1113J1928D01*
G03X525742I-737J-1277D01*
G02X523516I-1113J1928D01*
G03X522042I-737J-1277D01*
G01X522001Y919923D01*
G02X519815Y919947I-1072J1952D01*
G03X518341I-737J-1277D01*
G01X518283Y919913D01*
G02X516115Y919947I-1053J1962D01*
G03X514641I-737J-1277D01*
G01X514583Y919913D01*
G02X512415Y919947I-1053J1962D01*
G03X510941I-737J-1277D01*
G02X508715I-1113J1928D01*
G03X507241I-737J-1277D01*
G01X507183Y919913D01*
G02X505015Y919947I-1053J1962D01*
G03X503541I-737J-1277D01*
G01X503483Y919913D01*
G02X501315Y919947I-1053J1962D01*
G01X501206Y920009D01*
X498729Y921875D01*
G01X551423Y908461D02*
X549938D01*
X547170Y911229D01*
G02X547046Y911557I298J300D01*
G02X547107Y911991I2956J-194D01*
G03X546289Y913307I-1087J237D01*
G02X545716Y913539I541J2159D01*
G03X544242I-737J-1277D01*
G02X542016I-1113J1927D01*
G03X540542I-737J-1277D01*
G02X538316I-1113J1927D01*
G02X537204Y915427I1113J1927D01*
G01Y915466D01*
G03X536501Y916723I-1475J0D01*
G01X536466Y916743D01*
G03X534992I-737J-1277D01*
G02X532766I-1113J1927D01*
G03X531292I-737J-1277D01*
G02X529066I-1113J1927D01*
G03X527592I-737J-1277D01*
G01X527551Y916719D01*
G02X525365Y916743I-1072J1951D01*
G03X523891I-737J-1277D01*
G01X523850Y916719D01*
G02X521666Y916743I-1071J1951D01*
G03X520192I-737J-1277D01*
G02X518024Y916709I-1114J1927D01*
G01X517966Y916743D01*
G03X516492I-737J-1277D01*
G02X514324Y916709I-1114J1927D01*
G01X514266Y916743D01*
G03X512792I-737J-1277D01*
G02X510624Y916709I-1114J1927D01*
G01X510566Y916743D01*
G03X509092I-737J-1277D01*
G02X506924Y916709I-1114J1927D01*
G01X506866Y916743D01*
G03X505392I-737J-1277D01*
G02X503224Y916709I-1114J1927D01*
G01X503166Y916743D01*
X503142Y916757D01*
G02X502068Y918411I1136J1913D01*
G01X501809Y918670D01*
X500578D01*
G01X551424Y922991D02*
X550634D01*
X550154Y923471D01*
Y925792D01*
X549391Y926555D01*
X548678D01*
G03X547941Y926356I3J-1475D01*
G01X547883Y926322D01*
G02X545715Y926356I-1054J1961D01*
G02X544604Y928222I1114J1927D01*
G01Y928283D01*
G03X542392Y929560I-1475J0D01*
G02X540224Y929526I-1115J1928D01*
G01X540166Y929560D01*
G03X538692I-737J-1277D01*
G02X536524Y929526I-1115J1928D01*
G01X536466Y929560D01*
G03X534992I-737J-1277D01*
G02X532824Y929526I-1115J1928D01*
G01X532766Y929560D01*
G03X531292I-737J-1277D01*
G02X529066I-1113J1928D01*
G03X527592I-737J-1277D01*
G02X525366I-1113J1928D01*
G03X523892I-737J-1277D01*
G02X521706Y929536I-1114J1928D01*
G01X521665Y929560D01*
G03X520191I-737J-1277D01*
G02X518007Y929536I-1113J1928D01*
G01X517966Y929560D01*
G03X516492I-737J-1277D01*
G02X514324Y929526I-1115J1928D01*
G01X514266Y929560D01*
G03X512792I-737J-1277D01*
G02X510624Y929526I-1115J1928D01*
G01X510566Y929560D01*
G03X509092I-737J-1277D01*
G01X509109Y929571D01*
G03X508309Y928966I1782J-3188D01*
G01X508124Y928781D01*
G03X507841Y928098I683J-683D01*
G02X507615Y927557I-763J1D01*
G01X507331Y927276D01*
X506866Y927006D01*
G02X506139Y926809I-736J1277D01*
G01X504562Y926798D01*
X502315D01*
G02X498729Y928283I0J5072D01*
G01X551423Y916619D02*
X551331D01*
X551096Y916854D01*
X550361D01*
X549186Y918029D01*
G02X548728Y918641I1907J1905D01*
G03X547017Y919653I-1707J-933D01*
G02X545652Y919983I-4J2973D01*
G03X544242Y919947I-672J-1313D01*
G02X542016I-1113J1928D01*
G02X540904Y921802I1113J1928D01*
G01Y921875D01*
G03X540201Y923132I-1475J0D01*
G01X540172Y923149D01*
X540166Y923152D01*
G03X538692I-737J-1277D01*
G02X536524Y923118I-1114J1927D01*
G01X536466Y923152D01*
G03X534992I-737J-1277D01*
G02X532766I-1113J1927D01*
G03X531292I-737J-1277D01*
G02X529066I-1113J1927D01*
G03X527592I-737J-1277D01*
G02X525366I-1113J1927D01*
G03X523892I-737J-1277D01*
G02X521724Y923118I-1114J1927D01*
G01X521666Y923152D01*
G03X520192I-737J-1277D01*
G02X517966I-1113J1927D01*
G03X516492I-737J-1277D01*
G02X514324Y923118I-1114J1927D01*
G01X514266Y923152D01*
G03X512792I-737J-1277D01*
G02X510606Y923128I-1114J1927D01*
G01X510565Y923152D01*
G03X509091I-737J-1277D01*
G02X506907Y923128I-1113J1927D01*
G01X506866Y923152D01*
G03X505392I-737J-1277D01*
G02X503224Y923118I-1114J1927D01*
G01X503166Y923152D01*
G03X501692I-737J-1277D01*
G02X499524Y923118I-1114J1927D01*
G01X499466Y923152D01*
X499463Y923154D01*
X499442Y923166D01*
G02X498368Y924821I1136J1913D01*
G01X498110Y925079D01*
X496878D01*
G01X551423Y917839D02*
X551331D01*
X551095Y917603D01*
X550672D01*
X549716Y918559D01*
G02X549385Y919001I1376J1376D01*
G03X547016Y920402I-2364J-1293D01*
G02X545995Y920649I-2J2224D01*
G03X543866Y920598I-1018J-1978D01*
G02X542392I-737J1277D01*
G01X542357Y920618D01*
G02X541654Y921875I772J1257D01*
G03X540565Y923788I-2225J0D01*
G01X540544Y923800D01*
X540541Y923802D01*
X540483Y923836D01*
G03X538315Y923802I-1054J-1961D01*
G02X536841I-737J1277D01*
G01X536800Y923826D01*
G03X534616Y923802I-1071J-1951D01*
G02X533142I-737J1277D01*
G03X530916I-1113J-1927D01*
G02X529442I-737J1277D01*
G03X527216I-1113J-1927D01*
G02X525742I-737J1277D01*
G01X525701Y923826D01*
G03X523515Y923802I-1072J-1951D01*
G02X522041I-737J1277D01*
G01X522000Y923826D01*
G03X519816Y923802I-1071J-1951D01*
G02X518342I-737J1277D01*
G01X518301Y923826D01*
G03X516115Y923802I-1072J-1951D01*
G02X514641I-737J1277D01*
G01X514583Y923836D01*
G03X512415Y923802I-1054J-1961D01*
G02X510941I-737J1277D01*
G03X508715I-1113J-1927D01*
G02X507241I-737J1277D01*
G01X507183Y923836D01*
G03X505015Y923802I-1054J-1961D01*
G02X503541I-737J1277D01*
G01X503483Y923836D01*
G03X501315Y923802I-1054J-1961D01*
G02X499841I-737J1277D01*
G01X499835Y923805D01*
X499806Y923822D01*
G02X499121Y924854I773J1256D01*
G01X499346Y925079D01*
X500578D01*
G01X552924Y949055D02*
X552019D01*
X549854Y951220D01*
X548470D01*
X547170Y949920D01*
X546200D01*
X545716Y949436D01*
G02X544242I-737J1277D01*
G03X542016I-1113J-1927D01*
G02X540542I-737J1277D01*
G03X538316I-1113J-1927D01*
G02X536842I-737J1277D01*
G03X534616I-1113J-1927D01*
G02X533142I-737J1277D01*
G01X533101Y949460D01*
G03X530915Y949436I-1072J-1951D01*
G02X529441I-737J1277D01*
G01X529400Y949460D01*
G03X527216Y949436I-1071J-1951D01*
G02X525742I-737J1277D01*
G01X525701Y949460D01*
G03X523515Y949436I-1072J-1951D01*
G02X522041I-737J1277D01*
G03X519815I-1113J-1927D01*
G02X518341I-737J1277D01*
G01X518283Y949470D01*
G03X516115Y949436I-1054J-1961D01*
G02X514641I-737J1277D01*
G01X514583Y949470D01*
G03X512415Y949436I-1054J-1961D01*
G02X510941I-737J1277D01*
G01X510900Y949460D01*
G03X508716Y949436I-1071J-1951D01*
G02X507242I-737J1277D01*
G01X507201Y949460D01*
G03X505015Y949436I-1072J-1951D01*
G03X504583Y949110I1115J-1926D01*
G01X504084Y948975D01*
X503736Y948998D01*
X502324D01*
G03X498729Y947509I0J-5084D01*
G01X552924Y938571D02*
X551234D01*
X549819Y939986D01*
X548024D01*
G03X547930Y939974I0J-370D01*
G03X547566Y939823I380J-1430D01*
G02X546092I-737J1277D01*
G03X543866I-1113J-1927D01*
G02X542392I-737J1277D01*
G03X540166I-1113J-1927D01*
G02X538692I-737J1277D01*
G03X536466I-1113J-1927D01*
G02X534992I-737J1277D01*
G03X532766I-1113J-1927D01*
G02X531292I-737J1277D01*
G03X529066I-1113J-1927D01*
G02X527591I-737J1277D01*
G01X527569Y939836D01*
G03X525366Y939823I-1090J-1940D01*
G02X523909Y939812I-738J1277D01*
G01X523891Y939823D01*
X523862Y939840D01*
G03X521666Y939823I-1083J-1944D01*
G02X520209Y939812I-738J1277D01*
G01X520191Y939823D01*
X520162Y939840D01*
G03X517966Y939823I-1083J-1944D01*
G02X516509Y939812I-738J1277D01*
G01X516491Y939823D01*
X516462Y939840D01*
G03X514266Y939823I-1083J-1944D01*
G02X512809Y939812I-738J1277D01*
G01X512791Y939823D01*
X512762Y939840D01*
G03X510566Y939823I-1083J-1944D01*
G02X509109Y939812I-738J1277D01*
G01X509091Y939823D01*
X509077Y939831D01*
G02X508785Y940054I687J1202D01*
G01X508524Y940315D01*
X507543Y941602D01*
G03X506866Y942377I-1472J-603D01*
G03X505392I-737J-1277D01*
G01X505279Y942311D01*
X504326Y942176D01*
X503903Y941753D01*
Y941100D01*
G02X501683Y939828I-1474J0D01*
G01X501680Y939830D01*
G03X499727Y939953I-1097J-1854D01*
G01X499344Y940033D01*
X498729Y941099D01*
Y941100D01*
G01X552924Y934546D02*
X551193D01*
X549474Y936265D01*
X548403D01*
G03X545716Y936619I-1574J-1574D01*
G02X544242I-737J1277D01*
G03X542016I-1113J-1928D01*
G02X540542I-737J1277D01*
G03X538316I-1113J-1928D01*
G02X536842I-737J1277D01*
G03X534616I-1113J-1928D01*
G02X533142I-737J1277D01*
G03X530916I-1113J-1928D01*
G02X529442I-737J1277D01*
G01X529441Y936618D01*
G03X527216I-1112J-1927D01*
G01X527199Y936608D01*
G02X525741Y936618I-720J1288D01*
G03X523539Y936632I-1113J-1927D01*
G01X523516Y936618D01*
X523493Y936605D01*
G02X522041Y936618I-715J1291D01*
G03X519839Y936632I-1113J-1927D01*
G01X519816Y936618D01*
X519793Y936605D01*
G02X518341Y936618I-715J1291D01*
G03X516139Y936632I-1113J-1927D01*
G01X516116Y936618D01*
X516093Y936605D01*
G02X514641Y936618I-715J1291D01*
G03X512439Y936632I-1113J-1927D01*
G01X512416Y936618D01*
X512393Y936605D01*
G02X510941Y936618I-715J1291D01*
G03X508739Y936632I-1113J-1927D01*
G01X508716Y936618D01*
X508693Y936605D01*
G02X507241Y936618I-715J1291D01*
G02X506504Y937882I738J1277D01*
G01Y937896D01*
G03X506382Y938623I-2225J0D01*
G01X505347Y939658D01*
X504123D01*
G02X501375Y939139I-1695J1441D01*
G01X501298Y939184D01*
G03X500079Y939283I-712J-1208D01*
G01X499963Y938963D01*
X500578Y937897D01*
Y937896D01*
G01X496878Y944304D02*
X498896D01*
X499121Y944079D01*
X499132Y944006D01*
G03X499743Y943086I1300J200D01*
G01X499835Y943030D01*
X499841Y943027D01*
G03X501315I737J1277D01*
G01X501350Y943047D01*
G03X502180Y943681I-1951J3415D01*
G01X502593Y944094D01*
G03X502822Y944541I-578J578D01*
G02X505015Y945581I1456J-237D01*
G03X507183Y945547I1115J1928D01*
G01X507241Y945581D01*
G02X508715I737J-1277D01*
G03X510883Y945547I1115J1928D01*
G01X510941Y945581D01*
G02X512415I737J-1277D01*
G03X514583Y945547I1115J1928D01*
G01X514641Y945581D01*
G02X516115I737J-1277D01*
G03X518301Y945557I1114J1928D01*
G01X518342Y945581D01*
G02X519816I737J-1277D01*
G01X519857Y945557D01*
G03X522041Y945581I1071J1952D01*
G02X523515I737J-1277D01*
G03X525701Y945557I1114J1928D01*
G01X525742Y945581D01*
G02X527216I737J-1277D01*
G03X529400Y945557I1113J1928D01*
G01X529441Y945581D01*
G02X530915I737J-1277D01*
G01X530917Y945582D01*
G03X533141I1112J1927D01*
G02X534595Y945594I738J-1278D01*
G03X536840Y945581I1134J1912D01*
G01X536841D01*
G02X538315I737J-1277D01*
G03X540483Y945547I1115J1928D01*
G01X540541Y945581D01*
G02X542015I737J-1277D01*
G03X544183Y945547I1115J1928D01*
G01X544241Y945581D01*
G02X545715I737J-1277D01*
G03X547883Y945547I1115J1928D01*
G01X547941Y945581D01*
G02X548678Y945781I742J-1276D01*
G01X549554D01*
X551215Y944120D01*
X552597D01*
X552832Y943885D01*
X552924D01*
G01X500578Y944304D02*
G02X503166Y946232I10017J-10745D01*
G01X503224Y946266D01*
G02X505392Y946232I1053J-1962D01*
G03X506866I737J1277D01*
G01X506924Y946266D01*
G02X509092Y946232I1053J-1962D01*
G03X510566I737J1277D01*
G01X510624Y946266D01*
G02X512792Y946232I1053J-1962D01*
G03X514266I737J1277D01*
G01X514324Y946266D01*
G02X516492Y946232I1053J-1962D01*
G03X517966I737J1277D01*
G02X520150Y946256I1113J-1928D01*
G01X520191Y946232D01*
G03X521665I737J1277D01*
G01X521706Y946256D01*
G02X523892Y946232I1072J-1952D01*
G03X525366I737J1277D01*
G02X527592I1113J-1928D01*
G03X529066I737J1277D01*
G01X529124Y946266D01*
G02X531292Y946232I1053J-1962D01*
G03X532766I737J1277D01*
G02X534992I1113J-1928D01*
G01X534993Y946231D01*
G03X536465I736J1275D01*
G01X536466Y946232D01*
X536524Y946266D01*
G02X538692Y946232I1053J-1962D01*
G03X540166I737J1277D01*
G01X540224Y946266D01*
G02X542392Y946232I1053J-1962D01*
G03X543866I737J1277D01*
G01X543924Y946266D01*
G02X546092Y946232I1053J-1962D01*
G03X547566I737J1277D01*
G02X548678Y946530I1113J-1928D01*
G01X549865D01*
X551526Y944869D01*
X552596D01*
X552832Y945105D01*
X552924D01*
G01Y952975D02*
X552334D01*
X551590Y953719D01*
X548645D01*
X547566Y952640D01*
G02X546092I-737J1277D01*
G03X543866I-1113J-1927D01*
G02X542392I-737J1277D01*
G03X540166I-1113J-1927D01*
G02X538692I-737J1277D01*
G03X536466I-1113J-1927D01*
G02X534992I-737J1277D01*
G03X532766I-1113J-1927D01*
G02X531292I-737J1277D01*
G03X529124Y952674I-1114J-1927D01*
G01X529066Y952640D01*
G02X527592I-737J1277D01*
G03X525366I-1113J-1927D01*
G02X523892I-737J1277D01*
G03X521724Y952674I-1114J-1927D01*
G01X521666Y952640D01*
G02X520192I-737J1277D01*
G03X518024Y952674I-1114J-1927D01*
G01X517966Y952640D01*
G02X516492I-737J1277D01*
G03X514324Y952674I-1114J-1927D01*
G01X514266Y952640D01*
G02X512792I-737J1277D01*
G03X510624Y952674I-1114J-1927D01*
G01X510566Y952640D01*
G02X509092I-737J1277D01*
G03X506866I-1113J-1927D01*
G02X505392I-737J1277D01*
G03X503224Y952674I-1114J-1927D01*
G01X503166Y952640D01*
X503142Y952626D01*
G03X502068Y950972I1136J-1913D01*
G01X501809Y950713D01*
X500578D01*
G01X542571Y960104D02*
X541221D01*
X540166Y959049D01*
G02X538692I-737J1277D01*
G03X536466I-1113J-1927D01*
G02X534992I-737J1277D01*
G03X532766I-1113J-1927D01*
G02X531292I-737J1277D01*
G03X529124Y959083I-1114J-1927D01*
G01X529066Y959049D01*
G02X527592I-737J1277D01*
G03X525366I-1113J-1927D01*
G02X523892I-737J1277D01*
G03X521666I-1113J-1927D01*
G02X520192I-737J1277D01*
G03X518024Y959083I-1114J-1927D01*
G01X517966Y959049D01*
G02X516492I-737J1277D01*
G03X514324Y959083I-1114J-1927D01*
G01X514266Y959049D01*
G02X512792I-737J1277D01*
G03X510606Y959073I-1114J-1927D01*
G01X510565Y959049D01*
G02X509091I-737J1277D01*
G03X506907Y959073I-1113J-1927D01*
G01X506866Y959049D01*
G02X505392I-737J1277D01*
G03X503224Y959083I-1114J-1927D01*
G01X503166Y959049D01*
X503142Y959035D01*
G03X502068Y957380I1136J-1913D01*
G01X501810Y957122D01*
X500578D01*
G01X540045Y965427D02*
X539439D01*
X539054Y965042D01*
Y963530D01*
G02X538317Y962254I-1473J0D01*
G01X538316Y962253D01*
G02X536842I-737J1277D01*
G01X536808Y962272D01*
X536800Y962277D01*
G03X534616Y962253I-1071J-1951D01*
G02X533142I-737J1277D01*
G01X533101Y962277D01*
G03X530915Y962253I-1072J-1951D01*
G02X529441I-737J1277D01*
G01X529400Y962277D01*
G03X527216Y962253I-1071J-1951D01*
G02X525742I-737J1277D01*
G01X525701Y962277D01*
G03X523515Y962253I-1072J-1951D01*
G02X522041I-737J1277D01*
G01X522000Y962277D01*
G03X519816Y962253I-1071J-1951D01*
G02X518342I-737J1277D01*
G01X518301Y962277D01*
G03X516115Y962253I-1072J-1951D01*
G02X514641I-737J1277D01*
G01X514583Y962287D01*
G03X512415Y962253I-1054J-1961D01*
G02X510941I-737J1277D01*
G03X508715I-1113J-1927D01*
G02X507241I-737J1277D01*
G01X507183Y962287D01*
G03X505015Y962253I-1054J-1961D01*
G02X503541I-737J1277D01*
G01X503500Y962277D01*
G03X501316Y962253I-1071J-1951D01*
G01X501008Y962075D01*
G03X498729Y960326I5508J-9537D01*
G01X542036Y979665D02*
X541428D01*
X540055Y981038D01*
X537161D01*
X535324Y982875D01*
X532386D01*
X531223Y981712D01*
G02X530916Y981479I-1038J1049D01*
G02X529442I-737J1277D01*
G03X527216I-1113J-1927D01*
G02X525742I-737J1277D01*
G03X523516I-1113J-1927D01*
G02X522042I-737J1277D01*
G03X519816I-1113J-1927D01*
G02X518342I-737J1277D01*
G01X518301Y981503D01*
G03X516115Y981479I-1072J-1951D01*
G02X514641I-737J1277D01*
G01X514583Y981513D01*
G03X512415Y981479I-1054J-1961D01*
G02X510941I-737J1277D01*
G03X508715I-1113J-1927D01*
G02X507241I-737J1277D01*
G01X507183Y981513D01*
G03X505015Y981479I-1054J-1961D01*
G02X503541I-737J1277D01*
G01X503483Y981513D01*
G03X501315Y981479I-1054J-1961D01*
G02X499841I-737J1277D01*
G01X499783Y981513D01*
G03X497615Y981479I-1054J-1961D01*
G02X496141I-737J1277D01*
G01X496100Y981503D01*
G03X493916Y981479I-1071J-1951D01*
G02X492442I-737J1277D01*
G01X492401Y981503D01*
G03X490215Y981479I-1072J-1951D01*
G01X490103Y981415D01*
X487629Y979552D01*
G01X537521Y975373D02*
X536802D01*
X536104Y976071D01*
Y976420D01*
G03X532766Y978275I-2225J-73D01*
G02X531292I-737J1277D01*
G03X529066I-1113J-1928D01*
G02X527592I-737J1277D01*
G03X525366I-1113J-1928D01*
G02X523892I-737J1277D01*
G03X521666I-1113J-1928D01*
G02X520192I-737J1277D01*
G03X518024Y978309I-1115J-1928D01*
G01X517966Y978275D01*
G02X516492I-737J1277D01*
G03X514266I-1113J-1928D01*
G02X512792I-737J1277D01*
G03X510606Y978299I-1114J-1928D01*
G01X510565Y978275D01*
G02X509091I-737J1277D01*
G03X506907Y978299I-1113J-1928D01*
G01X506866Y978275D01*
G02X505392I-737J1277D01*
G03X503224Y978309I-1115J-1928D01*
G01X503166Y978275D01*
G02X501692I-737J1277D01*
G03X499524Y978309I-1115J-1928D01*
G01X499466Y978275D01*
G02X497992I-737J1277D01*
G03X495766I-1113J-1928D01*
G02X494292I-737J1277D01*
G03X492124Y978309I-1115J-1928D01*
G01X492066Y978275D01*
G02X490592I-737J1277D01*
G03X488424Y978309I-1115J-1928D01*
G01X488366Y978275D01*
X488252Y978210D01*
X485778Y976347D01*
G01X542093Y977366D02*
X538631D01*
X536222Y979775D01*
Y980917D01*
X535034Y982105D01*
X532676D01*
X531753Y981182D01*
G02X531292Y980829I-1572J1575D01*
G02X529066I-1113J1927D01*
G03X527592I-737J-1277D01*
G02X525366I-1113J1927D01*
G03X523892I-737J-1277D01*
G02X521666I-1113J1927D01*
G03X520192I-737J-1277D01*
G02X517966I-1113J1927D01*
G03X516492I-737J-1277D01*
G02X514324Y980795I-1114J1927D01*
G01X514266Y980829D01*
G03X512792I-737J-1277D01*
G02X510606Y980805I-1114J1927D01*
G01X510565Y980829D01*
G03X509091I-737J-1277D01*
G02X506907Y980805I-1113J1927D01*
G01X506866Y980829D01*
G03X505392I-737J-1277D01*
G02X503224Y980795I-1114J1927D01*
G01X503166Y980829D01*
G03X501692I-737J-1277D01*
G02X499524Y980795I-1114J1927D01*
G01X499466Y980829D01*
G03X497992I-737J-1277D01*
G02X495824Y980795I-1114J1927D01*
G01X495766Y980829D01*
G03X494292I-737J-1277D01*
G01X494178Y980762D01*
X491329Y979552D01*
G01X538600Y971408D02*
X537794D01*
X537187Y972015D01*
Y973815D01*
X535354Y975648D01*
Y976347D01*
G03X534651Y977604I-1475J0D01*
G01X534616Y977624D01*
G03X533142I-737J-1277D01*
G02X530916I-1113J1928D01*
G03X529442I-737J-1277D01*
G02X527216I-1113J1928D01*
G03X525742I-737J-1277D01*
G02X523516I-1113J1928D01*
G03X522042I-737J-1277D01*
G01X522001Y977600D01*
G02X519815Y977624I-1072J1952D01*
G03X518341I-737J-1277D01*
G01X518300Y977600D01*
G02X516116Y977624I-1071J1952D01*
G03X514642I-737J-1277D01*
G01X514601Y977600D01*
G02X512415Y977624I-1072J1952D01*
G03X510941I-737J-1277D01*
G02X508715I-1113J1928D01*
G03X507241I-737J-1277D01*
G01X507183Y977590D01*
G02X505015Y977624I-1053J1962D01*
G03X503541I-737J-1277D01*
G01X503483Y977590D01*
G02X501315Y977624I-1053J1962D01*
G03X499841I-737J-1277D01*
G01X499800Y977600D01*
G02X497616Y977624I-1071J1952D01*
G03X496142I-737J-1277D01*
G01X496030Y977558D01*
X493178Y976347D01*
G01X545897Y986314D02*
X544587D01*
X544396Y986505D01*
X506207D01*
X499162Y993550D01*
Y999684D01*
G01X553526Y1038079D02*
X552329D01*
X550544Y1039864D01*
X549111D01*
G02X548374Y1040063I3J1475D01*
G01X548316Y1040097D01*
G03X546148Y1040063I-1054J-1961D01*
G02X544674I-737J1277D01*
G01X544616Y1040097D01*
G03X542448Y1040063I-1054J-1961D01*
G02X540974I-737J1277D01*
G03X538748I-1113J-1927D01*
G02X537274I-737J1277D01*
G03X535048I-1113J-1927D01*
G02X533574I-737J1277D01*
G03X531348I-1113J-1927D01*
G02X529874I-737J1277D01*
G01X529816Y1040097D01*
G03X527648Y1040063I-1054J-1961D01*
G02X526174I-737J1277D01*
G01Y1040062D01*
G03X523972Y1040076I-1113J-1927D01*
G01X523949Y1040062D01*
X523926Y1040049D01*
G02X522474Y1040062I-715J1291D01*
G03X520272Y1040076I-1113J-1927D01*
G01X520249Y1040062D01*
X520226Y1040049D01*
G02X518774Y1040062I-715J1291D01*
G03X516572Y1040076I-1113J-1927D01*
G01X516549Y1040062D01*
X516526Y1040049D01*
G02X515074Y1040062I-715J1291D01*
G03X512872Y1040076I-1113J-1927D01*
G01X512849Y1040062D01*
X512826Y1040049D01*
G02X511374Y1040062I-715J1291D01*
G03X509172Y1040076I-1113J-1927D01*
G01X509149Y1040062D01*
X509126Y1040049D01*
G02X507674Y1040062I-715J1291D01*
G03X505472Y1040076I-1113J-1927D01*
G02X504026Y1039698I-1446J2578D01*
G01X502141D01*
G03X499162Y1038136I0J-3622D01*
G01X553026Y1027656D02*
X551073D01*
X550461Y1027044D01*
X549114D01*
G02X548374Y1027246I5J1476D01*
G01X548339Y1027266D01*
G02X547636Y1028523I772J1257D01*
G01Y1028562D01*
G03X546524Y1030450I-2225J-39D01*
G03X544298I-1113J-1927D01*
G02X542824I-737J1277D01*
G03X540598I-1113J-1927D01*
G02X539124I-737J1277D01*
G03X536898I-1113J-1927D01*
G02X535424I-737J1277D01*
G03X533198I-1113J-1927D01*
G02X531724I-737J1277D01*
G03X529540Y1030474I-1113J-1927D01*
G01X529499Y1030450D01*
G02X528025I-737J1277D01*
G03X525857Y1030484I-1114J-1927D01*
G01X525799Y1030450D01*
G02X524325I-737J1277D01*
G03X522139Y1030474I-1114J-1927D01*
G01X522098Y1030450D01*
G02X520624I-737J1277D01*
G03X518440Y1030474I-1113J-1927D01*
G01X518399Y1030450D01*
G02X516925I-737J1277D01*
G03X514757Y1030484I-1114J-1927D01*
G01X514699Y1030450D01*
G02X513225I-737J1277D01*
G03X511057Y1030484I-1114J-1927D01*
G01X510999Y1030450D01*
G02X509525I-737J1277D01*
G02X508970Y1031014I741J1285D01*
G01X508600Y1031683D01*
X507888Y1032650D01*
X507299Y1033004D01*
G03X505825I-737J-1277D01*
G02X503657Y1032970I-1114J1927D01*
G01X503599Y1033004D01*
G03X502125I-737J-1277D01*
G01X502012Y1032938D01*
X499162Y1031727D01*
G01X553526Y1032844D02*
X553434D01*
X553199Y1033079D01*
X552353D01*
X551546Y1033885D01*
X551041Y1035103D01*
X550242Y1035903D01*
X550241D01*
G03X549918Y1036166I-1409J-1401D01*
G01X549917D01*
G03X549849Y1036208I-809J-1233D01*
G03X548375I-737J-1277D01*
G02X546207Y1036174I-1115J1928D01*
G01X546149Y1036208D01*
G03X544675I-737J-1277D01*
G02X542489Y1036184I-1114J1928D01*
G01X542448Y1036208D01*
G03X540974I-737J-1277D01*
G02X538748I-1113J1928D01*
G03X537274I-737J-1277D01*
G02X535048I-1113J1928D01*
G03X533574I-737J-1277D01*
G02X531348I-1113J1928D01*
G03X529874I-737J-1277D01*
G01X529816Y1036174D01*
G02X527648Y1036208I-1053J1962D01*
G03X526174I-737J-1277D01*
G01X526116Y1036174D01*
G02X523948Y1036208I-1053J1962D01*
G03X522474I-737J-1277D01*
G01X522433Y1036184D01*
G02X520249Y1036208I-1071J1952D01*
G03X518775I-737J-1277D01*
G01X518734Y1036184D01*
G02X516548Y1036208I-1072J1952D01*
G03X515074I-737J-1277D01*
G01X515016Y1036174D01*
G02X512848Y1036208I-1053J1962D01*
G03X511374I-737J-1277D01*
G02X509148I-1113J1928D01*
G03X507674I-737J-1277D01*
G01X507616Y1036174D01*
G02X505448Y1036208I-1053J1962D01*
G03X503974I-737J-1277D01*
G01X503916Y1036174D01*
G02X501748Y1036208I-1053J1962D01*
G03X499554Y1035157I-737J-1277D01*
G01X499780Y1034931D01*
X501011D01*
G01X553526Y1034064D02*
X553434D01*
X553198Y1033828D01*
X552664D01*
X552182Y1034310D01*
X551677Y1035528D01*
X550772Y1036433D01*
G03X550327Y1036794I-1937J-1933D01*
G03X550225Y1036857I-1219J-1860D01*
G03X548001I-1112J-1926D01*
G01X548000D01*
X547998Y1036859D01*
G02X546524I-737J1277D01*
G01X546466Y1036893D01*
G03X544298Y1036859I-1053J-1962D01*
G02X542824I-737J1277D01*
G03X540598I-1113J-1928D01*
G02X539124I-737J1277D01*
G03X536898I-1113J-1928D01*
G02X535424I-737J1277D01*
G01X535422Y1036857D01*
G03X533200I-1111J-1926D01*
G01X533198Y1036859D01*
G02X531724I-737J1277D01*
G03X529540Y1036883I-1113J-1928D01*
G01X529499Y1036859D01*
G02X528025I-737J1277D01*
G03X525857Y1036893I-1115J-1928D01*
G01X525799Y1036859D01*
G02X524325I-737J1277D01*
G03X522157Y1036893I-1115J-1928D01*
G01X522099Y1036859D01*
G02X520625I-737J1277D01*
G03X518399I-1113J-1928D01*
G02X516925I-737J1277D01*
G03X514757Y1036893I-1115J-1928D01*
G01X514699Y1036859D01*
G02X513225I-737J1277D01*
G03X511039Y1036883I-1114J-1928D01*
G01X510998Y1036859D01*
G02X509524I-737J1277D01*
G03X507340Y1036883I-1113J-1928D01*
G01X507299Y1036859D01*
G02X505825I-737J1277D01*
G03X503657Y1036893I-1115J-1928D01*
G01X503599Y1036859D01*
G02X502125I-737J1277D01*
G03X498811Y1035272I-1114J-1928D01*
G03X498800Y1035189I2201J-334D01*
G01X498542Y1034931D01*
X497311D01*
G01X553526Y1061485D02*
X552608D01*
X552100Y1060977D01*
X551132Y1060576D01*
X549844Y1059288D01*
G02X548370I-737J1277D01*
G01X548329Y1059312D01*
G03X546145Y1059288I-1071J-1951D01*
G02X544671I-737J1277D01*
G01X544630Y1059312D01*
G03X542446Y1059288I-1071J-1951D01*
G02X540972I-737J1277D01*
G03X538748I-1112J-1927D01*
G02X537274I-737J1277D01*
G03X535048I-1113J-1927D01*
G02X533574I-737J1277D01*
G01X533516Y1059322D01*
G03X531348Y1059288I-1054J-1961D01*
G02X529874I-737J1277D01*
G01X529816Y1059322D01*
G03X527648Y1059288I-1054J-1961D01*
G02X526174I-737J1277D01*
G01X526133Y1059312D01*
G03X523949Y1059288I-1071J-1951D01*
G01X523926Y1059275D01*
G02X522474Y1059288I-715J1290D01*
G03X520272Y1059302I-1113J-1927D01*
G01X520249Y1059288D01*
X520226Y1059275D01*
G02X518774Y1059288I-715J1290D01*
G03X516572Y1059302I-1113J-1927D01*
G01X516549Y1059288D01*
X516526Y1059275D01*
G02X515074Y1059288I-715J1290D01*
G03X512872Y1059302I-1113J-1927D01*
G01X512849Y1059288D01*
X512826Y1059275D01*
G02X511374Y1059288I-715J1290D01*
G03X509172Y1059302I-1113J-1927D01*
G01X509149Y1059288D01*
X509126Y1059275D01*
G02X507674Y1059288I-715J1290D01*
G03X505495Y1059300I-1100J-1904D01*
G01X505479Y1059291D01*
G02X504963Y1059017I-5834J10363D01*
G02X504447Y1058898I-515J1057D01*
G01X502872D01*
G03X499162Y1057361I0J-5246D01*
G01X553526Y1051070D02*
X552598D01*
X551182Y1049654D01*
G02X550862Y1049514I-337J335D01*
G02X550220Y1049676I-37J1205D01*
G01X550179Y1049700D01*
G03X547995Y1049676I-1071J-1951D01*
G02X546521I-737J1276D01*
G01X546480Y1049700D01*
G03X544296Y1049676I-1071J-1951D01*
G02X542822I-737J1276D01*
G01X542781Y1049700D01*
G03X540597Y1049676I-1071J-1951D01*
G02X539123I-737J1276D01*
G01X539082Y1049700D01*
G03X536898Y1049676I-1071J-1951D01*
G02X535424I-737J1276D01*
G03X533240Y1049700I-1113J-1927D01*
G01X533199Y1049676D01*
G02X531725I-737J1276D01*
G01X531701Y1049689D01*
G03X529499Y1049675I-1089J-1940D01*
G02X528047Y1049662I-737J1277D01*
G01X528024Y1049675D01*
X528001Y1049689D01*
G03X525799Y1049675I-1089J-1940D01*
G02X524347Y1049662I-737J1277D01*
G01X524324Y1049675D01*
X524301Y1049689D01*
G03X522099Y1049675I-1089J-1940D01*
G02X520647Y1049662I-737J1277D01*
G01X520624Y1049675D01*
X520601Y1049689D01*
G03X518399Y1049675I-1089J-1940D01*
G02X516947Y1049662I-737J1277D01*
G01X516924Y1049675D01*
X516901Y1049689D01*
G03X514699Y1049675I-1089J-1940D01*
G02X513247Y1049662I-737J1277D01*
G01X513224Y1049675D01*
X513201Y1049689D01*
G03X510999Y1049675I-1089J-1940D01*
G02X509496Y1049691I-738J1277D01*
G02X508876Y1050447I766J1260D01*
G03X508591Y1050996I-2239J-814D01*
G03X508179Y1051640I-1101J-251D01*
G03X507299Y1052229I-4869J-6322D01*
G03X505825I-737J-1277D01*
G02X503657Y1052195I-1115J1928D01*
G01X503599Y1052229D01*
G03X502125I-737J-1277D01*
G01X502016Y1052165D01*
X499162Y1050952D01*
G01X553526Y1057463D02*
X553434D01*
X553198Y1057227D01*
X551909D01*
X550881Y1056199D01*
X550179Y1056108D01*
G03X547995Y1056084I-1071J-1951D01*
G02X546555Y1056065I-737J1277D01*
G01X546451Y1056125D01*
G03X544297Y1056084I-1040J-1968D01*
G02X542870Y1056057I-738J1277D01*
G01X542823Y1056084D01*
X542765Y1056118D01*
G03X540597Y1056084I-1054J-1961D01*
G02X539123I-737J1277D01*
G01X539082Y1056108D01*
G03X536898Y1056084I-1071J-1951D01*
G02X535424I-737J1277D01*
G03X533240Y1056108I-1113J-1927D01*
G01X533199Y1056084D01*
G02X531725I-737J1277D01*
G03X529557Y1056118I-1114J-1927D01*
G01X529499Y1056084D01*
G02X528025I-737J1277D01*
G03X525857Y1056118I-1114J-1927D01*
G01X525799Y1056084D01*
G02X524325I-737J1277D01*
G03X522157Y1056118I-1114J-1927D01*
G01X522099Y1056084D01*
G02X520625I-737J1277D01*
G03X518399I-1113J-1927D01*
G02X516925I-737J1277D01*
G03X514757Y1056118I-1114J-1927D01*
G01X514699Y1056084D01*
G02X513225I-737J1277D01*
G03X511057Y1056118I-1114J-1927D01*
G01X510999Y1056084D01*
G02X509525I-737J1277D01*
G03X507357Y1056118I-1114J-1927D01*
G01X507299Y1056084D01*
G02X505954Y1056018I-737J1277D01*
G02X505825Y1056084I606J1344D01*
G01X505824D01*
G03X503430Y1055975I-1112J-1925D01*
G01X502704Y1055463D01*
X502671Y1055454D01*
X502589Y1055396D01*
X501876Y1055361D01*
X501748Y1055434D01*
G03X500274I-737J-1277D01*
G01X500268Y1055431D01*
X500239Y1055414D01*
G03X499554Y1054382I773J-1256D01*
G01X499329Y1054157D01*
X497311D01*
G01X553526Y1074942D02*
X552805D01*
X548737Y1070874D01*
Y1070178D01*
G02X548034Y1068921I-1475J0D01*
G01X547999Y1068901D01*
G02X546525I-737J1277D01*
G03X544357Y1068935I-1114J-1927D01*
G01X544299Y1068901D01*
G02X542825I-737J1277D01*
G03X540657Y1068935I-1114J-1927D01*
G01X540599Y1068901D01*
G02X539125I-737J1277D01*
G03X536957Y1068935I-1114J-1927D01*
G01X536899Y1068901D01*
G02X535425I-737J1277D01*
G01X535424D01*
G03X533199I-1112J-1927D01*
G02X531741Y1068891I-738J1277D01*
G01X531724Y1068901D01*
X531701Y1068915D01*
G03X529499Y1068901I-1089J-1940D01*
G02X528047Y1068888I-737J1277D01*
G01X528024Y1068901D01*
X528001Y1068915D01*
G03X525799Y1068901I-1089J-1940D01*
G02X524347Y1068888I-737J1277D01*
G01X524324Y1068901D01*
X524301Y1068915D01*
G03X522099Y1068901I-1089J-1940D01*
G02X520647Y1068888I-737J1277D01*
G01X520624Y1068901D01*
X520601Y1068915D01*
G03X518399Y1068901I-1089J-1940D01*
G02X516947Y1068888I-737J1277D01*
G01X516924Y1068901D01*
X516901Y1068915D01*
G03X514699Y1068901I-1089J-1940D01*
G02X513247Y1068888I-737J1277D01*
G01X513224Y1068901D01*
X513201Y1068915D01*
G03X510999Y1068901I-1089J-1940D01*
G02X509496Y1068917I-738J1277D01*
G02X508876Y1069673I766J1260D01*
G03X508591Y1070222I-2239J-814D01*
G03X508179Y1070866I-1101J-251D01*
G03X507299Y1071455I-4869J-6322D01*
G03X505825I-737J-1277D01*
G02X503657Y1071421I-1115J1928D01*
G01X503599Y1071455D01*
G03X502125I-737J-1277D01*
G01X502016Y1071391D01*
X499162Y1070178D01*
G01X551197Y1084578D02*
X550767Y1084148D01*
Y1081966D01*
X547116Y1078315D01*
X545411D01*
G02X544674Y1078514I3J1476D01*
G03X542448I-1113J-1927D01*
G02X540974I-737J1277D01*
G03X538748I-1113J-1927D01*
G02X537274I-737J1277D01*
G03X535048I-1113J-1927D01*
G02X533574I-737J1277D01*
G01X533516Y1078548D01*
G03X531348Y1078514I-1054J-1961D01*
G02X529874I-737J1277D01*
G01X529816Y1078548D01*
G03X527648Y1078514I-1054J-1961D01*
G02X526174I-737J1277D01*
G01X526133Y1078538D01*
G03X523949Y1078514I-1071J-1951D01*
G02X522475I-737J1277D01*
G01X522434Y1078538D01*
G03X520248Y1078514I-1072J-1951D01*
G02X518774I-737J1277D01*
G01X518716Y1078548D01*
G03X516548Y1078514I-1054J-1961D01*
G02X515074I-737J1277D01*
G03X512872Y1078528I-1113J-1927D01*
G01X512849Y1078514D01*
X512826Y1078501D01*
G02X511374Y1078514I-715J1290D01*
G03X509172Y1078528I-1113J-1927D01*
G01X509149Y1078514D01*
X509126Y1078501D01*
G02X507674Y1078514I-715J1290D01*
G01X507498Y1078616D01*
G03X505713Y1078381I-739J-1280D01*
G01X505695Y1078363D01*
G02X505055Y1078098I-640J640D01*
G01X502809D01*
G03X499162Y1076587I0J-5157D01*
G01X553526Y1080218D02*
X553434D01*
X553199Y1080453D01*
X552685D01*
X547091Y1074859D01*
X545409D01*
G03X544670Y1074661I0J-1477D01*
G01X544671D01*
X544672Y1074660D01*
G02X542488Y1074636I-1113J1927D01*
G01X542414Y1074679D01*
G03X540974Y1074660I-703J-1296D01*
G02X538748I-1113J1927D01*
G03X537274I-737J-1277D01*
G02X535048I-1113J1927D01*
G03X533574I-737J-1277D01*
G01X533516Y1074626D01*
G02X531348Y1074660I-1054J1961D01*
G03X529874I-737J-1277D01*
G01X529816Y1074626D01*
G02X527648Y1074660I-1054J1961D01*
G03X526174I-737J-1277D01*
G01X526116Y1074626D01*
G02X523948Y1074660I-1054J1961D01*
G03X522474I-737J-1277D01*
G01X522433Y1074636D01*
G02X520249Y1074660I-1071J1951D01*
G03X518775I-737J-1277D01*
G01X518734Y1074636D01*
G02X516548Y1074660I-1072J1951D01*
G03X515074I-737J-1277D01*
G01X515016Y1074626D01*
G02X512848Y1074660I-1054J1961D01*
G03X511374I-737J-1277D01*
G01X511316Y1074626D01*
G02X509148Y1074660I-1054J1961D01*
G03X507674I-737J-1277D01*
G01X507616Y1074626D01*
G02X505448Y1074660I-1054J1961D01*
G03X503974I-737J-1277D01*
G01X503968Y1074657D01*
X503954Y1074649D01*
Y1074648D01*
G03X503946Y1074643I775J-1250D01*
G03X503303Y1073826I763J-1262D01*
G02X503211Y1073598I-1408J435D01*
G01X502985Y1073154D01*
G02X502928Y1073075I-277J140D01*
G01X502613Y1072760D01*
G02X501783Y1072126I-2781J2781D01*
G01X501748Y1072106D01*
G02X500274I-737J1277D01*
G01X500268Y1072109D01*
X500239Y1072126D01*
G02X499554Y1073158I773J1256D01*
G01X499329Y1073383D01*
X497311D01*
G01X553217Y1099508D02*
X552530D01*
X548906Y1095884D01*
Y1095370D01*
X548305Y1094769D01*
G02X547998Y1094536I-1038J1049D01*
G03X546886Y1092681I1113J-1928D01*
G01Y1092608D01*
G02X546183Y1091351I-1475J0D01*
G01X546148Y1091331D01*
G03X545036Y1089443I1113J-1927D01*
G01Y1089404D01*
G02X544333Y1088147I-1475J0D01*
G01X544298Y1088127D01*
G02X542824I-737J1277D01*
G03X540598I-1113J-1927D01*
G02X539124I-737J1277D01*
G03X536898I-1113J-1927D01*
G02X535424I-737J1277D01*
G03X533240Y1088151I-1113J-1927D01*
G01X533199Y1088127D01*
G02X531725I-737J1277D01*
G03X529557Y1088161I-1114J-1927D01*
G01X529499Y1088127D01*
G02X528025I-737J1277D01*
G03X525857Y1088161I-1114J-1927D01*
G01X525799Y1088127D01*
G02X524325I-737J1277D01*
G03X522139Y1088151I-1114J-1927D01*
G01X522098Y1088127D01*
G02X520624I-737J1277D01*
G03X518440Y1088151I-1113J-1927D01*
G01X518399Y1088127D01*
G02X516925I-737J1277D01*
G03X514757Y1088161I-1114J-1927D01*
G01X514699Y1088127D01*
G02X513225I-737J1277D01*
G03X511057Y1088161I-1114J-1927D01*
G01X510999Y1088127D01*
G02X508859Y1088951I-737J1277D01*
G03X507357Y1090647I-3347J-1451D01*
G01X507299Y1090681D01*
G03X505825I-737J-1277D01*
G02X503657Y1090647I-1114J1927D01*
G01X503599Y1090681D01*
G03X502125I-737J-1276D01*
G01X501415Y1090271D01*
G02X501099Y1090123I-1040J1808D01*
G01X499162Y1089404D01*
G01X552627Y1105547D02*
X552535D01*
X552300Y1105782D01*
X552053D01*
X551711Y1105439D01*
X550562Y1103296D01*
X550217Y1102463D01*
X549339Y1101150D01*
X548825Y1100638D01*
G02X548595Y1100441I-1557J1586D01*
G02X546150Y1100295I-1333J1780D01*
G01X546149D01*
X546148Y1100294D01*
G03X543936Y1099017I-737J-1277D01*
G01Y1098978D01*
G02X542824Y1097090I-2225J39D01*
G01X542789Y1097070D01*
G03X542086Y1095813I772J-1257D01*
G01Y1095740D01*
G02X538748Y1093885I-2225J73D01*
G03X537274I-737J-1277D01*
G01X537233Y1093861D01*
G02X535047Y1093885I-1072J1952D01*
G03X533573I-737J-1277D01*
G01X533532Y1093861D01*
G02X531348Y1093885I-1071J1952D01*
G03X529874I-737J-1277D01*
G02X527648I-1113J1928D01*
G03X526174I-737J-1277D01*
G01X526116Y1093851D01*
G02X523948Y1093885I-1053J1962D01*
G03X522474I-737J-1277D01*
G01X522416Y1093851D01*
G02X520248Y1093885I-1053J1962D01*
G03X518774I-737J-1277D01*
G01X518733Y1093861D01*
G02X516549Y1093885I-1071J1952D01*
G03X515075I-737J-1277D01*
G02X512907Y1093851I-1115J1928D01*
G01X512849Y1093885D01*
G03X511375I-737J-1277D01*
G01X511334Y1093861D01*
G02X509148Y1093885I-1072J1952D01*
G03X507674I-737J-1277D01*
G01X507616Y1093851D01*
G02X505448Y1093885I-1053J1962D01*
G03X503255Y1092845I-737J-1277D01*
G02X503026Y1092398I-807J131D01*
G01X502613Y1091985D01*
G02X501783Y1091351I-2781J2781D01*
G01X501748Y1091331D01*
G02X499554Y1092383I-737J1277D01*
G01X499329Y1092608D01*
X497311D01*
G01X546541Y888967D02*
X544999Y890509D01*
Y892295D01*
X544067Y893690D01*
X540473Y897284D01*
G03X540166Y897517I-1038J-1049D01*
G03X538692I-737J-1277D01*
G02X536466I-1113J1928D01*
G03X534992I-737J-1277D01*
G02X532766I-1113J1928D01*
G03X531292I-737J-1277D01*
G02X529124Y897483I-1115J1928D01*
G01X529066Y897517D01*
G03X527592I-737J-1277D01*
G02X525366I-1113J1928D01*
G03X523892I-737J-1277D01*
G02X521666I-1113J1928D01*
G03X520192I-737J-1277D01*
G02X518024Y897483I-1115J1928D01*
G01X517966Y897517D01*
G03X516492I-737J-1277D01*
G02X514324Y897483I-1115J1928D01*
G01X514266Y897517D01*
G03X512792I-737J-1277D01*
G02X510624Y897483I-1115J1928D01*
G01X510566Y897517D01*
G02X509453Y899389I1112J1928D01*
G01Y899445D01*
G03X508750Y900702I-1475J0D01*
G01X508715Y900722D01*
G02X507852Y901626I1113J1927D01*
G01X506129Y902649D01*
G01X546507Y881426D02*
X544758Y883175D01*
Y884039D01*
X542767Y886030D01*
Y889936D01*
X538623Y894080D01*
G03X538316Y894313I-1038J-1049D01*
G03X536842I-737J-1277D01*
G02X534616I-1113J1927D01*
G03X533142I-737J-1277D01*
G01X533101Y894289D01*
G02X530915Y894313I-1072J1951D01*
G03X529441I-737J-1277D01*
G01X529400Y894289D01*
G02X527216Y894313I-1071J1951D01*
G03X525742I-737J-1277D01*
G01X525701Y894289D01*
G02X523515Y894313I-1072J1951D01*
G03X522041I-737J-1277D01*
G01X521983Y894279D01*
G02X519815Y894313I-1054J1961D01*
G03X518341I-737J-1277D01*
G01X518300Y894289D01*
G02X516116Y894313I-1071J1951D01*
G03X514642I-737J-1277D01*
G01X514601Y894289D01*
G02X512415Y894313I-1072J1951D01*
G03X510941I-737J-1277D01*
G01X510883Y894279D01*
G02X508715Y894313I-1054J1961D01*
G01X508698Y894323D01*
X508691Y894327D01*
G02X507603Y896240I1138J1913D01*
G03X506900Y897497I-1475J0D01*
G01X506865Y897517D01*
G02X506576Y897716I1114J1927D01*
G01X504278Y899445D01*
G01X548323Y892336D02*
X548231D01*
X547996Y892571D01*
X547181D01*
X546600Y893152D01*
X546133Y894279D01*
X542048Y898364D01*
Y899835D01*
X541253Y900630D01*
G03X540542Y900724I-417J-417D01*
G01X540541Y900723D01*
G02X538317I-1112J1926D01*
G03X536840I-739J-1278D01*
G01X536841Y900721D01*
G02X534616Y900722I-1112J1928D01*
G03X533142I-737J-1277D01*
G01X533101Y900698D01*
G02X530915Y900722I-1072J1951D01*
G03X529441I-737J-1277D01*
G01X529400Y900698D01*
G02X527216Y900722I-1071J1951D01*
G03X525742I-737J-1277D01*
G02X523516I-1113J1927D01*
G03X522042I-737J-1277D01*
G01X522001Y900698D01*
G02X519815Y900722I-1072J1951D01*
G03X518341I-737J-1277D01*
G01X518283Y900688D01*
G02X516115Y900722I-1054J1961D01*
G03X514641I-737J-1277D01*
G01X514583Y900688D01*
G02X512415Y900722I-1054J1961D01*
G01X512391Y900736D01*
G02X512363Y900752I1090J1941D01*
G01X512364Y900754D01*
G02X511305Y902649I1166J1895D01*
G03X510606Y903904I-1476J0D01*
G01X510600Y903907D01*
X510503Y903962D01*
X509994Y904188D01*
X508596D01*
X507990Y904309D01*
X507794Y904390D01*
G02X507241Y904576I184J1463D01*
G01X507235Y904579D01*
X507206Y904596D01*
G02X506521Y905628I773J1256D01*
G01X506296Y905853D01*
X504278D01*
G01X548808Y903949D02*
X548372Y904385D01*
X547341D01*
X546554Y905172D01*
Y907720D01*
X544173Y910101D01*
G03X543866Y910334I-1038J-1049D01*
G03X542392I-737J-1277D01*
G02X540166I-1113J1928D01*
G03X538692I-737J-1277D01*
G02X536466I-1113J1928D01*
G03X534992I-737J-1277D01*
G02X532766I-1113J1928D01*
G03X531292I-737J-1277D01*
G02X529066I-1113J1928D01*
G03X527592I-737J-1277D01*
G02X525366I-1113J1928D01*
G03X523892I-737J-1277D01*
G02X521706Y910310I-1114J1928D01*
G01X521665Y910334D01*
G03X520191I-737J-1277D01*
G02X518007Y910310I-1113J1928D01*
G01X517966Y910334D01*
G02X516853Y912206I1112J1928D01*
G01Y912262D01*
G03X516150Y913519I-1475J0D01*
G01X516115Y913539D01*
G03X514641I-737J-1277D01*
G01X514583Y913505D01*
G02X512415Y913539I-1054J1961D01*
G03X510941I-737J-1277D01*
G01X510900Y913515D01*
G02X508716Y913539I-1071J1951D01*
G03X507242I-737J-1277D01*
G01X507126Y913471D01*
X504278Y912262D01*
G01X548323Y898765D02*
X547098D01*
X546378Y899485D01*
Y902800D01*
X542151Y907027D01*
G03X542016Y907130I-451J-451D01*
G03X540542I-737J-1277D01*
G02X538316I-1113J1927D01*
G03X536842I-737J-1277D01*
G02X534616I-1113J1927D01*
G03X533142I-737J-1277D01*
G02X530916I-1113J1927D01*
G03X529442I-737J-1277D01*
G02X527216I-1113J1927D01*
G03X525742I-737J-1277D01*
G01X525701Y907106D01*
G02X523515Y907130I-1072J1951D01*
G03X522041I-737J-1277D01*
G02X519857Y907106I-1113J1927D01*
G01X519816Y907130D01*
G03X518342I-737J-1277D01*
G01X518301Y907106D01*
G02X516115Y907130I-1072J1951D01*
G02X515004Y908996I1114J1927D01*
G01Y909057D01*
G03X514301Y910314I-1475J0D01*
G01X514266Y910334D01*
G03X512792I-737J-1277D01*
G02X510624Y910300I-1115J1928D01*
G01X510566Y910334D01*
G03X509092I-737J-1277D01*
G01X508982Y910270D01*
X506129Y909057D01*
G01X548323Y893556D02*
X548231D01*
X547995Y893320D01*
X547492D01*
X547236Y893577D01*
X546769Y894704D01*
X542797Y898675D01*
Y900146D01*
X541783Y901160D01*
G03X540168Y901373I-946J-947D01*
G01X540166Y901372D01*
G02X538692I-737J1277D01*
G03X536466I-1113J-1927D01*
G02X534992I-737J1277D01*
G03X532766I-1113J-1927D01*
G02X531292I-737J1277D01*
G03X529124Y901406I-1114J-1927D01*
G01X529066Y901372D01*
G02X527592I-737J1277D01*
G03X525366I-1113J-1927D01*
G02X523892I-737J1277D01*
G03X521666I-1113J-1927D01*
G02X520192I-737J1277D01*
G03X518024Y901406I-1114J-1927D01*
G01X517966Y901372D01*
G02X516492I-737J1277D01*
G03X514324Y901406I-1114J-1927D01*
G01X514266Y901372D01*
G02X512792I-737J1277D01*
G01X512757Y901392D01*
G02X512054Y902649I772J1257D01*
G03X510989Y904548I-2226J0D01*
G01X510974Y904557D01*
X510843Y904632D01*
X510153Y904937D01*
X508671D01*
X508216Y905028D01*
X507978Y905266D01*
Y905853D01*
G01X552057Y924958D02*
X551302D01*
X550904Y925356D01*
Y926107D01*
X549707Y927304D01*
X548678D01*
G03X547566Y927006I0J-2224D01*
G02X546092I-737J1277D01*
G01X546057Y927026D01*
G02X545354Y928283I772J1257D01*
G01Y928339D01*
G03X544241Y930211I-2225J-56D01*
G01X544183Y930245D01*
G03X542015Y930211I-1053J-1962D01*
G02X540541I-737J1277D01*
G01X540483Y930245D01*
G03X538315Y930211I-1053J-1962D01*
G02X536841I-737J1277D01*
G01X536783Y930245D01*
G03X534615Y930211I-1053J-1962D01*
G02X533141I-737J1277D01*
G01X533100Y930235D01*
G03X530916Y930211I-1071J-1952D01*
G02X529442I-737J1277D01*
G03X527216I-1113J-1928D01*
G02X525742I-737J1277D01*
G01X525701Y930235D01*
G03X523515Y930211I-1072J-1952D01*
G02X522041I-737J1277D01*
G03X519815I-1113J-1928D01*
G02X518341I-737J1277D01*
G01X518283Y930245D01*
G03X516115Y930211I-1053J-1962D01*
G02X514641I-737J1277D01*
G01X514583Y930245D01*
G03X512415Y930211I-1053J-1962D01*
G02X510941I-737J1277D01*
G01X510900Y930235D01*
G03X508716Y930211I-1071J-1952D01*
G01X508745Y930227D01*
X508327Y929982D01*
G03X506130Y928284I5523J-9416D01*
G01X506129Y928283D01*
G01X551867Y914535D02*
X550966D01*
X548575Y916926D01*
G03X547772Y917482I-1935J-1936D01*
G02X547758Y917489I1217J2452D01*
G03X545716Y917393I-928J-2023D01*
G02X544242I-737J1277D01*
G03X542016I-1113J-1927D01*
G02X540542I-737J1277D01*
G01X540507Y917413D01*
G02X539804Y918670I772J1257D01*
G01Y918743D01*
G03X538692Y920598I-2225J-73D01*
G03X536466I-1113J-1928D01*
G02X534992I-737J1277D01*
G03X532766I-1113J-1928D01*
G02X531292I-737J1277D01*
G03X529066I-1113J-1928D01*
G02X527592I-737J1277D01*
G03X525366I-1113J-1928D01*
G02X523892I-737J1277D01*
G03X521666I-1113J-1928D01*
G02X520192I-737J1277D01*
G01X520162Y920614D01*
G03X517966Y920597I-1083J-1944D01*
G02X516509Y920587I-737J1278D01*
G01X516462Y920614D01*
G03X514266Y920597I-1083J-1944D01*
G02X512809Y920587I-737J1278D01*
G01X512791Y920597D01*
X512762Y920614D01*
G03X510566Y920597I-1083J-1944D01*
G02X509109Y920587I-737J1278D01*
G01X507530Y921499D01*
G03X506129Y921875I-1402J-2424D01*
G01X551867Y910558D02*
X551267D01*
X550159Y911666D01*
Y912896D01*
X549062Y913993D01*
X546884D01*
G02X546092Y914189I-56J1473D01*
G03X543866I-1113J-1927D01*
G02X542392I-737J1277D01*
G03X540166I-1113J-1927D01*
G02X538692I-737J1277D01*
G01X538657Y914209D01*
G02X537954Y915466I772J1257D01*
G01Y915505D01*
G03X536842Y917393I-2225J-39D01*
G03X534616I-1113J-1927D01*
G02X533142I-737J1277D01*
G03X530916I-1113J-1927D01*
G02X529442I-737J1277D01*
G03X527216I-1113J-1927D01*
G02X525742I-737J1277D01*
G03X523574Y917427I-1114J-1927D01*
G01X523516Y917393D01*
G02X522042I-737J1277D01*
G01X522001Y917417D01*
G03X519815Y917393I-1072J-1951D01*
G02X518341I-737J1277D01*
G01X518283Y917427D01*
G03X516115Y917393I-1054J-1961D01*
G02X514641I-737J1277D01*
G01X514583Y917427D01*
G03X512415Y917393I-1054J-1961D01*
G02X510941I-737J1277D01*
G01X510883Y917427D01*
G03X508715Y917393I-1054J-1961D01*
G02X507241I-737J1277D01*
G01X507183Y917427D01*
G03X505015Y917393I-1054J-1961D01*
G02X503541I-737J1277D01*
G01X503506Y917413D01*
G02X502821Y918444I773J1256D01*
G01X503047Y918670D01*
X504278D01*
G01X552057Y928908D02*
X550819D01*
X549716Y930011D01*
X548678D01*
G02X547941Y930211I5J1476D01*
G01X547906Y930231D01*
G02X547203Y931488I772J1257D01*
G01Y931549D01*
G03X546092Y933415I-2225J-61D01*
G03X543924Y933449I-1114J-1927D01*
G01X543866Y933415D01*
G02X542392I-737J1276D01*
G03X540224Y933449I-1114J-1927D01*
G01X540166Y933415D01*
G02X538692I-737J1276D01*
G03X536524Y933449I-1114J-1927D01*
G01X536466Y933415D01*
G02X534992I-737J1276D01*
G03X532824Y933449I-1114J-1927D01*
G01X532766Y933415D01*
G02X531292I-737J1276D01*
G03X529066I-1113J-1927D01*
G02X527592I-737J1276D01*
G01X527551Y933439D01*
G03X525365Y933415I-1072J-1951D01*
G02X523891I-737J1276D01*
G03X521707Y933439I-1113J-1927D01*
G01X521666Y933415D01*
G02X520192I-737J1276D01*
G03X518024Y933449I-1114J-1927D01*
G01X517966Y933415D01*
G02X516492I-737J1276D01*
G03X514324Y933449I-1114J-1927D01*
G01X514266Y933415D01*
G02X512792I-737J1276D01*
G03X510624Y933449I-1114J-1927D01*
G01X510566Y933415D01*
G02X509092I-737J1276D01*
G03X506866I-1113J-1927D01*
G01X506560Y933238D01*
G03X504278Y931488I5495J-9528D01*
G01X551424Y921023D02*
X551219D01*
X550983Y920787D01*
X550460D01*
X549694Y921552D01*
G03X549343Y921852I-2159J-2170D01*
G01X547628Y923113D01*
G03X545272Y923631I-1762J-2397D01*
G02X544241Y923802I-290J1447D01*
G01X544235Y923805D01*
X544206Y923822D01*
G02X543503Y925079I772J1257D01*
G01Y925140D01*
G03X542392Y927006I-2225J-61D01*
G03X540224Y927040I-1114J-1927D01*
G01X540166Y927006D01*
G02X538692I-737J1277D01*
G03X536524Y927040I-1114J-1927D01*
G01X536466Y927006D01*
G02X534992I-737J1277D01*
G03X532766I-1113J-1927D01*
G02X531292I-737J1277D01*
G03X529066I-1113J-1927D01*
G02X527592I-737J1277D01*
G03X525366I-1113J-1927D01*
G02X523892I-737J1277D01*
G03X521706Y927030I-1114J-1927D01*
G01X521665Y927006D01*
X521666D01*
G02X520214Y926993I-737J1277D01*
G01X520168Y927019D01*
G03X517966Y927006I-1090J-1940D01*
G02X516514Y926993I-737J1277D01*
G01X516468Y927019D01*
G03X514266Y927006I-1090J-1940D01*
G02X512814Y926993I-737J1277D01*
G02X512807Y926996I575J1350D01*
G01X512804Y926998D01*
X512794Y927004D01*
X512755Y927025D01*
G03X510460Y926941I-1078J-1948D01*
G01X509521Y926328D01*
X508825Y926294D01*
X508715Y926356D01*
G03X506521Y925304I-737J-1277D01*
G01X506296Y925079D01*
X504278D01*
G01X551424Y919803D02*
X551218D01*
X550983Y920038D01*
X550149D01*
X549165Y921021D01*
G03X548900Y921248I-1632J-1637D01*
G01X547184Y922509D01*
G03X545422Y922897I-1318J-1793D01*
G02X543924Y923118I-443J2181D01*
G01X543866Y923152D01*
X543857Y923157D01*
X543849Y923162D01*
X543842Y923166D01*
G02X542753Y925079I1136J1913D01*
G03X542050Y926336I-1475J0D01*
G01X542015Y926356D01*
G03X540541I-737J-1277D01*
G01X540483Y926322D01*
G02X538315Y926356I-1054J1961D01*
G03X536841I-737J-1277D01*
G01X536800Y926332D01*
G02X534616Y926356I-1071J1951D01*
G03X533142I-737J-1277D01*
G02X530916I-1113J1927D01*
G03X529442I-737J-1277D01*
G02X527216I-1113J1927D01*
G03X525742I-737J-1277D01*
G01X525701Y926332D01*
G02X523515Y926356I-1072J1951D01*
G03X522041I-737J-1277D01*
G02X519839Y926343I-1112J1927D01*
G01X519793Y926369D01*
G03X518341Y926356I-715J-1290D01*
G02X516139Y926343I-1112J1927D01*
G01X516093Y926369D01*
G03X514641Y926356I-715J-1290D01*
G02X512439Y926343I-1112J1927D01*
G01X512435Y926345D01*
X512432Y926347D01*
X512393Y926369D01*
G03X510870Y926314I-716J-1293D01*
G01X509761Y925590D01*
X508422Y925523D01*
X507978Y925079D01*
G01X552924Y947078D02*
X551831D01*
X550814Y948095D01*
X548349D01*
X547566Y948786D01*
G03X546092I-737J-1277D01*
G02X543866I-1113J1927D01*
G03X542392I-737J-1277D01*
G02X540166I-1113J1927D01*
G03X538692I-737J-1277D01*
G02X536466I-1113J1927D01*
G03X534992I-737J-1277D01*
G02X532766I-1113J1927D01*
G03X531292I-737J-1277D01*
G02X529124Y948752I-1114J1927D01*
G01X529066Y948786D01*
G03X527592I-737J-1277D01*
G02X525366I-1113J1927D01*
G03X523892I-737J-1277D01*
G02X521706Y948762I-1114J1927D01*
G01X521665Y948786D01*
G03X520191I-737J-1277D01*
G02X518007Y948762I-1113J1927D01*
G01X517966Y948786D01*
G03X516492I-737J-1277D01*
G02X514324Y948752I-1114J1927D01*
G01X514266Y948786D01*
G03X512792I-737J-1277D01*
G02X510624Y948752I-1114J1927D01*
G01X510566Y948786D01*
G03X509092I-737J-1277D01*
G02X506866I-1113J1927D01*
G03X505392I-737J-1277D01*
G01X505357Y948766D01*
G03X504672Y947735I773J-1256D01*
G01X504898Y947509D01*
X506129D01*
G01X552924Y936581D02*
X551645D01*
X548989Y939237D01*
X548179D01*
G03X547942Y939173I0J-472D01*
G02X545716I-1113J1927D01*
G03X544242I-737J-1277D01*
G02X542016I-1113J1927D01*
G03X540542I-737J-1277D01*
G02X538316I-1113J1927D01*
G03X536842I-737J-1277D01*
G02X534616I-1113J1927D01*
G03X533142I-737J-1277D01*
G02X530916I-1113J1927D01*
G03X529442I-737J-1277D01*
G01X529441D01*
G02X527216I-1112J1927D01*
G01X527206Y939179D01*
G03X525741Y939173I-727J-1283D01*
G02X523545Y939156I-1113J1927D01*
G01X523516Y939173D01*
X523498Y939184D01*
G03X522041Y939173I-719J-1288D01*
G02X519845Y939156I-1113J1927D01*
G01X519816Y939173D01*
X519798Y939184D01*
G03X518341Y939173I-719J-1288D01*
G02X516145Y939156I-1113J1927D01*
G01X516116Y939173D01*
X516098Y939184D01*
G03X514641Y939173I-719J-1288D01*
G02X512445Y939156I-1113J1927D01*
G01X512416Y939173D01*
X512398Y939184D01*
G03X510941Y939173I-719J-1288D01*
G02X508745Y939156I-1113J1927D01*
G01X508307Y939414D01*
G02X506130Y941099I5539J9405D01*
G01X506129Y941100D01*
G01X552057Y932069D02*
X551539D01*
X547873Y935735D01*
G03X547566Y935968I-1038J-1049D01*
G03X546092I-737J-1277D01*
G02X543866I-1113J1928D01*
G03X542392I-737J-1277D01*
G02X540166I-1113J1928D01*
G03X538692I-737J-1277D01*
G02X536466I-1113J1928D01*
G03X534992I-737J-1277D01*
G02X532766I-1113J1928D01*
G03X531292I-737J-1277D01*
G02X529066I-1113J1928D01*
G01Y935969D01*
G03X527591I-737J-1277D01*
G01X527577Y935960D01*
G02X525366Y935969I-1098J1936D01*
G03X523914Y935982I-737J-1277D01*
G01X523891Y935969D01*
X523868Y935955D01*
G02X521666Y935969I-1089J1941D01*
G03X520214Y935982I-737J-1277D01*
G01X520191Y935969D01*
X520168Y935955D01*
G02X517966Y935969I-1089J1941D01*
G03X516514Y935982I-737J-1277D01*
G01X516491Y935969D01*
X516468Y935955D01*
G02X514266Y935969I-1089J1941D01*
G03X512814Y935982I-737J-1277D01*
G01X512791Y935969D01*
X512768Y935955D01*
G02X510566Y935969I-1089J1941D01*
G03X509114Y935982I-737J-1277D01*
G01X509091Y935969D01*
X509068Y935955D01*
G02X506866Y935969I-1089J1941D01*
G01X506551Y936151D01*
G02X504278Y937896I5502J9519D01*
G01X552924Y941915D02*
X552832D01*
X552596Y941679D01*
X551643D01*
X550494Y942828D01*
X548678D01*
G02X547883Y943061I1J1476D01*
G03X545715Y943027I-1054J-1961D01*
G02X544241I-737J1277D01*
G01X544183Y943061D01*
G03X542015Y943027I-1054J-1961D01*
G02X540541I-737J1277D01*
G01X540483Y943061D01*
G03X538315Y943027I-1054J-1961D01*
G02X536841I-737J1277D01*
G01X536840D01*
G03X534618Y943026I-1110J-1927D01*
G01X534616Y943027D01*
G02X533142I-737J1277D01*
G01X533101Y943051D01*
G03X530915Y943027I-1072J-1951D01*
G02X529441I-737J1277D01*
G01X529400Y943051D01*
G03X527216Y943027I-1071J-1951D01*
G02X525742I-737J1277D01*
G01X525701Y943051D01*
G03X523515Y943027I-1072J-1951D01*
G02X522041I-737J1277D01*
G01X522000Y943051D01*
G03X519816Y943027I-1071J-1951D01*
G02X518342I-737J1277D01*
G01X518301Y943051D01*
G03X516115Y943027I-1072J-1951D01*
G02X514641I-737J1277D01*
G01X514583Y943061D01*
G03X512415Y943027I-1054J-1961D01*
G02X510941I-737J1277D01*
G01X510462Y943304D01*
X510148Y943388D01*
X508671D01*
X508216Y943479D01*
X507978Y943717D01*
Y944304D01*
G01X552924Y940695D02*
X552832D01*
X552597Y940930D01*
X551332D01*
X550183Y942079D01*
X548928D01*
X548927Y942078D01*
X548926Y942079D01*
X548677D01*
G02X547566Y942377I1J2225D01*
G03X546092I-737J-1277D01*
G02X543924Y942343I-1114J1927D01*
G01X543866Y942377D01*
G03X542392I-737J-1277D01*
G02X540224Y942343I-1114J1927D01*
G01X540166Y942377D01*
G03X538692I-737J-1277D01*
G02X536524Y942343I-1114J1927D01*
G01X536466Y942377D01*
G03X534992I-737J-1277D01*
G02X532766I-1113J1927D01*
G03X531292I-737J-1277D01*
G02X529124Y942343I-1114J1927D01*
G01X529066Y942377D01*
G03X527592I-737J-1277D01*
G02X525366I-1113J1927D01*
G03X523892I-737J-1277D01*
G02X521724Y942343I-1114J1927D01*
G01X521666Y942377D01*
G03X520192I-737J-1277D01*
G02X517966I-1113J1927D01*
G03X516492I-737J-1277D01*
G02X514324Y942343I-1114J1927D01*
G01X514266Y942377D01*
G03X512792I-737J-1277D01*
G01X512790Y942378D01*
G02X510566I-1112J1926D01*
G01X510172Y942606D01*
X510049Y942639D01*
X508597D01*
X507990Y942760D01*
X507794Y942841D01*
G02X507241Y943027I184J1463D01*
G01X507235Y943030D01*
X507206Y943047D01*
G02X506521Y944079I773J1256D01*
G01X506296Y944304D01*
X504278D01*
G01X552924Y951015D02*
X551935D01*
X550430Y952520D01*
X548567D01*
X548127Y952080D01*
G03X547942Y951990I551J-1368D01*
G02X545716I-1113J1927D01*
G03X544242I-737J-1277D01*
G02X542016I-1113J1927D01*
G03X540542I-737J-1277D01*
G02X538316I-1113J1927D01*
G03X536842I-737J-1277D01*
G02X534616I-1113J1927D01*
G03X533142I-737J-1277D01*
G01X533101Y951966D01*
G02X530915Y951990I-1072J1951D01*
G03X529441I-737J-1277D01*
G01X529400Y951966D01*
G02X527216Y951990I-1071J1951D01*
G03X525742I-737J-1277D01*
G01X525701Y951966D01*
G02X523515Y951990I-1072J1951D01*
G03X522041I-737J-1277D01*
G01X521983Y951956D01*
G02X519815Y951990I-1054J1961D01*
G03X518341I-737J-1277D01*
G01X518283Y951956D01*
G02X516115Y951990I-1054J1961D01*
G03X514641I-737J-1277D01*
G01X514583Y951956D01*
G02X512415Y951990I-1054J1961D01*
G03X510941I-737J-1277D01*
G01X510900Y951966D01*
G02X508716Y951990I-1071J1951D01*
G03X507242I-737J-1277D01*
G01X507201Y951966D01*
G02X505015Y951990I-1072J1951D01*
G03X503541I-737J-1277D01*
G01X503506Y951970D01*
G03X502821Y950939I773J-1256D01*
G01X503047Y950713D01*
X504278D01*
G01X542177Y956697D02*
X541367D01*
X539963Y958101D01*
X539429D01*
G02X538316Y958399I-1J2225D01*
G03X536842I-737J-1277D01*
G02X534616I-1113J1927D01*
G03X533142I-737J-1277D01*
G01X533101Y958375D01*
G02X530915Y958399I-1072J1951D01*
G03X529441I-737J-1277D01*
G01X529400Y958375D01*
G02X527216Y958399I-1071J1951D01*
G03X525742I-737J-1277D01*
G02X523516I-1113J1927D01*
G03X522042I-737J-1277D01*
G01X522001Y958375D01*
G02X519815Y958399I-1072J1951D01*
G03X518341I-737J-1277D01*
G01X518283Y958365D01*
G02X516115Y958399I-1054J1961D01*
G03X514641I-737J-1277D01*
G01X514583Y958365D01*
G02X512415Y958399I-1054J1961D01*
G03X510941I-737J-1277D01*
G02X508715I-1113J1927D01*
G03X507241I-737J-1277D01*
G01X507183Y958365D01*
G02X505015Y958399I-1054J1961D01*
G03X503541I-737J-1277D01*
G01X503506Y958379D01*
G03X502821Y957347I773J-1256D01*
G01X503046Y957122D01*
X504278D01*
G01X540593Y962793D02*
X539819Y962019D01*
X539215D01*
X539152Y961956D01*
G02X536524Y961569I-1574J1574D01*
G01X536466Y961603D01*
G03X534992I-737J-1277D01*
G02X532766I-1113J1927D01*
G03X531292I-737J-1277D01*
G02X529124Y961569I-1114J1927D01*
G01X529066Y961603D01*
G03X527592I-737J-1277D01*
G02X525366I-1113J1927D01*
G03X523892I-737J-1277D01*
G02X521724Y961569I-1114J1927D01*
G01X521666Y961603D01*
G03X520192I-737J-1277D01*
G02X517966I-1113J1927D01*
G03X516492I-737J-1277D01*
G02X514324Y961569I-1114J1927D01*
G01X514266Y961603D01*
G03X512792I-737J-1277D01*
G02X510606Y961579I-1114J1927D01*
G01X510565Y961603D01*
G03X509091I-737J-1277D01*
G02X508191Y961315I-1113J1927D01*
G03X506161Y960358I318J-3306D01*
G01X506129Y960326D01*
G01X510106Y996900D02*
Y997684D01*
X508787Y999003D01*
Y999684D01*
G03X507698Y1001597I-2225J0D01*
G01X506153Y1002498D01*
G03X504711Y1002888I-1442J-2472D01*
G01X508036Y996900D02*
Y999718D01*
G03X507299Y1000961I-1474J-34D01*
G03X506599Y1001267I-1712J-2962D01*
G03X506252Y1001319I-345J-1122D01*
G01X504799D01*
G02X501011Y1002888I0J5356D01*
G01X536471Y996825D02*
X520413D01*
X519136Y998102D01*
Y999780D01*
G03X518443Y1001019I-1454J0D01*
G03X517690Y1001219I-753J-1318D01*
G01X515019D01*
X512111Y1002888D01*
G01X550025Y1023653D02*
X547553D01*
X547405Y1023801D01*
G02X546489Y1024061I0J1744D01*
G02X545786Y1025318I772J1257D01*
G01Y1025391D01*
G03X544674Y1027246I-2225J-73D01*
G03X542448I-1113J-1928D01*
G02X540974I-737J1277D01*
G03X538748I-1113J-1928D01*
G02X537274I-737J1277D01*
G03X535048I-1113J-1928D01*
G02X533574I-737J1277D01*
G03X531348I-1113J-1928D01*
G02X529874I-737J1277D01*
G01X529816Y1027280D01*
G03X527648Y1027246I-1053J-1962D01*
G02X526174I-737J1277D01*
G03X523948I-1113J-1928D01*
G02X522474I-737J1277D01*
G01X522416Y1027280D01*
G03X520248Y1027246I-1053J-1962D01*
G02X518774I-737J1277D01*
G01X518716Y1027280D01*
G03X516548Y1027246I-1053J-1962D01*
G02X515074I-737J1277D01*
G01X515016Y1027280D01*
G03X512848Y1027246I-1053J-1962D01*
G02X511374I-737J1277D01*
G01X511316Y1027280D01*
G03X509148Y1027246I-1053J-1962D01*
G02X507674I-737J1277D01*
G01X507639Y1027266D01*
G02X506936Y1028523I772J1257D01*
G01Y1028584D01*
G03X505825Y1030450I-2225J-61D01*
G03X503657Y1030484I-1114J-1927D01*
G01X503599Y1030450D01*
X503575Y1030436D01*
G03X502501Y1028782I1136J-1913D01*
G01X502242Y1028523D01*
X501011D01*
G01X553025Y1025674D02*
X551086D01*
X550465Y1026295D01*
X549114D01*
G02X547998Y1026595I0J2226D01*
G02X546886Y1028450I1113J1928D01*
G01Y1028523D01*
G03X546183Y1029780I-1475J0D01*
G01X546148Y1029800D01*
G03X544674I-737J-1277D01*
G02X542448I-1113J1927D01*
G03X540974I-737J-1277D01*
G02X538748I-1113J1927D01*
G03X537274I-737J-1277D01*
G02X535048I-1113J1927D01*
G03X533574I-737J-1277D01*
G02X531348I-1113J1927D01*
G03X529874I-737J-1277D01*
G01X529816Y1029766D01*
G02X527648Y1029800I-1054J1961D01*
G03X526174I-737J-1277D01*
G01X526116Y1029766D01*
G02X523948Y1029800I-1054J1961D01*
G03X522474I-737J-1277D01*
G02X520248I-1113J1927D01*
G03X518774I-737J-1277D01*
G01X518716Y1029766D01*
G02X516548Y1029800I-1054J1961D01*
G03X515074I-737J-1277D01*
G01X515016Y1029766D01*
G02X512848Y1029800I-1054J1961D01*
G03X511374I-737J-1277D01*
G01X511316Y1029766D01*
G02X509148Y1029800I-1054J1961D01*
G02X506562Y1031727I6959J12037D01*
G01X550025Y1021693D02*
X548247D01*
X546862Y1023078D01*
G02X545036Y1025257I462J2242D01*
G01Y1025318D01*
G03X544333Y1026575I-1475J0D01*
G01X544298Y1026595D01*
G03X542824I-737J-1277D01*
G02X540598I-1113J1928D01*
G03X539124I-737J-1277D01*
G02X536898I-1113J1928D01*
G03X535424I-737J-1277D01*
G02X533198I-1113J1928D01*
G03X531724I-737J-1277D01*
G02X529540Y1026571I-1113J1928D01*
G01X529499Y1026595D01*
G03X528025I-737J-1277D01*
G02X525839Y1026571I-1114J1928D01*
G01X525798Y1026595D01*
G03X524324I-737J-1277D01*
G02X522140Y1026571I-1113J1928D01*
G01X522099Y1026595D01*
G03X520625I-737J-1277D01*
G02X518457Y1026561I-1115J1928D01*
G01X518399Y1026595D01*
G03X516925I-737J-1277D01*
G02X514757Y1026561I-1115J1928D01*
G01X514699Y1026595D01*
G03X513225I-737J-1277D01*
G02X511057Y1026561I-1115J1928D01*
G01X510999Y1026595D01*
G03X509525I-737J-1277D01*
G02X507357Y1026561I-1115J1928D01*
G01X507299Y1026595D01*
G02X506186Y1028467I1112J1928D01*
G01Y1028523D01*
G03X505483Y1029780I-1475J0D01*
G01X505448Y1029800D01*
G03X503974I-737J-1277D01*
G01X503939Y1029780D01*
G03X503254Y1028749I773J-1256D01*
G01X503480Y1028523D01*
X504711D01*
G01X553526Y1042014D02*
X551585D01*
X550685Y1042914D01*
G03X548057Y1043301I-1574J-1574D01*
G01X547999Y1043267D01*
G02X546525I-737J1277D01*
G03X544357Y1043301I-1114J-1927D01*
G01X544299Y1043267D01*
G02X542825I-737J1277D01*
G03X540657Y1043301I-1114J-1927D01*
G01X540599Y1043267D01*
G02X539125I-737J1277D01*
G03X536957Y1043301I-1114J-1927D01*
G01X536899Y1043267D01*
G02X535425I-737J1277D01*
G03X533257Y1043301I-1114J-1927D01*
G01X533199Y1043267D01*
G02X531725I-737J1277D01*
G03X529557Y1043301I-1114J-1927D01*
G01X529499Y1043267D01*
G02X528042Y1043256I-738J1277D01*
G01X528024Y1043267D01*
X527995Y1043284D01*
G03X525799Y1043267I-1083J-1944D01*
G02X524342Y1043256I-738J1277D01*
G01X524324Y1043267D01*
X524295Y1043284D01*
G03X522099Y1043267I-1083J-1944D01*
G02X520642Y1043256I-738J1277D01*
G01X520624Y1043267D01*
X520595Y1043284D01*
G03X518399Y1043267I-1083J-1944D01*
G02X516942Y1043256I-738J1277D01*
G01X516924Y1043267D01*
X516895Y1043284D01*
G03X514699Y1043267I-1083J-1944D01*
G02X513242Y1043256I-738J1277D01*
G01X513224Y1043267D01*
X513195Y1043284D01*
G03X510999Y1043267I-1083J-1944D01*
G02X509542Y1043256I-738J1277D01*
G01X509524Y1043267D01*
X509495Y1043284D01*
G03X507299Y1043267I-1083J-1944D01*
G02X505842Y1043256I-738J1277D01*
G01X505824Y1043267D01*
X505795Y1043284D01*
G03X503599Y1043267I-1083J-1944D01*
G03X503108Y1042882I1114J-1926D01*
G02X501011Y1041340I-5495J5276D01*
G01X553526Y1040046D02*
X552493D01*
X550155Y1042384D01*
G03X549848Y1042617I-1038J-1049D01*
G03X548374I-737J-1277D01*
G01X548316Y1042583D01*
G02X546148Y1042617I-1054J1961D01*
G03X544674I-737J-1277D01*
G01X544616Y1042583D01*
G02X542448Y1042617I-1054J1961D01*
G03X540974I-737J-1277D01*
G01X540916Y1042583D01*
G02X538748Y1042617I-1054J1961D01*
G03X537274I-737J-1277D01*
G01X537216Y1042583D01*
G02X535048Y1042617I-1054J1961D01*
G03X533574I-737J-1277D01*
G01X533516Y1042583D01*
G02X531348Y1042617I-1054J1961D01*
G03X529874I-737J-1277D01*
G02X527678Y1042600I-1113J1927D01*
G01X527649Y1042617D01*
X527631Y1042628D01*
G03X526174Y1042617I-719J-1288D01*
G02X523978Y1042600I-1113J1927D01*
G01X523949Y1042617D01*
X523931Y1042628D01*
G03X522474Y1042617I-719J-1288D01*
G02X520278Y1042600I-1113J1927D01*
G01X520249Y1042617D01*
X520231Y1042628D01*
G03X518774Y1042617I-719J-1288D01*
G02X516578Y1042600I-1113J1927D01*
G01X516549Y1042617D01*
X516531Y1042628D01*
G03X515074Y1042617I-719J-1288D01*
G02X512878Y1042600I-1113J1927D01*
G01X512849Y1042617D01*
X512831Y1042628D01*
G03X511374Y1042617I-719J-1288D01*
G02X509178Y1042600I-1113J1927D01*
G01X509149Y1042617D01*
X509131Y1042628D01*
G03X507674Y1042617I-719J-1288D01*
G02X506569Y1042319I-1112J1927D01*
G03X504711Y1041340I0J-2253D01*
G01X553526Y1036088D02*
X552760D01*
X549733Y1039115D01*
X549110D01*
G02X548967Y1039119I-9J2225D01*
G02X547999Y1039413I146J2220D01*
G03X546525I-737J-1277D01*
G02X544357Y1039379I-1114J1927D01*
G01X544299Y1039413D01*
G03X542825I-737J-1277D01*
G02X540639Y1039389I-1114J1927D01*
G01X540598Y1039413D01*
G03X539124I-737J-1277D01*
G02X536898I-1113J1927D01*
G03X535424I-737J-1277D01*
G02X533198I-1113J1927D01*
G03X531724I-737J-1277D01*
G02X529540Y1039389I-1113J1927D01*
G01X529499Y1039413D01*
G03X528025I-737J-1277D01*
G02X525857Y1039379I-1114J1927D01*
G01X525799Y1039413D01*
G03X524347Y1039426I-737J-1277D01*
G01X524324Y1039413D01*
X524301Y1039399D01*
G02X522099Y1039413I-1089J1941D01*
G03X520647Y1039426I-737J-1277D01*
G01X520624Y1039413D01*
X520601Y1039399D01*
G02X518399Y1039413I-1089J1941D01*
G03X516947Y1039426I-737J-1277D01*
G01X516924Y1039413D01*
X516901Y1039399D01*
G02X514699Y1039413I-1089J1941D01*
G03X513247Y1039426I-737J-1277D01*
G01X513224Y1039413D01*
X513201Y1039399D01*
G02X510999Y1039413I-1089J1941D01*
G03X509547Y1039426I-737J-1277D01*
G01X509524Y1039413D01*
X507958Y1038510D01*
G02X506562Y1038136I-1397J2423D01*
G01X553526Y1047114D02*
X552427D01*
X552136Y1046823D01*
X551156D01*
G03X549848Y1046472I0J-2614D01*
G02X548374I-737J1277D01*
G01X548316Y1046506D01*
G03X546148Y1046472I-1053J-1962D01*
G02X544674I-737J1277D01*
G01X544616Y1046506D01*
G03X542448Y1046472I-1053J-1962D01*
G02X540974I-737J1277D01*
G01X540916Y1046506D01*
G03X538748Y1046472I-1053J-1962D01*
G02X537274I-737J1277D01*
G01X537216Y1046506D01*
G03X535048Y1046472I-1053J-1962D01*
G02X533574I-737J1277D01*
G01X533516Y1046506D01*
G03X531348Y1046472I-1053J-1962D01*
G01X531349Y1046471D01*
X531326Y1046458D01*
G02X529874Y1046471I-715J1290D01*
G03X527672Y1046485I-1113J-1927D01*
G01X527649Y1046471D01*
X527626Y1046458D01*
G02X526174Y1046471I-715J1290D01*
G03X523972Y1046485I-1113J-1927D01*
G01X523949Y1046471D01*
X523926Y1046458D01*
G02X522474Y1046471I-715J1290D01*
G03X520272Y1046485I-1113J-1927D01*
G01X520249Y1046471D01*
X520226Y1046458D01*
G02X518774Y1046471I-715J1290D01*
G03X516572Y1046485I-1113J-1927D01*
G01X516549Y1046471D01*
X516526Y1046458D01*
G02X515074Y1046471I-715J1290D01*
G03X512872Y1046485I-1113J-1927D01*
G01X512849Y1046471D01*
X512826Y1046458D01*
G02X511374Y1046471I-715J1290D01*
G01X511333Y1046495D01*
G03X509149Y1046471I-1071J-1951D01*
G02X506937Y1047748I-737J1277D01*
G03X505849Y1049661I-2226J0D01*
G01X505825Y1049675D01*
G03X503657Y1049709I-1114J-1927D01*
G01X503599Y1049675D01*
X503480Y1049607D01*
X501011Y1047749D01*
G01X553526Y1045140D02*
X552380D01*
X551699Y1045821D01*
G03X550225I-737J-1277D01*
G02X548057Y1045787I-1115J1928D01*
G01X547999Y1045821D01*
G03X546525I-737J-1277D01*
G02X544357Y1045787I-1115J1928D01*
G01X544299Y1045821D01*
G03X542825I-737J-1277D01*
G02X540657Y1045787I-1115J1928D01*
G01X540599Y1045821D01*
G03X539125I-737J-1277D01*
G02X536957Y1045787I-1115J1928D01*
G01X536899Y1045821D01*
G03X535425I-737J-1277D01*
G02X533257Y1045787I-1115J1928D01*
G01X533199Y1045821D01*
G03X531725I-737J-1277D01*
G01X531701Y1045808D01*
G02X529499Y1045822I-1089J1941D01*
G03X528047Y1045835I-737J-1278D01*
G01X528024Y1045822D01*
X528001Y1045808D01*
G02X525799Y1045822I-1089J1941D01*
G03X524347Y1045835I-737J-1278D01*
G01X524324Y1045822D01*
X524301Y1045808D01*
G02X522099Y1045822I-1089J1941D01*
G03X520647Y1045835I-737J-1278D01*
G01X520624Y1045822D01*
X520601Y1045808D01*
G02X518399Y1045822I-1089J1941D01*
G03X516947Y1045835I-737J-1278D01*
G01X516924Y1045822D01*
X516901Y1045808D01*
G02X514699Y1045822I-1089J1941D01*
G03X513247Y1045835I-737J-1278D01*
G01X513224Y1045822D01*
X513201Y1045808D01*
G02X510999Y1045822I-1089J1941D01*
G03X509547Y1045835I-737J-1278D01*
G01X509524Y1045822D01*
X509501Y1045808D01*
G02X507299Y1045822I-1089J1941D01*
G01X506992Y1045999D01*
G02X504713Y1047747I5460J9478D01*
G01X504711Y1047749D01*
G01X554726Y1030859D02*
X554634D01*
X554398Y1030623D01*
X552729D01*
X552356Y1030250D01*
X550961D01*
G02X550224Y1030450I5J1475D01*
G01X550168Y1030482D01*
G02X549486Y1031726I794J1244D01*
G01Y1031788D01*
G03X548375Y1033654I-2225J-61D01*
G03X546207Y1033688I-1114J-1927D01*
G01X546149Y1033654D01*
G02X544675I-737J1277D01*
G03X542489Y1033678I-1114J-1927D01*
G01X542448Y1033654D01*
G02X540974I-737J1277D01*
G03X538748I-1113J-1927D01*
G02X537274I-737J1277D01*
G03X535048I-1113J-1927D01*
G02X533574I-737J1277D01*
G03X531348I-1113J-1927D01*
G02X529874I-737J1277D01*
G01X529816Y1033688D01*
G03X527648Y1033654I-1054J-1961D01*
G02X526174I-737J1277D01*
G01X526116Y1033688D01*
G03X523948Y1033654I-1054J-1961D01*
G02X522474I-737J1277D01*
G03X520290Y1033678I-1113J-1927D01*
G01X520249Y1033654D01*
G02X518775I-737J1277D01*
G01X518734Y1033678D01*
G03X516548Y1033654I-1072J-1951D01*
G02X515074I-737J1277D01*
G01X515016Y1033688D01*
G03X512849Y1033655I-1054J-1961D01*
G01X512848Y1033654D01*
G02X511374I-737J1277D01*
G01X511370Y1033656D01*
X510918Y1033920D01*
X510058Y1034121D01*
X508634D01*
X508411Y1034344D01*
Y1034931D01*
G01X554726Y1029639D02*
X554634D01*
X554399Y1029874D01*
X553040D01*
X552667Y1029501D01*
X550961D01*
G02X549848Y1029799I-1J2225D01*
G02X549765Y1029849I1107J1931D01*
G02X548735Y1031688I1195J1877D01*
G01X548736Y1031727D01*
G03X548033Y1032984I-1475J0D01*
G01X547998Y1033004D01*
G03X546524I-737J-1277D01*
G01X546466Y1032970D01*
G02X544298Y1033004I-1054J1961D01*
G03X542824I-737J-1277D01*
G02X540598I-1113J1927D01*
G03X539124I-737J-1277D01*
G01X539123Y1033003D01*
G02X536898Y1033004I-1112J1928D01*
G01X536899Y1033005D01*
G03X535422I-739J-1278D01*
G01X535423Y1033003D01*
G02X533198Y1033004I-1112J1928D01*
G03X531724I-737J-1277D01*
G02X529540Y1032980I-1113J1927D01*
G01X529499Y1033004D01*
G03X528025I-737J-1277D01*
G02X525857Y1032970I-1114J1927D01*
G01X525799Y1033004D01*
G03X524325I-737J-1277D01*
G02X522139Y1032980I-1114J1927D01*
G01X522098Y1033004D01*
G03X520624I-737J-1277D01*
G01X520583Y1032980D01*
G02X518399Y1033004I-1071J1951D01*
G03X516925I-737J-1277D01*
G02X514757Y1032970I-1114J1927D01*
G01X514699Y1033004D01*
G03X513253Y1033019I-736J-1277D01*
G01X513225Y1033004D01*
G02X511057Y1032970I-1114J1927D01*
G01X510637Y1033216D01*
X509971Y1033372D01*
X508501D01*
X508423Y1033387D01*
X508227Y1033468D01*
G02X507674Y1033654I184J1463D01*
G01X507668Y1033657D01*
X507639Y1033674D01*
G02X506954Y1034706I773J1256D01*
G01X506729Y1034931D01*
X504711D01*
G01X553526Y1065454D02*
X552739D01*
X551429Y1064579D01*
X550840Y1063157D01*
X550474Y1062791D01*
X549111D01*
G03X547999Y1062493I1J-2227D01*
G02X546525I-737J1277D01*
G03X544357Y1062527I-1115J-1928D01*
G01X544299Y1062493D01*
G02X542825I-737J1277D01*
G03X540657Y1062527I-1115J-1928D01*
G01X540599Y1062493D01*
G02X539125I-737J1277D01*
G03X536957Y1062527I-1115J-1928D01*
G01X536899Y1062493D01*
G02X535425I-737J1277D01*
G03X533257Y1062527I-1115J-1928D01*
G01X533199Y1062493D01*
G02X531725I-737J1277D01*
G03X529557Y1062527I-1115J-1928D01*
G01X529499Y1062493D01*
G02X528025I-737J1277D01*
G03X525839Y1062517I-1114J-1928D01*
G01X525798Y1062493D01*
G02X524324I-737J1277D01*
G01X524283Y1062517D01*
G03X522099Y1062493I-1071J-1952D01*
G02X520625I-737J1277D01*
G03X518457Y1062527I-1115J-1928D01*
G01X518399Y1062493D01*
G02X516925I-737J1277D01*
G03X514757Y1062527I-1115J-1928D01*
G01X514699Y1062493D01*
G02X513225I-737J1277D01*
G03X511057Y1062527I-1115J-1928D01*
G01X510999Y1062493D01*
G02X509525I-737J1277D01*
G03X507357Y1062527I-1115J-1928D01*
G01X507299Y1062493D01*
G02X505825I-737J1277D01*
G03X503657Y1062527I-1115J-1928D01*
G01X503599Y1062493D01*
X503485Y1062428D01*
X501011Y1060565D01*
G01X553526Y1063478D02*
X552483D01*
X551047Y1062042D01*
X549112D01*
G03X548374Y1061842I4J-1477D01*
G01X548316Y1061808D01*
G02X546148Y1061842I-1053J1962D01*
G03X544674I-737J-1277D01*
G01X544616Y1061808D01*
G02X542448Y1061842I-1053J1962D01*
G03X540974I-737J-1277D01*
G01X540916Y1061808D01*
G02X538748Y1061842I-1053J1962D01*
G03X537274I-737J-1277D01*
G01X537216Y1061808D01*
G02X535048Y1061842I-1053J1962D01*
G03X533574I-737J-1277D01*
G01X533516Y1061808D01*
G02X531348Y1061842I-1053J1962D01*
G03X529874I-737J-1277D01*
G01X529816Y1061808D01*
G02X527648Y1061842I-1053J1962D01*
G03X526174I-737J-1277D01*
G02X523990Y1061818I-1113J1928D01*
G01X523949Y1061842D01*
G03X522475I-737J-1277D01*
G01X522434Y1061818D01*
G02X520248Y1061842I-1072J1952D01*
G03X518774I-737J-1277D01*
G01X518716Y1061808D01*
G02X516548Y1061842I-1053J1962D01*
G03X515074I-737J-1277D01*
G01X515016Y1061808D01*
G02X512848Y1061842I-1053J1962D01*
G03X511374I-737J-1277D01*
G01X511316Y1061808D01*
G02X509148Y1061842I-1053J1962D01*
G03X507674I-737J-1277D01*
G01X507559Y1061775D01*
X504711Y1060565D01*
G01X553526Y1059434D02*
X551914D01*
X551251Y1058974D01*
G03X550904Y1058927I-2J-1288D01*
G03X550220Y1058638I786J-2815D01*
G02X548036Y1058614I-1113J1927D01*
G01X547995Y1058638D01*
G03X546521I-737J-1277D01*
G02X544337Y1058614I-1113J1927D01*
G01X544296Y1058638D01*
G03X542822I-737J-1277D01*
G02X540638Y1058614I-1113J1927D01*
G01X540597Y1058638D01*
G03X539123I-737J-1277D01*
G01X539082Y1058614D01*
G02X536898Y1058638I-1071J1951D01*
G03X535424I-737J-1277D01*
G02X533240Y1058614I-1113J1927D01*
G01X533199Y1058638D01*
G03X531725I-737J-1277D01*
G02X529557Y1058604I-1114J1927D01*
G01X529499Y1058638D01*
G03X528025I-737J-1277D01*
G02X525857Y1058604I-1114J1927D01*
G01X525799Y1058638D01*
G03X524325I-737J-1277D01*
G02X522099I-1113J1927D01*
G03X520625I-737J-1277D01*
G02X518457Y1058604I-1114J1927D01*
G01X518399Y1058638D01*
G03X516925I-737J-1277D01*
G02X514757Y1058604I-1114J1927D01*
G01X514699Y1058638D01*
G03X513225I-737J-1277D01*
G02X511057Y1058604I-1114J1927D01*
G01X510999Y1058638D01*
G03X509525I-737J-1277D01*
G01X509412Y1058572D01*
X506562Y1057361D01*
G01X553526Y1049098D02*
X552550D01*
G03X552336Y1049066I-1J-722D01*
G01X552076Y1048985D01*
G03X551746Y1048870I1689J-5377D01*
G02X550031Y1048927I-789J2081D01*
G03X548183I-924J-2023D01*
G02X546187Y1049001I-924J2025D01*
G01X546146Y1049025D01*
G03X544672I-737J-1276D01*
G02X542488Y1049001I-1113J1927D01*
G01X542447Y1049025D01*
G03X540973I-737J-1276D01*
G02X538789Y1049001I-1113J1927D01*
G01X538748Y1049025D01*
G03X537274I-737J-1276D01*
G02X535048I-1113J1927D01*
G03X533574I-737J-1276D01*
G01X533516Y1048991D01*
G02X531348Y1049025I-1054J1961D01*
G01X531326Y1049039D01*
G03X529874Y1049026I-715J-1290D01*
G02X527672Y1049012I-1113J1926D01*
G01X527649Y1049026D01*
X527626Y1049039D01*
G03X526174Y1049026I-715J-1290D01*
G02X523972Y1049012I-1113J1926D01*
G01X523949Y1049026D01*
X523926Y1049039D01*
G03X522474Y1049026I-715J-1290D01*
G02X520272Y1049012I-1113J1926D01*
G01X520249Y1049026D01*
X520226Y1049039D01*
G03X518774Y1049026I-715J-1290D01*
G02X516572Y1049012I-1113J1926D01*
G01X516549Y1049026D01*
X516526Y1049039D01*
G03X515074Y1049026I-715J-1290D01*
G02X512872Y1049012I-1113J1926D01*
G01X512849Y1049026D01*
X512826Y1049039D01*
G03X511374Y1049026I-715J-1290D01*
G02X509172Y1049012I-1113J1926D01*
G01X508979Y1049121D01*
G02X506562Y1050952I5572J9866D01*
G01X553526Y1056243D02*
X553434D01*
X553199Y1056478D01*
X552220D01*
X551231Y1055488D01*
X550033Y1055333D01*
X549819Y1055451D01*
G03X548369Y1055435I-711J-1294D01*
G02X546205Y1055400I-1113J1926D01*
G01X546100Y1055461D01*
G03X544673Y1055434I-689J-1304D01*
G02X542505Y1055400I-1114J1927D01*
G01X542447Y1055434D01*
X542414Y1055453D01*
G03X540974Y1055434I-703J-1296D01*
G02X538806Y1055400I-1114J1927D01*
G01X538748Y1055434D01*
G03X537274I-737J-1277D01*
G02X535048I-1113J1927D01*
G03X533574I-737J-1277D01*
G01X533516Y1055400D01*
G02X531348Y1055434I-1054J1961D01*
G03X529874I-737J-1277D01*
G01X529816Y1055400D01*
G02X527648Y1055434I-1054J1961D01*
G03X526174I-737J-1277D01*
G01X526116Y1055400D01*
G02X523948Y1055434I-1054J1961D01*
G03X522474I-737J-1277D01*
G01X522433Y1055410D01*
G02X520249Y1055434I-1071J1951D01*
G03X518775I-737J-1277D01*
G01X518734Y1055410D01*
G02X516548Y1055434I-1072J1951D01*
G03X515074I-737J-1277D01*
G01X515016Y1055400D01*
G02X512848Y1055434I-1054J1961D01*
G03X511374I-737J-1277D01*
G01X511316Y1055400D01*
G02X509148Y1055434I-1054J1961D01*
G03X507674I-737J-1277D01*
G01X507645Y1055417D01*
Y1055418D01*
G02X505645Y1055335I-1082J1943D01*
G01X505623D01*
X505450Y1055434D01*
Y1055435D01*
G03X503862Y1055363I-738J-1276D01*
G01X503029Y1054774D01*
X502996Y1054766D01*
X502136Y1054157D01*
X501011D01*
G01X553526Y1054257D02*
X553434D01*
X553198Y1054021D01*
X552123D01*
X551280Y1053178D01*
X550956D01*
G03X549844Y1052880I0J-2224D01*
G02X548370I-737J1277D01*
G03X546188Y1052904I-1112J-1928D01*
G01X546100Y1052853D01*
G02X544673Y1052880I-689J1304D01*
G03X542505Y1052914I-1115J-1928D01*
G01X542447Y1052880D01*
X542414Y1052861D01*
G02X540974Y1052880I-703J1296D01*
G03X538806Y1052914I-1115J-1928D01*
G01X538748Y1052880D01*
G02X537274I-737J1277D01*
G03X535048I-1113J-1928D01*
G02X533574I-737J1277D01*
G01X533516Y1052914D01*
G03X531348Y1052880I-1053J-1962D01*
G02X529874I-737J1277D01*
G01X529816Y1052914D01*
G03X527648Y1052880I-1054J-1961D01*
G02X526174I-737J1277D01*
G01X526116Y1052914D01*
G03X523948Y1052880I-1054J-1961D01*
G02X522474I-737J1277D01*
G03X520290Y1052904I-1113J-1927D01*
G01X520249Y1052880D01*
G02X518775I-737J1277D01*
G01X518734Y1052904D01*
G03X516548Y1052880I-1072J-1951D01*
G02X515074I-737J1277D01*
G01X515016Y1052914D01*
G03X512848Y1052880I-1054J-1961D01*
G02X511374I-737J1277D01*
G01X511237Y1052954D01*
X511196Y1052981D01*
X511001Y1053111D01*
X509818Y1053347D01*
X508634D01*
X508411Y1053570D01*
Y1054157D01*
G01X553526Y1053037D02*
X553434D01*
X553199Y1053272D01*
X552434D01*
X551591Y1052429D01*
X550956D01*
G03X550218Y1052231I0J-1474D01*
G02X547996I-1111J1926D01*
G03X546557Y1052251I-737J-1279D01*
G01X546523Y1052232D01*
X546463Y1052197D01*
G02X544298Y1052231I-1052J1960D01*
G03X542871Y1052259I-739J-1279D01*
G01X542823Y1052232D01*
X542781Y1052207D01*
G02X540599Y1052231I-1070J1950D01*
G03X539172Y1052259I-739J-1279D01*
G01X539125Y1052232D01*
G02X536900Y1052231I-1113J1925D01*
G03X535422I-739J-1279D01*
G02X533197Y1052232I-1112J1926D01*
G01X533150Y1052259D01*
G03X531723Y1052231I-688J-1307D01*
G02X529500I-1111J1926D01*
G01X529496Y1052233D01*
X529452Y1052258D01*
G03X528023Y1052231I-690J-1305D01*
G02X525797Y1052232I-1112J1926D01*
G01X525750Y1052260D01*
G03X524323Y1052231I-687J-1307D01*
G02X522099I-1112J1926D01*
G03X520659Y1052251I-738J-1278D01*
G01X520626Y1052232D01*
G02X518398I-1114J1925D01*
G01X518365Y1052252D01*
G03X516923Y1052231I-702J-1299D01*
G02X514697Y1052232I-1112J1926D01*
G01X514650Y1052260D01*
G03X513223Y1052231I-687J-1307D01*
G02X511010Y1052225I-1112J1926D01*
G01X510852Y1052310D01*
X510709Y1052405D01*
X509744Y1052598D01*
X508501D01*
X508423Y1052613D01*
X508227Y1052694D01*
G02X507674Y1052880I184J1463D01*
G01X507668Y1052883D01*
X507639Y1052900D01*
G02X506954Y1053932I773J1256D01*
G01X506729Y1054157D01*
X504711D01*
G01X553526Y1083410D02*
X552823D01*
X551967Y1082554D01*
Y1081966D01*
X547567Y1077566D01*
X545411D01*
G02X544298Y1077864I0J2226D01*
G03X542824I-737J-1277D01*
G02X540598I-1113J1927D01*
G03X539124I-737J-1277D01*
G02X536898I-1113J1927D01*
G03X535424I-737J-1277D01*
G02X533240Y1077840I-1113J1927D01*
G01X533199Y1077864D01*
G03X531725I-737J-1277D01*
G02X529557Y1077830I-1114J1927D01*
G01X529499Y1077864D01*
G03X528025I-737J-1277D01*
G02X525857Y1077830I-1114J1927D01*
G01X525799Y1077864D01*
G03X524325I-737J-1277D01*
G02X522099I-1113J1927D01*
G03X520625I-737J-1277D01*
G02X518457Y1077830I-1114J1927D01*
G01X518399Y1077864D01*
G03X516925I-737J-1277D01*
G02X514757Y1077830I-1114J1927D01*
G01X514699Y1077864D01*
G03X513247Y1077878I-738J-1277D01*
G01X513224Y1077864D01*
X513201Y1077851D01*
G02X510999Y1077864I-1090J1940D01*
G03X509547Y1077878I-738J-1277D01*
G01X509524Y1077864D01*
X507958Y1076961D01*
G02X506562Y1076587I-1397J2423D01*
G01X553526Y1070981D02*
X552901D01*
X549140Y1067220D01*
X548384D01*
X546662Y1065498D01*
X545411D01*
G02X544616Y1065731I1J1476D01*
G03X542448Y1065697I-1054J-1961D01*
G02X540974I-737J1277D01*
G01X540916Y1065731D01*
G03X538748Y1065697I-1054J-1961D01*
G02X537274I-737J1277D01*
G01X537216Y1065731D01*
G03X535048Y1065697I-1054J-1961D01*
G02X533574I-737J1277D01*
G01X533516Y1065731D01*
G03X531348Y1065697I-1054J-1961D01*
G02X529874I-737J1277D01*
G01X529816Y1065731D01*
G03X527648Y1065697I-1054J-1961D01*
G02X526174I-737J1277D01*
G03X523948I-1113J-1927D01*
G02X522474I-737J1277D01*
G01X522416Y1065731D01*
G03X520248Y1065697I-1054J-1961D01*
G02X518774I-737J1277D01*
G01X518716Y1065731D01*
G03X516548Y1065697I-1054J-1961D01*
G02X515074I-737J1277D01*
G01X515016Y1065731D01*
G03X512848Y1065697I-1054J-1961D01*
G02X511374I-737J1277D01*
G01X511316Y1065731D01*
G03X509148Y1065697I-1054J-1961D01*
G02X507674I-737J1277D01*
G01X507639Y1065717D01*
G02X506936Y1066974I772J1257D01*
G01Y1067035D01*
G03X505825Y1068901I-2225J-61D01*
G03X503657Y1068935I-1114J-1927D01*
G01X503599Y1068901D01*
X503575Y1068887D01*
G03X502501Y1067233I1136J-1913D01*
G01X502242Y1066974D01*
X501011D01*
G01X553526Y1072966D02*
X552275D01*
X549487Y1070178D01*
G02X546148Y1068251I-2225J0D01*
G03X544674I-737J-1277D01*
G01X544616Y1068217D01*
G02X542448Y1068251I-1054J1961D01*
G03X540974I-737J-1277D01*
G01X540916Y1068217D01*
G02X538748Y1068251I-1054J1961D01*
G03X537274I-737J-1277D01*
G01X537216Y1068217D01*
G02X535048Y1068251I-1054J1961D01*
G01X535049Y1068252D01*
G03X533574I-737J-1277D01*
G02X531364Y1068243I-1113J1926D01*
G01X531349Y1068252D01*
X531326Y1068265D01*
G03X529874Y1068252I-715J-1290D01*
G02X527672Y1068238I-1113J1926D01*
G01X527649Y1068252D01*
X527626Y1068265D01*
G03X526174Y1068252I-715J-1290D01*
G02X523972Y1068238I-1113J1926D01*
G01X523949Y1068252D01*
X523926Y1068265D01*
G03X522474Y1068252I-715J-1290D01*
G02X520272Y1068238I-1113J1926D01*
G01X520249Y1068252D01*
X520226Y1068265D01*
G03X518774Y1068252I-715J-1290D01*
G02X516572Y1068238I-1113J1926D01*
G01X516549Y1068252D01*
X516526Y1068265D01*
G03X515074Y1068252I-715J-1290D01*
G02X512872Y1068238I-1113J1926D01*
G01X512849Y1068252D01*
X512826Y1068265D01*
G03X511374Y1068252I-715J-1290D01*
G02X509172Y1068238I-1113J1926D01*
G01X508979Y1068347D01*
G02X506562Y1070178I5572J9866D01*
G01X553526Y1069020D02*
X553085D01*
X550536Y1066471D01*
X548695D01*
X546973Y1064749D01*
X545411D01*
G02X544299Y1065047I0J2224D01*
G03X542825I-737J-1277D01*
G02X540657Y1065013I-1114J1927D01*
G01X540599Y1065047D01*
G03X539125I-737J-1277D01*
G02X536957Y1065013I-1114J1927D01*
G01X536899Y1065047D01*
G03X535425I-737J-1277D01*
G02X533257Y1065013I-1114J1927D01*
G01X533199Y1065047D01*
G03X531725I-737J-1277D01*
G02X529557Y1065013I-1114J1927D01*
G01X529499Y1065047D01*
G03X528025I-737J-1277D01*
G02X525839Y1065023I-1114J1927D01*
G01X525798Y1065047D01*
G03X524324I-737J-1277D01*
G02X522140Y1065023I-1113J1927D01*
G01X522099Y1065047D01*
G03X520625I-737J-1277D01*
G02X518457Y1065013I-1114J1927D01*
G01X518399Y1065047D01*
G03X516925I-737J-1277D01*
G02X514757Y1065013I-1114J1927D01*
G01X514699Y1065047D01*
G03X513225I-737J-1277D01*
G02X511057Y1065013I-1114J1927D01*
G01X510999Y1065047D01*
G03X509525I-737J-1277D01*
G02X507357Y1065013I-1114J1927D01*
G01X507299Y1065047D01*
X507275Y1065061D01*
G02X506186Y1066974I1136J1913D01*
G03X505483Y1068231I-1475J0D01*
G01X505448Y1068251D01*
G03X503974I-737J-1277D01*
G01X503939Y1068231D01*
G03X503254Y1067200I773J-1256D01*
G01X503480Y1066974D01*
X504711D01*
G01X553526Y1078139D02*
X553434D01*
X553198Y1077903D01*
X551863D01*
X546271Y1072311D01*
G02X544727Y1072074I-933J934D01*
G01X544681Y1072100D01*
X544677Y1072102D01*
G02X544674Y1072106I1083J815D01*
G01X544616Y1072140D01*
G03X542448Y1072106I-1053J-1962D01*
G02X540974I-737J1277D01*
G01X540916Y1072140D01*
G03X538748Y1072106I-1053J-1962D01*
G02X537274I-737J1277D01*
G01X537216Y1072140D01*
G03X535048Y1072106I-1053J-1962D01*
G02X533574I-737J1277D01*
G01X533516Y1072140D01*
G03X531348Y1072106I-1053J-1962D01*
G02X529874I-737J1277D01*
G01X529816Y1072140D01*
G03X527648Y1072106I-1053J-1962D01*
G02X526174I-737J1277D01*
G01X526116Y1072140D01*
G03X523948Y1072106I-1053J-1962D01*
G02X522474I-737J1277D01*
G03X520290Y1072130I-1113J-1928D01*
G01X520249Y1072106D01*
G02X518775I-737J1277D01*
G01X518734Y1072130D01*
G03X516548Y1072106I-1072J-1952D01*
G02X515074I-737J1277D01*
G01X515016Y1072140D01*
G03X512849Y1072107I-1054J-1962D01*
G01X512848Y1072106D01*
G02X511374I-737J1277D01*
G01X510725Y1072480D01*
X510365Y1072467D01*
X510364Y1072469D01*
X509044Y1072481D01*
X509042D01*
X508648Y1072560D01*
Y1072559D01*
X508411Y1072796D01*
Y1073383D01*
G01X553526Y1081438D02*
X553434D01*
X553198Y1081202D01*
X552374D01*
X546780Y1075608D01*
X545408D01*
G03X544296Y1075310I1J-2226D01*
G02X542856Y1075291I-737J1277D01*
G01X542782Y1075334D01*
G03X540598Y1075310I-1071J-1951D01*
G02X539124I-737J1277D01*
G03X536898I-1113J-1927D01*
G02X535424I-737J1277D01*
G03X533240Y1075334I-1113J-1927D01*
G01X533199Y1075310D01*
G02X531725I-737J1277D01*
G03X529557Y1075344I-1114J-1927D01*
G01X529499Y1075310D01*
G02X528025I-737J1277D01*
G03X525857Y1075344I-1114J-1927D01*
G01X525799Y1075310D01*
G02X524325I-737J1277D01*
G03X522157Y1075344I-1114J-1927D01*
G01X522099Y1075310D01*
G02X520625I-737J1277D01*
G03X518399I-1113J-1927D01*
G02X516925I-737J1277D01*
G03X514757Y1075344I-1114J-1927D01*
G01X514699Y1075310D01*
G02X513225I-737J1277D01*
G03X511057Y1075344I-1114J-1927D01*
G01X510999Y1075310D01*
G02X509525I-737J1277D01*
G03X507357Y1075344I-1114J-1927D01*
G01X507299Y1075310D01*
G02X505825I-737J1277D01*
G03X503657Y1075344I-1114J-1927D01*
G01X503599Y1075310D01*
X503596Y1075308D01*
X503575Y1075296D01*
G03X503548Y1075279I1172J-1891D01*
G03X502825Y1074564I1160J-1896D01*
G01X502687Y1074332D01*
G03X502572Y1074031I817J-485D01*
G01X502327Y1073574D01*
X502136Y1073383D01*
X501011D01*
G01X553526Y1076919D02*
X553434D01*
X553199Y1077154D01*
X552174D01*
X546801Y1071781D01*
G02X544366Y1071417I-1463J1463D01*
G01X544310Y1071449D01*
X544299Y1071455D01*
G03X542825I-737J-1277D01*
G02X540657Y1071421I-1115J1928D01*
G01X540599Y1071455D01*
G03X539125I-737J-1277D01*
G02X536957Y1071421I-1115J1928D01*
G01X536899Y1071455D01*
G03X535425I-737J-1277D01*
G02X533257Y1071421I-1115J1928D01*
G01X533199Y1071455D01*
G03X531725I-737J-1277D01*
G02X529557Y1071421I-1115J1928D01*
G01X529499Y1071455D01*
G03X528025I-737J-1277D01*
G02X525857Y1071421I-1115J1928D01*
G01X525799Y1071455D01*
G03X524325I-737J-1277D01*
G02X522139Y1071431I-1114J1928D01*
G01X522098Y1071455D01*
G03X520624I-737J-1277D01*
G01X520583Y1071431D01*
G02X518399Y1071455I-1071J1952D01*
G03X516925I-737J-1277D01*
G02X514757Y1071421I-1115J1928D01*
G01X514699Y1071455D01*
G03X513225I-737J-1277D01*
G02X513222Y1071457I545J821D01*
G02X511000I-1111J1926D01*
G01X510537Y1071723D01*
X510388Y1071718D01*
X510357D01*
X509037Y1071731D01*
X509035D01*
X508961Y1071732D01*
X508958Y1071733D01*
X508501Y1071823D01*
X508423Y1071839D01*
X508227Y1071920D01*
G02X507674Y1072106I184J1463D01*
G01X507668Y1072109D01*
X507639Y1072126D01*
G02X506954Y1073158I773J1256D01*
G01X506729Y1073383D01*
X504711D01*
G01X549807Y1085968D02*
X549437Y1085598D01*
Y1084341D01*
X549667Y1083785D01*
Y1082066D01*
X548370Y1080769D01*
X543562D01*
G02X542448Y1081068I1J2228D01*
G03X540974I-737J-1277D01*
G01X540916Y1081034D01*
G02X538748Y1081068I-1053J1962D01*
G03X537274I-737J-1277D01*
G01X537216Y1081034D01*
G02X535048Y1081068I-1053J1962D01*
G03X533574I-737J-1277D01*
G01X533516Y1081034D01*
G02X531348Y1081068I-1053J1962D01*
G03X529874I-737J-1277D01*
G01X529816Y1081034D01*
G02X527648Y1081068I-1054J1961D01*
G03X526174I-737J-1277D01*
G02X523990Y1081044I-1113J1927D01*
G01X523949Y1081068D01*
G03X522475I-737J-1277D01*
G01X522434Y1081044D01*
G02X520248Y1081068I-1072J1951D01*
G03X518774I-737J-1277D01*
G01X518716Y1081034D01*
G02X516548Y1081068I-1054J1961D01*
G03X515074I-737J-1277D01*
G01X515016Y1081034D01*
G02X512848Y1081068I-1054J1961D01*
G03X511374I-737J-1277D01*
G01X511316Y1081034D01*
G02X509148Y1081068I-1054J1961D01*
G03X507674I-737J-1277D01*
G01X507616Y1081034D01*
G02X505448Y1081068I-1054J1961D01*
G03X503974I-737J-1277D01*
G01X503939Y1081048D01*
G03X503254Y1080017I773J-1256D01*
G01X503480Y1079791D01*
X504711D01*
G01X552627Y1089823D02*
X550698D01*
X550347Y1089472D01*
Y1088211D01*
X548577Y1086441D01*
Y1084199D01*
X548869Y1083494D01*
Y1082503D01*
X547884Y1081518D01*
X543563D01*
G02X542825Y1081719I6J1477D01*
G03X540657Y1081753I-1115J-1928D01*
G01X540599Y1081719D01*
G02X539125I-737J1277D01*
G03X536957Y1081753I-1115J-1928D01*
G01X536899Y1081719D01*
G02X535425I-737J1277D01*
G03X533257Y1081753I-1115J-1928D01*
G01X533199Y1081719D01*
G02X531725I-737J1277D01*
G03X529578Y1081764I-1114J-1928D01*
G01X529499Y1081718D01*
G02X528025I-737J1277D01*
G03X525839Y1081742I-1114J-1927D01*
G01X525798Y1081718D01*
G02X524324I-737J1277D01*
G01X524283Y1081742D01*
G03X522099Y1081718I-1071J-1951D01*
G02X520625I-737J1277D01*
G03X518457Y1081752I-1114J-1927D01*
G01X518399Y1081718D01*
G02X516925I-737J1277D01*
G03X514757Y1081752I-1114J-1927D01*
G01X514699Y1081718D01*
G02X513225I-737J1277D01*
G03X511057Y1081752I-1114J-1927D01*
G01X510999Y1081718D01*
G02X509525I-737J1277D01*
G03X507357Y1081752I-1114J-1927D01*
G01X507299Y1081718D01*
G02X505825I-737J1277D01*
G03X503657Y1081752I-1114J-1927D01*
G01X503599Y1081718D01*
X503575Y1081704D01*
G03X502501Y1080050I1136J-1913D01*
G01X502242Y1079791D01*
X501011D01*
G01X552627Y1108790D02*
X551433D01*
X550960Y1108317D01*
X549546Y1104904D01*
X548521Y1103879D01*
X547936D01*
G03X546526Y1103498I0J-2798D01*
G02X544340Y1103474I-1114J1928D01*
G01X544299Y1103498D01*
G03X542825I-737J-1277D01*
G01X542789Y1103478D01*
G03X542086Y1102221I772J-1257D01*
G01Y1102182D01*
G02X540974Y1100294I-2225J39D01*
G01X540939Y1100274D01*
G03X540236Y1099017I772J-1257D01*
G01Y1098978D01*
G02X539124Y1097090I-2225J39D01*
G02X536898I-1113J1927D01*
G03X535424I-737J-1277D01*
G02X533198I-1113J1927D01*
G03X531724I-737J-1277D01*
G02X529498I-1113J1927D01*
G03X528024I-737J-1277D01*
G02X525840Y1097066I-1113J1927D01*
G01X525799Y1097090D01*
G03X524325I-737J-1277D01*
G02X522099I-1113J1927D01*
G03X520625I-737J-1277D01*
G02X518399I-1113J1927D01*
G03X516925I-737J-1277D01*
G02X514739Y1097066I-1114J1927D01*
G01X514698Y1097090D01*
G03X513224I-737J-1277D01*
G01X512864Y1096879D01*
X511722Y1096209D01*
G02X510262Y1095813I-1459J2490D01*
G01X552516Y1110760D02*
X551486D01*
X550867Y1110141D01*
Y1110119D01*
X548929Y1105436D01*
X548141Y1104648D01*
X548009D01*
G03X546149Y1104149I0J-3717D01*
G02X544675I-737J1277D01*
G01X544634Y1104173D01*
G03X542448Y1104149I-1072J-1952D01*
G03X541336Y1102294I1113J-1928D01*
G01Y1102221D01*
G02X540633Y1100964I-1475J0D01*
G01X540598Y1100944D01*
G03X539486Y1099056I1113J-1927D01*
G01Y1099017D01*
G02X538783Y1097760I-1475J0D01*
G01X538748Y1097740D01*
G02X537274I-737J1277D01*
G03X535048I-1113J-1927D01*
G02X533574I-737J1277D01*
G03X531348I-1113J-1927D01*
G02X529874I-737J1277D01*
G03X527648I-1113J-1927D01*
G02X526174I-737J1277D01*
G01X526133Y1097764D01*
G03X523949Y1097740I-1071J-1951D01*
G02X522475I-737J1277D01*
G03X520249I-1113J-1927D01*
G02X518775I-737J1277D01*
G01X518734Y1097764D01*
G03X516548Y1097740I-1072J-1951D01*
G02X515074I-737J1277D01*
G03X512890Y1097764I-1113J-1927D01*
G01X512559Y1097571D01*
X512200Y1097432D01*
X511801Y1097519D01*
G02X511681Y1097563I63J358D01*
G01X511375Y1097740D01*
G03X509207Y1097774I-1114J-1927D01*
G01X508785Y1097528D01*
G03X506561Y1095813I5460J-9380D01*
G01X552627Y1095541D02*
X551908D01*
X548736Y1092369D01*
Y1089404D01*
G02X548033Y1088147I-1475J0D01*
G01X547998Y1088127D01*
G03X546886Y1086239I1113J-1927D01*
G01Y1086200D01*
G02X546183Y1084943I-1475J0D01*
G01X546148Y1084923D01*
G02X544674I-737J1277D01*
G01X544616Y1084957D01*
G03X542448Y1084923I-1054J-1961D01*
G02X540974I-737J1277D01*
G01X540916Y1084957D01*
G03X538748Y1084923I-1054J-1961D01*
G02X537274I-737J1277D01*
G01X537216Y1084957D01*
G03X535048Y1084923I-1054J-1961D01*
G02X533574I-737J1277D01*
G01X533516Y1084957D01*
G03X531348Y1084923I-1054J-1961D01*
G02X529874I-737J1277D01*
G01X529816Y1084957D01*
G03X527648Y1084923I-1053J-1962D01*
G02X526174I-737J1277D01*
G03X523948I-1113J-1928D01*
G02X522474I-737J1277D01*
G01X522416Y1084957D01*
G03X520248Y1084923I-1053J-1962D01*
G02X518774I-737J1277D01*
G01X518716Y1084957D01*
G03X516548Y1084923I-1053J-1962D01*
G02X515074I-737J1277D01*
G01X515016Y1084957D01*
G03X512848Y1084923I-1053J-1962D01*
G02X511374I-737J1277D01*
G01X511333Y1084947D01*
G03X509149Y1084923I-1071J-1952D01*
G02X507675I-737J1277D01*
G01X507640Y1084943D01*
G02X506937Y1086200I772J1257D01*
G03X505849Y1088113I-2226J0D01*
G01X505825Y1088127D01*
G03X503657Y1088161I-1114J-1927D01*
G01X503599Y1088127D01*
X503575Y1088113D01*
G03X502501Y1086459I1136J-1913D01*
G01X502242Y1086200D01*
X501011D01*
G01X553217Y1097526D02*
X552506D01*
X549600Y1094620D01*
X549216D01*
X548835Y1094239D01*
G02X548339Y1093865I-1575J1573D01*
G03X547636Y1092608I772J-1257D01*
G01Y1092569D01*
G02X546524Y1090681I-2225J39D01*
G01X546489Y1090661D01*
G03X545786Y1089404I772J-1257D01*
G01Y1089365D01*
G02X544674Y1087477I-2225J39D01*
G02X542448I-1113J1927D01*
G03X540974I-737J-1277D01*
G02X538748I-1113J1927D01*
G03X537274I-737J-1277D01*
G02X535048I-1113J1927D01*
G03X533574I-737J-1277D01*
G01X533516Y1087443D01*
G02X531348Y1087477I-1054J1961D01*
G03X529874I-737J-1277D01*
G01X529816Y1087443D01*
G02X527648Y1087477I-1054J1961D01*
G03X526174I-737J-1277D01*
G01X526116Y1087443D01*
G02X523948Y1087477I-1054J1961D01*
G03X522474I-737J-1277D01*
G02X520248I-1113J1927D01*
G03X518774I-737J-1277D01*
G01X518716Y1087443D01*
G02X516548Y1087477I-1054J1961D01*
G03X515074I-737J-1277D01*
G01X515016Y1087443D01*
G02X512848Y1087477I-1054J1961D01*
G03X511374I-737J-1277D01*
G01X511333Y1087453D01*
G02X509149Y1087477I-1071J1951D01*
G02X508848Y1087685I1110J1929D01*
G01X506562Y1089404D01*
G01X552627Y1093545D02*
X551943D01*
X549486Y1091088D01*
Y1089365D01*
G02X548374Y1087477I-2225J39D01*
G01X548339Y1087457D01*
G03X547636Y1086200I772J-1257D01*
G01Y1086139D01*
G02X546525Y1084273I-2225J61D01*
G02X544357Y1084239I-1114J1927D01*
G01X544299Y1084273D01*
G03X542825I-737J-1277D01*
G02X540657Y1084239I-1114J1927D01*
G01X540599Y1084273D01*
G03X539125I-737J-1277D01*
G02X536957Y1084239I-1114J1927D01*
G01X536899Y1084273D01*
G03X535425I-737J-1277D01*
G02X533257Y1084239I-1114J1927D01*
G01X533199Y1084273D01*
G03X531725I-737J-1277D01*
G02X529521Y1084259I-1114J1927D01*
G01X529499Y1084272D01*
G03X528025I-737J-1277D01*
G02X525839Y1084248I-1114J1928D01*
G01X525798Y1084272D01*
G03X524324I-737J-1277D01*
G02X522140Y1084248I-1113J1928D01*
G01X522099Y1084272D01*
G03X520625I-737J-1277D01*
G02X518457Y1084238I-1115J1928D01*
G01X518399Y1084272D01*
G03X516925I-737J-1277D01*
G02X514757Y1084238I-1115J1928D01*
G01X514699Y1084272D01*
G03X513225I-737J-1277D01*
G02X511057Y1084238I-1115J1928D01*
G01X510999Y1084272D01*
G03X509525I-737J-1277D01*
G02X507299I-1113J1928D01*
G02X506186Y1086170I1113J1928D01*
G01Y1086200D01*
G03X505483Y1087457I-1475J0D01*
G01X505448Y1087477D01*
G03X503974I-737J-1277D01*
G01X503939Y1087457D01*
G03X503254Y1086426I773J-1256D01*
G01X503480Y1086200D01*
X504711D01*
G01X552627Y1102700D02*
X552535D01*
X552299Y1102464D01*
X551597D01*
X550942Y1101809D01*
X550566Y1100906D01*
X547699Y1098039D01*
X547260D01*
G03X545036Y1095886I1J-2226D01*
G01Y1095813D01*
G02X544333Y1094556I-1475J0D01*
G01X544298Y1094536D01*
G03X543186Y1092681I1113J-1928D01*
G01Y1092608D01*
G02X542483Y1091351I-1475J0D01*
G01X542448Y1091331D01*
G02X540974I-737J1277D01*
G03X538748I-1113J-1927D01*
G02X537274I-737J1277D01*
G01X537233Y1091355D01*
G03X535047Y1091331I-1072J-1951D01*
G02X533607Y1091312I-737J1277D01*
G01X533574Y1091331D01*
X533516Y1091365D01*
G03X531348Y1091331I-1054J-1961D01*
G02X529874I-737J1277D01*
G01X529816Y1091365D01*
G03X527648Y1091331I-1054J-1961D01*
G02X526174I-737J1277D01*
G01X526116Y1091365D01*
G03X523948Y1091331I-1054J-1961D01*
G02X522474I-737J1277D01*
G03X520248I-1113J-1927D01*
G02X518774I-737J1277D01*
G01X518733Y1091355D01*
G03X516549Y1091331I-1071J-1951D01*
G02X515075I-737J1277D01*
G03X512850Y1091332I-1113J-1927D01*
G01X512851Y1091330D01*
X512850D01*
G02X512837Y1091323I-706J1295D01*
G01X512770Y1091287D01*
X512540Y1091183D01*
G02X511712Y1091174I-424J937D01*
G01X511532Y1091251D01*
G02X511377Y1091328I578J1358D01*
G01X511376Y1091330D01*
X511208Y1091420D01*
X511205Y1091422D01*
X511168Y1091442D01*
X511167D01*
X510563Y1091692D01*
X509105D01*
X508648Y1091784D01*
X508411Y1092021D01*
Y1092608D01*
G01X552627Y1106767D02*
X552535D01*
X552299Y1106531D01*
X551742D01*
X551102Y1105891D01*
X549884Y1103617D01*
X549553Y1102818D01*
X548757Y1101629D01*
X548298Y1101171D01*
G02X548148Y1101042I-1033J1050D01*
G01X548146D01*
G02X546524Y1100944I-885J1179D01*
G03X543186Y1099056I-1113J-1927D01*
G01Y1099017D01*
G02X542483Y1097760I-1475J0D01*
G01X542448Y1097740D01*
G03X541336Y1095852I1113J-1927D01*
G01Y1095813D01*
G02X539124Y1094536I-1475J0D01*
G03X536898I-1113J-1928D01*
G02X535424I-737J1277D01*
G03X533256Y1094570I-1115J-1928D01*
G01X533198Y1094536D01*
G02X531724I-737J1277D01*
G03X529498I-1113J-1928D01*
G02X528024I-737J1277D01*
G03X525840Y1094560I-1113J-1928D01*
G01X525799Y1094536D01*
G02X524325I-737J1277D01*
G03X522157Y1094570I-1115J-1928D01*
G01X522099Y1094536D01*
G02X520625I-737J1277D01*
G03X518457Y1094570I-1115J-1928D01*
G01X518399Y1094536D01*
G02X516925I-737J1277D01*
G01X516884Y1094560D01*
G03X514698Y1094536I-1072J-1952D01*
G02X513224I-737J1277D01*
G01X513183Y1094560D01*
G03X510999Y1094536I-1071J-1952D01*
G02X509525I-737J1277D01*
G03X507357Y1094570I-1115J-1928D01*
G01X507299Y1094536D01*
G02X505825I-737J1277D01*
G03X503657Y1094570I-1115J-1928D01*
G01X503599Y1094536D01*
G03X501011Y1092608I7429J-12673D01*
G01X552627Y1101480D02*
X552535D01*
X552300Y1101715D01*
X551908D01*
X551577Y1101384D01*
X551201Y1100481D01*
X548010Y1097290D01*
X547260D01*
G03X546522Y1097092I1J-1477D01*
G03X546489Y1097070I802J-1238D01*
G03X545786Y1095813I772J-1257D01*
G01Y1095740D01*
G02X544674Y1093885I-2225J73D01*
G01X544639Y1093865D01*
G03X543936Y1092608I772J-1257D01*
G01Y1092569D01*
G02X542824Y1090681I-2225J39D01*
G02X540598I-1113J1927D01*
G03X539124I-737J-1277D01*
G02X536898I-1113J1927D01*
G03X535424I-737J-1277D01*
G02X533256Y1090647I-1114J1927D01*
G01X533198Y1090681D01*
X533165Y1090700D01*
G03X531725Y1090681I-703J-1296D01*
G02X529557Y1090647I-1114J1927D01*
G01X529499Y1090681D01*
G03X528025I-737J-1277D01*
G02X525857Y1090647I-1114J1927D01*
G01X525799Y1090681D01*
G03X524325I-737J-1277D01*
G02X522139Y1090657I-1114J1927D01*
G01X522098Y1090681D01*
G03X520624I-737J-1277D01*
G02X518440Y1090657I-1113J1927D01*
G01X518399Y1090681D01*
G03X516925I-737J-1277D01*
G02X514699I-1113J1927D01*
G03X513225I-737J-1277D01*
G02X513030Y1090581I-1112J1928D01*
G01X513028D01*
X512849Y1090500D01*
G02X511418Y1090485I-733J1620D01*
G01X511237Y1090562D01*
G02X511003Y1090679I876J2045D01*
G01X510980Y1090692D01*
X510852Y1090760D01*
X510849Y1090762D01*
X510414Y1090943D01*
X509030D01*
X508501Y1091049D01*
Y1091048D01*
X508423Y1091064D01*
X508227Y1091145D01*
G02X507674Y1091331I184J1463D01*
G01X507668Y1091334D01*
X507639Y1091351D01*
G02X506954Y1092383I773J1256D01*
G01X506729Y1092608D01*
X504711D01*
G01X548895Y1114380D02*
X548028Y1113513D01*
Y1109861D01*
G02X545608Y1107644I-2226J0D01*
G03X544298Y1107353I-195J-2218D01*
G02X542824I-737J1277D01*
G03X540598I-1113J-1927D01*
G03X539486Y1105465I1113J-1927D01*
G01Y1105426D01*
G02X538783Y1104169I-1475J0D01*
G01X538748Y1104149D01*
G03X537636Y1102294I1113J-1928D01*
G01Y1102221D01*
G02X536933Y1100964I-1475J0D01*
G01X536898Y1100944D01*
G02X535424I-737J1277D01*
G01X535383Y1100968D01*
G03X533197Y1100944I-1072J-1951D01*
G02X531723I-737J1277D01*
G03X529499I-1112J-1927D01*
G02X528025I-737J1277D01*
G03X525857Y1100978I-1114J-1927D01*
G01X525799Y1100944D01*
G02X524325I-737J1277D01*
G01X524284Y1100968D01*
G03X522098Y1100944I-1072J-1951D01*
G02X520624I-737J1277D01*
G01X520583Y1100968D01*
G03X518399Y1100944I-1071J-1951D01*
G02X517129Y1100847I-736J1277D01*
G01X517046Y1101154D01*
X517662Y1102221D01*
G01X550869Y1112407D02*
X549847Y1111385D01*
Y1109812D01*
X548689Y1107016D01*
X548376Y1106703D01*
G02X546190Y1106679I-1114J1927D01*
G01X546149Y1106703D01*
G03X544675I-737J-1277D01*
G02X542489Y1106679I-1114J1927D01*
G01X542448Y1106703D01*
G03X540974I-737J-1277D01*
G01X540939Y1106683D01*
G03X540236Y1105426I772J-1257D01*
G01Y1105353D01*
G02X539124Y1103498I-2225J73D01*
G01X539089Y1103478D01*
G03X538386Y1102221I772J-1257D01*
G01Y1102182D01*
G02X537274Y1100294I-2225J39D01*
G02X535048I-1113J1927D01*
G03X533574I-737J-1277D01*
G02X531406Y1100260I-1114J1927D01*
G01X531348Y1100294D01*
G03X529874I-737J-1277D01*
G01X529816Y1100260D01*
G02X527648Y1100294I-1054J1961D01*
G03X526174I-737J-1277D01*
G01X526133Y1100270D01*
G02X523949Y1100294I-1071J1951D01*
G03X522475I-737J-1277D01*
G02X520307Y1100260I-1114J1927D01*
G01X520249Y1100294D01*
G03X518775I-737J-1277D01*
G01X518734Y1100270D01*
G02X516778Y1100178I-1072J1951D01*
G01X516427Y1100084D01*
X515811Y1099017D01*
G01X560703Y858190D02*
X559575Y859318D01*
Y861461D01*
X558312Y862724D01*
X557925Y862722D01*
G02X557191Y862920I4J1475D01*
G01X557133Y862954D01*
G03X554965Y862920I-1054J-1961D01*
G02X553491I-737J1277D01*
G01X553433Y862954D01*
G03X551265Y862920I-1054J-1961D01*
G02X549791I-737J1277D01*
G02X549053Y864198I738J1278D01*
G01Y864199D01*
G03X545719Y866124I-2223J0D01*
G01X545716Y866123D01*
G03X544603Y864197I1111J-1927D01*
G02X543866Y862921I-1473J0D01*
G01X543865Y862920D01*
G02X542391I-737J1277D01*
G01X542333Y862954D01*
G03X540165Y862920I-1054J-1961D01*
G02X538691I-737J1277D01*
G01X538650Y862944D01*
G03X536466Y862920I-1071J-1951D01*
G02X534992I-737J1276D01*
G01X534882Y862984D01*
X532029Y864197D01*
G01X542062Y998315D02*
X540917D01*
X540687Y998085D01*
X534977D01*
X534547Y997655D01*
X524927D01*
X523212Y999370D01*
Y1000414D01*
X522152Y1001474D01*
X520927D01*
X519513Y1002888D01*
G01X550925Y1006600D02*
X549556D01*
X548077Y1008079D01*
X547342D01*
X546985Y1007722D01*
G02X544357Y1007335I-1574J1575D01*
G01X544252Y1007396D01*
G03X542825Y1007369I-689J-1304D01*
G02X540657Y1007335I-1115J1928D01*
G01X540599Y1007369D01*
G03X539125I-737J-1277D01*
G02X536966Y1007330I-1115J1928D01*
G01X536898Y1007370D01*
G03X535424I-737J-1277D01*
G02X533198I-1113J1927D01*
G03X531724I-737J-1277D01*
G03X530987Y1006127I737J-1277D01*
G01Y1006037D01*
G02X529874Y1004165I-2225J56D01*
G01X529839Y1004145D01*
G03X529154Y1003113I773J-1256D01*
G01X529379Y1002888D01*
X530611D01*
G01X550925Y1002274D02*
X549908D01*
X548316Y1003866D01*
X547262D01*
G02X546148Y1004165I0J2225D01*
G03X544674I-737J-1277D01*
G01X544616Y1004131D01*
G02X542448Y1004165I-1054J1961D01*
G03X540974I-737J-1277D01*
G01X540916Y1004131D01*
G02X538748Y1004165I-1054J1961D01*
G03X537274I-737J-1277D01*
G02X535048I-1113J1928D01*
G03X533574I-737J-1277D01*
G01X533539Y1004145D01*
G03X532836Y1002888I772J-1257D01*
G01Y1001304D01*
X532461Y1000929D01*
Y999684D01*
G01X550925Y1008828D02*
X547031D01*
X546455Y1008252D01*
G02X546149Y1008020I-1038J1051D01*
G02X544722Y1007993I-738J1277D01*
G01X544675Y1008020D01*
X544617Y1008054D01*
G03X542449Y1008020I-1053J-1962D01*
G02X541007Y1008001I-738J1277D01*
G01X540974Y1008020D01*
X540916Y1008054D01*
G03X538748Y1008020I-1053J-1962D01*
G02X537274I-737J1277D01*
G03X535048I-1113J-1927D01*
G02X533574I-737J1277D01*
G03X531348I-1113J-1927D01*
G03X530236Y1006132I1113J-1927D01*
G01Y1006059D01*
G02X529499Y1004816I-1474J34D01*
G03X528400Y1003145I1112J-1928D01*
G01X528143Y1002888D01*
X526911D01*
G01X550925Y1004615D02*
X547262D01*
G02X546525Y1004815I5J1476D01*
G03X544357Y1004849I-1114J-1927D01*
G01X544299Y1004815D01*
G02X542825I-737J1277D01*
G03X540657Y1004849I-1114J-1927D01*
G01X540599Y1004815D01*
G02X539125I-737J1277D01*
G01X539090Y1004836D01*
G03X536898Y1004816I-1078J-1948D01*
G02X535424I-737J1277D01*
G03X533198I-1113J-1928D01*
G03X532086Y1002961I1113J-1928D01*
G01Y1002888D01*
G02X531383Y1001631I-1475J0D01*
G01X530796Y1001296D01*
X527853D01*
X525062Y999684D01*
G01X553195Y844821D02*
X552587Y845429D01*
Y848232D01*
X550917Y849902D01*
X550531D01*
G02X549794Y850102I4J1474D01*
G03X547608Y850126I-1114J-1926D01*
G01X547567Y850102D01*
X547534Y850083D01*
G02X546094Y850102I-703J1294D01*
G03X543883I-1105J-1912D01*
G01X543866Y850092D01*
G02X542395I-735J1273D01*
G01X542390Y850094D01*
G02X541655Y851367I735J1273D01*
G01Y851377D01*
G03X541584Y851547I-241J-1D01*
G01X541297Y851835D01*
G03X540406Y852518I-3037J-3039D01*
G01X540166Y852657D01*
G03X538692I-737J-1277D01*
G02X536466I-1113J1927D01*
G02X535354Y854545I1113J1927D01*
G01Y854584D01*
G03X534803Y855733I-1475J-1D01*
G01X534495Y855651D01*
X533879Y854584D01*
G01X554634Y846260D02*
X553957Y846937D01*
Y850778D01*
X552378Y852357D01*
G02X551267Y852654I0J2227D01*
G01X551220Y852682D01*
G03X549793Y852655I-689J-1305D01*
G02X547625Y852621I-1115J1929D01*
G01X547567Y852655D01*
X547520Y852682D01*
G03X546093Y852655I-689J-1305D01*
G01X545983Y852590D01*
X543144Y851395D01*
X543129Y851380D01*
G01X551746Y843372D02*
X551297Y843821D01*
Y848386D01*
X550531Y849152D01*
G02X549417Y849451I0J2225D01*
G03X547977Y849470I-737J-1275D01*
G01X547944Y849451D01*
X547903Y849427D01*
G02X545717Y849451I-1072J1950D01*
G03X544260I-729J-1261D01*
G01X544243Y849441D01*
G02X542017I-1113J1926D01*
G01X542016D01*
X541899Y849508D01*
X539432Y851375D01*
X539429Y851378D01*
Y851380D01*
G01X560623Y863871D02*
Y863877D01*
X557635Y866865D01*
X556063D01*
X553953Y868975D01*
G03X551266Y869329I-1574J-1574D01*
G02X549792I-737J1277D01*
G03X547566I-1113J-1928D01*
G02X546092I-737J1277D01*
G03X543866I-1113J-1928D01*
G02X542392I-737J1277D01*
G03X540166I-1113J-1928D01*
G03X539054Y867403I1112J-1926D01*
G01Y867401D01*
G02X538351Y866144I-1475J0D01*
G01X538316Y866124D01*
X538203Y866060D01*
X535729Y864197D01*
G01X561109Y860596D02*
X560437Y861268D01*
Y861966D01*
X557446Y864957D01*
X556911D01*
X553423Y868445D01*
G03X553116Y868678I-1038J-1049D01*
G03X551642I-737J-1277D01*
G02X549416I-1113J1928D01*
G03X547942I-737J-1277D01*
G02X545716I-1113J1928D01*
G03X544242I-737J-1277D01*
G01X544207Y868658D01*
G03X543504Y867401I772J-1257D01*
G01Y867269D01*
X543128Y864197D01*
G01X560751Y855278D02*
X558799Y857230D01*
Y861100D01*
X557927Y861972D01*
G02X557784Y861976I-9J2225D01*
G02X556816Y862270I146J2220D01*
G03X555342I-737J-1277D01*
G02X553174Y862236I-1114J1927D01*
G01X553116Y862270D01*
G03X551642I-737J-1277D01*
G02X549474Y862236I-1114J1927D01*
G01X549297Y862338D01*
X546828Y864197D01*
G01X556135Y847762D02*
X555267Y848630D01*
Y850641D01*
X552801Y853107D01*
X552379D01*
G02X551585Y853340I2J1476D01*
G03X549417Y853306I-1053J-1963D01*
G02X547990Y853279I-738J1278D01*
G01X547943Y853306D01*
X547885Y853340D01*
G03X545717Y853306I-1053J-1963D01*
G02X544275Y853287I-738J1278D01*
G01X544242Y853306D01*
G03X542016I-1113J-1929D01*
G02X541531Y853105I-485J485D01*
G01X541296D01*
G02X540542Y853307I0J1507D01*
G03X538316I-1113J-1927D01*
G02X536842I-737J1277D01*
G01X536807Y853327D01*
G02X536104Y854584I772J1257D01*
G01Y854657D01*
G03X535208Y856371I-2225J-72D01*
G01X535113Y856722D01*
X535729Y857789D01*
G01X559892Y851518D02*
X559827Y851583D01*
Y851915D01*
X559178Y852564D01*
Y854264D01*
X557065Y856377D01*
Y858418D01*
X556716Y858767D01*
X556075D01*
G02X554943Y859078I0J2217D01*
G03X553491Y859066I-715J-1289D01*
G01X553433Y859032D01*
G02X551265Y859066I-1054J1961D01*
G03X549791I-737J-1277D01*
G01X549733Y859032D01*
G02X547565Y859066I-1054J1961D01*
G03X546091I-737J-1277D01*
G02X543867I-1112J1927D01*
G03X542597Y859163I-736J-1277D01*
G01X542514Y858856D01*
X543130Y857789D01*
G01X558487Y850112D02*
X558422Y850177D01*
X558088D01*
X557468Y850797D01*
Y854119D01*
X555275Y856312D01*
X554228D01*
G02X553491Y856512I5J1476D01*
G01X553433Y856546D01*
G03X551265Y856512I-1053J-1962D01*
G02X549791I-737J1277D01*
G01X549733Y856546D01*
G03X547565Y856512I-1053J-1962D01*
G02X546091I-737J1277D01*
G03X543867I-1112J-1928D01*
G02X542393I-737J1277D01*
G03X540474Y856661I-1115J-1927D01*
G03X540395Y856629I796J-2079D01*
G01X540045Y856722D01*
X539429Y857789D01*
G01X560755Y852381D02*
X560690Y852446D01*
X560356D01*
X559927Y852875D01*
Y854575D01*
X557814Y856688D01*
Y858729D01*
X557027Y859516D01*
X556076D01*
X556075Y859517D01*
G02X555341Y859714I0J1467D01*
G01X555342Y859716D01*
G03X553174Y859750I-1114J-1927D01*
G01X553116Y859716D01*
G02X551642I-737J1277D01*
G03X549474Y859750I-1114J-1927D01*
G01X549416Y859716D01*
G02X547942I-737J1277D01*
G03X545774Y859750I-1114J-1927D01*
G01X545716Y859716D01*
G02X544242I-737J1277D01*
G01X544184Y859750D01*
G03X542325Y859864I-1053J-1961D01*
G03X542246Y859832I796J-2079D01*
G01X541895Y859926D01*
X541279Y860993D01*
G01X557624Y849249D02*
X557559Y849314D01*
Y849646D01*
X556719Y850486D01*
Y853808D01*
X554964Y855563D01*
X554228D01*
G02X553116Y855861I1J2226D01*
G03X551642I-737J-1277D01*
G02X549474Y855827I-1115J1928D01*
G01X549416Y855861D01*
G03X547942I-737J-1277D01*
G02X545774Y855827I-1115J1928D01*
G01X545716Y855861D01*
G03X544242I-737J-1277D01*
G01X544184Y855827D01*
G02X542016Y855861I-1053J1962D01*
G03X540746Y855958I-736J-1277D01*
G01X540663Y855651D01*
X541279Y854584D01*
G01X1353204Y1012501D02*
X1354435D01*
X1354661Y1012275D01*
G02X1353976Y1011244I-1458J225D01*
G01X1353941Y1011224D01*
G02X1352467I-737J1277D01*
G03X1350299Y1011258I-1114J-1927D01*
G01X1350241Y1011224D01*
G02X1348767I-737J1277D01*
G03X1346541I-1113J-1927D01*
G02X1345067I-737J1277D01*
G03X1342881Y1011248I-1114J-1927D01*
G01X1342840Y1011224D01*
G02X1341366I-737J1277D01*
G03X1339182Y1011248I-1113J-1927D01*
G01X1339141Y1011224D01*
G02X1337667I-737J1277D01*
G03X1335481Y1011248I-1114J-1927D01*
G01X1335440Y1011224D01*
G02X1333966I-737J1277D01*
G03X1331740I-1113J-1927D01*
G02X1330266I-737J1277D01*
G03X1328040I-1113J-1927D01*
G02X1326566I-737J1277D01*
G03X1324340I-1113J-1927D01*
G02X1322866I-737J1277D01*
G03X1320640I-1113J-1927D01*
G02X1319166I-737J1277D01*
G03X1316940I-1113J-1927D01*
G02X1315466I-737J1277D01*
G03X1313240I-1113J-1927D01*
G02X1311766I-737J1277D01*
G03X1309540I-1113J-1927D01*
G02X1308066I-737J1277D01*
G03X1306953Y1011522I-1112J-1927D01*
G01X1305155D01*
X1304803Y1011170D01*
X1303082D01*
G01X1350920Y969939D02*
G02X1350607Y966009I-6346J-1472D01*
G02X1350216Y965643I-594J242D01*
G03X1349866Y965492I704J-2113D01*
G01X1349808Y965458D01*
G02X1348334I-737J1277D01*
G03X1346166Y965492I-1115J-1928D01*
G01X1346108Y965458D01*
G02X1344634I-737J1277D01*
G03X1342448Y965482I-1114J-1928D01*
G01X1342407Y965458D01*
G02X1340933I-737J1277D01*
G01X1340892Y965482D01*
G03X1338708Y965458I-1071J-1952D01*
G02X1337234I-737J1277D01*
G03X1335048Y965482I-1114J-1928D01*
G01X1335007Y965458D01*
G02X1333533I-737J1277D01*
G01X1333492Y965482D01*
G03X1331308Y965458I-1071J-1952D01*
G02X1329834I-737J1277D01*
G03X1327666Y965492I-1115J-1928D01*
G01X1327608Y965458D01*
G02X1326134I-737J1277D01*
G03X1323966Y965492I-1115J-1928D01*
G01X1323908Y965458D01*
G02X1322434I-737J1277D01*
G03X1320266Y965492I-1115J-1928D01*
G01X1320208Y965458D01*
G02X1318734I-737J1277D01*
G03X1316566Y965492I-1115J-1928D01*
G01X1316508Y965458D01*
G02X1315034I-737J1277D01*
G03X1312866Y965492I-1115J-1928D01*
G01X1312808Y965458D01*
G02X1311334I-737J1277D01*
G03X1309166Y965492I-1115J-1928D01*
G01X1309108Y965458D01*
G02X1307634I-737J1277D01*
G01X1307528Y965564D01*
X1307228D01*
X1305311Y967481D01*
Y967840D01*
X1304800Y969073D01*
X1304503Y969370D01*
X1303667D01*
G01X1356904Y1012501D02*
X1355673D01*
X1355414Y1012242D01*
G02X1354340Y1010588I-2210J259D01*
G01X1354316Y1010574D01*
X1354258Y1010540D01*
G02X1352090Y1010574I-1054J1961D01*
G03X1350616I-737J-1277D01*
G01X1350575Y1010550D01*
G02X1348391Y1010574I-1071J1951D01*
G03X1346917I-737J-1277D01*
G01X1346876Y1010550D01*
G02X1344690Y1010574I-1072J1951D01*
G03X1343216I-737J-1277D01*
G02X1340990I-1113J1927D01*
G03X1339516I-737J-1277D01*
G01X1339458Y1010540D01*
G02X1337290Y1010574I-1054J1961D01*
G03X1335816I-737J-1277D01*
G02X1333590I-1113J1927D01*
G03X1332116I-737J-1277D01*
G02X1329890I-1113J1927D01*
G03X1328416I-737J-1277D01*
G02X1326190I-1113J1927D01*
G03X1324716I-737J-1277D01*
G02X1322490I-1113J1927D01*
G03X1321016I-737J-1277D01*
G02X1318790I-1113J1927D01*
G03X1317316I-737J-1277D01*
G02X1315090I-1113J1927D01*
G03X1313616I-737J-1277D01*
G02X1311390I-1113J1927D01*
G03X1309916I-737J-1277D01*
G02X1307690I-1113J1927D01*
G03X1306953Y1010773I-740J-1276D01*
G01X1306165D01*
X1304602Y1009210D01*
X1303263D01*
G01X1358320Y969939D02*
G02X1358135Y966907I-20271J-285D01*
G02X1356296Y965081I-2113J289D01*
G02X1355606Y965051I-520J4010D01*
G03X1354841Y965018I-191J-4458D01*
G02X1354636Y965005I-196J1461D01*
G03X1353877Y964804I-16J-1475D01*
G02X1353562Y964652I-1075J1825D01*
G02X1351657Y964807I-789J2082D01*
G03X1350183I-737J-1277D01*
G01X1350125Y964773D01*
G02X1347957Y964807I-1053J1962D01*
G03X1346483I-737J-1277D01*
G01X1346425Y964773D01*
G02X1344257Y964807I-1053J1962D01*
G03X1342783I-737J-1277D01*
G02X1340599Y964783I-1113J1928D01*
G01X1340558Y964807D01*
G03X1339084I-737J-1277D01*
G01X1339043Y964783D01*
G02X1336857Y964807I-1072J1952D01*
G03X1335383I-737J-1277D01*
G02X1333199Y964783I-1113J1928D01*
G01X1333158Y964807D01*
G03X1331684I-737J-1277D01*
G01X1331643Y964783D01*
G02X1329457Y964807I-1072J1952D01*
G03X1327983I-737J-1277D01*
G01X1327925Y964773D01*
G02X1325757Y964807I-1053J1962D01*
G03X1324283I-737J-1277D01*
G01X1324225Y964773D01*
G02X1322057Y964807I-1053J1962D01*
G03X1320583I-737J-1277D01*
G01X1320525Y964773D01*
G02X1318357Y964807I-1053J1962D01*
G03X1316883I-737J-1277D01*
G01X1316825Y964773D01*
G02X1314657Y964807I-1053J1962D01*
G03X1313183I-737J-1277D01*
G01X1313125Y964773D01*
G02X1310957Y964807I-1053J1962D01*
G03X1309483I-737J-1277D01*
G01X1309425Y964773D01*
G02X1307257Y964807I-1053J1962D01*
G01X1306886D01*
X1304542Y967151D01*
Y967652D01*
X1304193Y968001D01*
X1303666D01*
G01X1351353Y1009297D02*
X1349846Y1008740D01*
G03X1348738Y1008220I2523J-6816D01*
G01X1348391Y1008020D01*
G02X1346917I-737J1277D01*
G01X1346876Y1008044D01*
G03X1344690Y1008020I-1072J-1951D01*
G02X1343216I-737J1277D01*
G01X1343158Y1008054D01*
G03X1340990Y1008020I-1054J-1961D01*
G02X1339516I-737J1277D01*
G03X1337290I-1113J-1927D01*
G02X1335816I-737J1277D01*
G01X1335758Y1008054D01*
G03X1333590Y1008020I-1054J-1961D01*
G02X1332116I-737J1277D01*
G03X1329890I-1113J-1927D01*
G02X1328416I-737J1277D01*
G01X1328358Y1008054D01*
G03X1326190Y1008020I-1054J-1961D01*
G02X1324716I-737J1277D01*
G03X1322490I-1113J-1927D01*
G02X1321016I-737J1277D01*
G03X1318790I-1113J-1927D01*
G02X1317316I-737J1277D01*
G03X1315090I-1113J-1927D01*
G02X1313616I-737J1277D01*
G03X1311390I-1113J-1927D01*
G02X1309916I-737J1277D01*
G03X1307690I-1113J-1927D01*
G02X1306953Y1007821I-740J1276D01*
G01X1306014D01*
X1305442Y1007249D01*
X1303263D01*
G01X1350920Y912262D02*
G03X1349520Y911887I1J-2803D01*
G01X1347958Y910985D01*
G02X1346484I-737J1277D01*
G01X1346443Y911009D01*
G03X1344257Y910985I-1072J-1952D01*
G02X1342783I-737J1277D01*
G01X1342725Y911019D01*
G03X1340557Y910985I-1053J-1962D01*
G02X1339083I-737J1277D01*
G01X1339025Y911019D01*
G03X1336857Y910985I-1053J-1962D01*
G02X1335383I-737J1277D01*
G03X1333157I-1113J-1928D01*
G03X1332045Y909130I1113J-1928D01*
G01Y909023D01*
G02X1331308Y907780I-1474J34D01*
G02X1329834I-737J1277D01*
G03X1327666Y907814I-1114J-1927D01*
G01X1327608Y907780D01*
G02X1326134I-737J1277D01*
G03X1323966Y907814I-1114J-1927D01*
G01X1323908Y907780D01*
G02X1322477Y907756I-737J1277D01*
G01X1322434Y907781D01*
G03X1320208I-1113J-1927D01*
G02X1318734I-737J1277D01*
G03X1316566Y907815I-1115J-1928D01*
G01X1316508Y907781D01*
G03X1315396Y905910I1113J-1927D01*
G01X1315395Y905854D01*
Y905820D01*
G02X1314658Y904577I-1474J34D01*
G02X1313184I-737J1277D01*
G03X1310958I-1113J-1927D01*
G02X1309484I-737J1277D01*
G03X1308248Y904908I-1236J-2142D01*
G01X1308239Y904917D01*
X1307394D01*
X1306095Y903618D01*
Y900403D01*
X1302738Y897046D01*
X1300865D01*
G01X1352771Y909057D02*
G02X1350186Y907955I-9572J18871D01*
G03X1349866Y907814I735J-2101D01*
G01X1349808Y907780D01*
G02X1348334I-737J1277D01*
G03X1346166Y907814I-1114J-1927D01*
G01X1346108Y907780D01*
G02X1344634I-737J1277D01*
G03X1342466Y907814I-1114J-1927D01*
G01X1342408Y907780D01*
G02X1340934I-737J1277D01*
G03X1338766Y907814I-1114J-1927D01*
G01X1338708Y907780D01*
G02X1337234I-737J1277D01*
G03X1333895Y905892I-1114J-1927D01*
G01Y905819D01*
G02X1331684Y904576I-1474J34D01*
G01X1331643Y904600D01*
G03X1329457Y904576I-1072J-1951D01*
G02X1327983I-737J1277D01*
G01X1327925Y904610D01*
G03X1325757Y904576I-1054J-1961D01*
G02X1324283I-737J1277D01*
G01X1324215Y904615D01*
G03X1322058Y904577I-1044J-1966D01*
G02X1320584I-737J1277D01*
G03X1318425Y904616I-1115J-1928D01*
G01X1318357Y904576D01*
G03X1317246Y902689I1114J-1926D01*
G01X1317245Y902650D01*
Y902616D01*
G02X1315034Y901373I-1474J34D01*
G03X1312808I-1113J-1927D01*
G01X1312809Y901372D01*
G02X1311335I-737J1277D01*
G01X1311294Y901396D01*
G03X1307996Y899445I-1072J-1951D01*
G01Y899065D01*
X1302057Y893126D01*
X1300865D01*
G01X1350920Y918670D02*
G03X1348333Y920598I-9501J-10049D01*
G03X1346149Y920622I-1113J-1928D01*
G01X1346108Y920598D01*
G02X1344634I-737J1277D01*
G03X1342466Y920632I-1115J-1928D01*
G01X1342408Y920598D01*
G02X1340934I-737J1277D01*
G03X1338766Y920632I-1115J-1928D01*
G01X1338708Y920598D01*
G02X1337234I-737J1277D01*
G03X1335008I-1113J-1928D01*
G02X1333534I-737J1277D01*
G03X1331366Y920632I-1115J-1928D01*
G01X1331308Y920598D01*
G02X1329834I-737J1277D01*
G03X1327666Y920632I-1115J-1928D01*
G01X1327608Y920598D01*
G02X1326134I-737J1277D01*
G03X1322795Y918726I-1113J-1928D01*
G01Y918636D01*
G02X1320584Y917393I-1474J34D01*
G01X1320530Y917425D01*
G03X1318358Y917394I-1058J-1959D01*
G02X1316884I-737J1278D01*
G01X1316843Y917418D01*
G03X1314657Y917394I-1072J-1952D01*
G02X1313183I-737J1277D01*
G03X1309845Y915522I-1113J-1928D01*
G01Y915466D01*
G02X1308370Y913990I-1476J0D01*
G01X1305491D01*
X1304240Y912739D01*
Y908992D01*
X1302574Y907326D01*
X1301465D01*
G01X1349071Y915466D02*
X1348946Y915922D01*
X1348793Y916009D01*
G03X1348184Y916170I-609J-1071D01*
G01X1347104D01*
X1346109Y916743D01*
X1346108D01*
G03X1344634I-737J-1277D01*
G02X1342466Y916709I-1114J1927D01*
G01X1342408Y916743D01*
G03X1340934I-737J-1277D01*
G02X1338748Y916719I-1114J1927D01*
G01X1338707Y916743D01*
G03X1337233I-737J-1277D01*
G01X1337192Y916719D01*
G02X1335008Y916743I-1071J1951D01*
G03X1333534I-737J-1277D01*
G02X1331366Y916709I-1114J1927D01*
G01X1331308Y916743D01*
G03X1329096Y915466I-737J-1277D01*
G02X1328000Y913549I-2225J0D01*
G01X1327925Y913505D01*
G02X1325757Y913539I-1054J1961D01*
G03X1324283I-737J-1277D01*
G01X1324242Y913515D01*
G02X1322058Y913539I-1071J1951D01*
G03X1320584I-737J-1277D01*
G02X1318358I-1113J1927D01*
G03X1316884I-737J-1277D01*
G02X1314658I-1113J1927D01*
G03X1312446Y912262I-737J-1277D01*
G01Y912189D01*
G02X1309108Y910334I-2225J73D01*
G03X1307634I-737J-1277D01*
G03X1307327Y910101I731J-1282D01*
G01X1306544Y909318D01*
Y907477D01*
X1303699Y904632D01*
Y903281D01*
X1302839Y902421D01*
X1301792D01*
X1301557Y902186D01*
X1301465D01*
G01X1352771Y915466D02*
G02X1351431Y915820I-1J2708D01*
G01X1349757Y916772D01*
G03X1348952Y916936I-648J-1121D01*
G01X1348727Y916909D01*
X1348708Y916919D01*
X1347305D01*
X1346425Y917427D01*
G03X1344257Y917393I-1054J-1961D01*
G02X1342783I-737J1277D01*
G01X1342725Y917427D01*
G03X1340557Y917393I-1054J-1961D01*
G02X1339083I-737J1277D01*
G03X1336899Y917417I-1113J-1927D01*
G01X1336858Y917393D01*
G02X1335384I-737J1277D01*
G01X1335343Y917417D01*
G03X1333157Y917393I-1072J-1951D01*
G02X1331683I-737J1277D01*
G01X1331625Y917427D01*
G03X1328346Y915527I-1054J-1961D01*
G01Y915466D01*
G02X1327643Y914209I-1475J0D01*
G01X1327614Y914192D01*
X1327608Y914189D01*
G02X1326134I-737J1277D01*
G03X1323966Y914223I-1114J-1927D01*
G01X1323908Y914189D01*
G02X1322434I-737J1277D01*
G03X1320208I-1113J-1927D01*
G02X1318734I-737J1277D01*
G03X1316508I-1113J-1927D01*
G02X1315034I-737J1277D01*
G01X1314993Y914213D01*
G03X1311696Y912323I-1072J-1951D01*
G01Y912262D01*
G02X1309484Y910985I-1475J0D01*
G03X1306797Y910631I-1113J-1928D01*
G01X1305795Y909629D01*
Y907788D01*
X1302950Y904943D01*
Y903592D01*
X1302528Y903170D01*
X1301793D01*
X1301557Y903406D01*
X1301465D01*
G01X1352771Y921875D02*
G03X1350231Y923774I-9569J-10151D01*
G01X1350183Y923802D01*
G03X1347957I-1113J-1927D01*
G02X1346483I-737J1277D01*
G01X1346425Y923836D01*
G03X1344257Y923802I-1054J-1961D01*
G02X1342783I-737J1277D01*
G01X1342725Y923836D01*
G03X1340557Y923802I-1054J-1961D01*
G02X1339083I-737J1277D01*
G01X1339025Y923836D01*
G03X1336857Y923802I-1054J-1961D01*
G02X1335383I-737J1277D01*
G01X1335342Y923826D01*
G03X1333158Y923802I-1071J-1951D01*
G02X1331684I-737J1277D01*
G01X1331643Y923826D01*
G03X1329457Y923802I-1072J-1951D01*
G02X1327983I-737J1277D01*
G01X1327925Y923836D01*
G03X1325757Y923802I-1054J-1961D01*
G02X1324283I-737J1277D01*
G01X1324215Y923841D01*
G03X1322058Y923803I-1044J-1966D01*
G03X1320947Y921949I1114J-1927D01*
G01X1320946Y921876D01*
Y921848D01*
G02X1320208Y920598I-1475J28D01*
G02X1318777Y920574I-737J1278D01*
G01X1318734Y920599D01*
X1318693Y920623D01*
G03X1316507Y920599I-1072J-1951D01*
G01X1316464Y920574D01*
G02X1315033Y920598I-694J1301D01*
G01X1314998Y920619D01*
G03X1312808Y920599I-1077J-1948D01*
G01X1312775Y920580D01*
G02X1311335Y920599I-703J1296D01*
G01X1311294Y920623D01*
G03X1309108Y920599I-1072J-1951D01*
G01X1309084Y920585D01*
G03X1307996Y918671I1138J-1913D01*
G02X1307293Y917414I-1475J0D01*
G01X1307258Y917394D01*
G02X1306521Y917194I-742J1276D01*
G01X1306210D01*
X1302619Y913603D01*
Y911595D01*
X1302270Y911246D01*
X1301466D01*
G01X1358753Y1009297D02*
X1356265Y1007443D01*
G02X1355963Y1007265I-959J1282D01*
G02X1353999Y1007336I-910J2032D01*
G01X1353941Y1007370D01*
G03X1352467I-737J-1277D01*
G02X1350299Y1007336I-1114J1927D01*
G01X1350241Y1007370D01*
G03X1348767I-737J-1277D01*
G02X1346541I-1113J1927D01*
G03X1345067I-737J-1277D01*
G02X1342899Y1007336I-1114J1927D01*
G01X1342841Y1007370D01*
G03X1341367I-737J-1277D01*
G02X1339181Y1007346I-1114J1927D01*
G01X1339140Y1007370D01*
G03X1337666I-737J-1277D01*
G02X1335482Y1007346I-1113J1927D01*
G01X1335441Y1007370D01*
G03X1333967I-737J-1277D01*
G02X1331781Y1007346I-1114J1927D01*
G01X1331740Y1007370D01*
G03X1330266I-737J-1277D01*
G02X1328082Y1007346I-1113J1927D01*
G01X1328041Y1007370D01*
G03X1326567I-737J-1277D01*
G02X1324381Y1007346I-1114J1927D01*
G01X1324340Y1007370D01*
G03X1322866I-737J-1277D01*
G02X1320640I-1113J1927D01*
G03X1319166I-737J-1277D01*
G02X1316940I-1113J1927D01*
G03X1315466I-737J-1277D01*
G02X1313240I-1113J1927D01*
G03X1311766I-737J-1277D01*
G02X1309540I-1113J1927D01*
G03X1308066I-737J-1277D01*
G02X1306953Y1007072I-1112J1927D01*
G01X1306412D01*
X1304587Y1005247D01*
X1303263D01*
G01X1356471Y966735D02*
X1355240D01*
X1354981Y966994D01*
G03X1353907Y968648I-2210J-259D01*
G01X1353883Y968662D01*
X1353848Y968682D01*
G02X1353145Y969939I772J1257D01*
G01Y970000D01*
G03X1352034Y971866I-2225J-61D01*
G03X1349866Y971900I-1114J-1927D01*
G01X1349808Y971866D01*
X1349784Y971852D01*
G03X1348695Y969939I1136J-1913D01*
G01Y969905D01*
G02X1347958Y968662I-1474J34D01*
G02X1346484I-737J1277D01*
G01X1346443Y968686D01*
G03X1344257Y968662I-1072J-1951D01*
G02X1342783I-737J1277D01*
G03X1340557I-1113J-1927D01*
G02X1339083I-737J1277D01*
G01X1339025Y968696D01*
G03X1336857Y968662I-1054J-1961D01*
G02X1335383I-737J1277D01*
G03X1333157I-1113J-1927D01*
G02X1331683I-737J1277D01*
G01X1331625Y968696D01*
G03X1329457Y968662I-1054J-1961D01*
G02X1327983I-737J1277D01*
G01X1327925Y968696D01*
G03X1325757Y968662I-1054J-1961D01*
G02X1324283I-737J1277D01*
G01X1324242Y968686D01*
G03X1322058Y968662I-1071J-1951D01*
G02X1320584I-737J1277D01*
G03X1318358I-1113J-1927D01*
G02X1316884I-737J1277D01*
G03X1314658I-1113J-1927D01*
G02X1313184I-737J1277D01*
G03X1310958I-1113J-1927D01*
G02X1309484I-737J1277D01*
G03X1307258I-1113J-1927D01*
G01X1306888D01*
X1306539Y969011D01*
Y971662D01*
X1305762Y972439D01*
X1304963D01*
G01X1353204Y1076587D02*
X1354435D01*
X1354661Y1076361D01*
G02X1352467Y1075310I-1457J226D01*
G03X1350281Y1075334I-1114J-1927D01*
G01X1350240Y1075310D01*
G02X1348766I-737J1277D01*
G03X1346582Y1075334I-1113J-1927D01*
G01X1346541Y1075310D01*
G02X1345067I-737J1277D01*
G03X1342899Y1075344I-1114J-1927D01*
G01X1342841Y1075310D01*
G02X1341367I-737J1277D01*
G03X1339199Y1075344I-1114J-1927D01*
G01X1339141Y1075310D01*
G02X1337667I-737J1277D01*
G03X1335499Y1075344I-1114J-1927D01*
G01X1335441Y1075310D01*
G02X1333967I-737J1277D01*
G01X1333926Y1075334D01*
G03X1331740Y1075310I-1072J-1951D01*
G02X1330266I-737J1277D01*
G03X1328040I-1113J-1927D01*
G02X1326566I-737J1277D01*
G01X1326531Y1075330D01*
G02X1325828Y1076587I772J1257D01*
G01Y1076626D01*
G03X1324716Y1078514I-2225J-39D01*
G03X1322490I-1113J-1927D01*
G02X1321016I-737J1277D01*
G01X1320981Y1078534D01*
G02X1320278Y1079791I772J1257D01*
G03X1319189Y1081704I-2225J0D01*
G01X1319165Y1081718D01*
X1319107Y1081752D01*
G03X1316939Y1081718I-1054J-1961D01*
G02X1315465I-737J1277D01*
G01X1315430Y1081738D01*
G02X1314727Y1082995I772J1257D01*
G01Y1083068D01*
G03X1313615Y1084923I-2225J-73D01*
G03X1311389I-1113J-1928D01*
G02X1309915I-737J1277D01*
G01X1309880Y1084943D01*
G02X1309177Y1086200I772J1257D01*
G01Y1086261D01*
G03X1308066Y1088127I-2225J-61D01*
G01Y1092684D01*
X1306983Y1093767D01*
X1304265D01*
G01X1351353Y1079791D02*
X1349892Y1079394D01*
X1348390Y1078514D01*
G02X1346916I-737J1277D01*
G01X1346858Y1078548D01*
G03X1344690Y1078514I-1054J-1961D01*
G02X1343216I-737J1277D01*
G01X1343158Y1078548D01*
G03X1340990Y1078514I-1054J-1961D01*
G02X1339516I-737J1277D01*
G01X1339475Y1078538D01*
G03X1337291Y1078514I-1071J-1951D01*
G02X1335817I-737J1277D01*
G01X1335776Y1078538D01*
G03X1333590Y1078514I-1072J-1951D01*
G02X1332116I-737J1277D01*
G03X1329890I-1113J-1927D01*
G02X1328416I-737J1277D01*
G01X1328381Y1078534D01*
G02X1327678Y1079791I772J1257D01*
G01Y1079830D01*
G03X1326566Y1081718I-2225J-39D01*
G03X1324340I-1113J-1927D01*
G02X1322866I-737J1277D01*
G01X1322831Y1081738D01*
G02X1322128Y1082995I772J1257D01*
G01Y1083025D01*
G03X1321015Y1084923I-2226J-30D01*
G03X1318789I-1113J-1928D01*
G02X1317315I-737J1277D01*
G01X1317280Y1084943D01*
G02X1316577Y1086200I772J1257D01*
G01Y1086261D01*
G03X1315466Y1088127I-2225J-61D01*
G03X1313298Y1088161I-1114J-1927D01*
G01X1313240Y1088127D01*
G02X1312034Y1088286I-499J865D01*
G01X1310540Y1089780D01*
Y1093297D01*
X1305662Y1098175D01*
X1304869D01*
G01X1351353Y1086200D02*
X1349117Y1087920D01*
X1348767Y1088127D01*
G03X1346541I-1113J-1927D01*
G02X1345067I-737J1277D01*
G03X1342899Y1088161I-1114J-1927D01*
G01X1342841Y1088127D01*
G02X1341367I-737J1277D01*
G03X1339199Y1088161I-1114J-1927D01*
G01X1339141Y1088127D01*
G02X1337667I-737J1277D01*
G03X1335481Y1088151I-1114J-1927D01*
G01X1335440Y1088127D01*
G02X1333966I-737J1277D01*
G01X1333931Y1088147D01*
G02X1333228Y1089404I772J1257D01*
G01Y1089465D01*
G03X1332117Y1091331I-2225J-61D01*
G01X1332082Y1091351D01*
G02X1331379Y1092608I772J1257D01*
G01Y1092638D01*
G03X1330266Y1094536I-2226J-30D01*
G01X1330231Y1094556D01*
G02X1329528Y1095813I772J1257D01*
G01Y1095852D01*
G03X1328416Y1097740I-2225J-39D01*
G03X1326190I-1113J-1927D01*
G02X1324716I-737J1277D01*
G03X1322490I-1113J-1927D01*
G02X1321016I-737J1277D01*
G03X1318790I-1113J-1927D01*
G02X1317316I-737J1277D01*
G01X1317281Y1097760D01*
G02X1316578Y1099017I772J1257D01*
G01Y1099056D01*
G03X1315466Y1100944I-2225J-39D01*
G01X1315431Y1100964D01*
G02X1314728Y1102221I772J1257D01*
G01Y1102294D01*
G03X1313616Y1104149I-2225J-73D01*
G02X1313309Y1104382I731J1282D01*
G01X1312449Y1105242D01*
Y1107769D01*
X1310074Y1110144D01*
X1309064D01*
G01X1349504Y1082995D02*
X1349379Y1083451D01*
X1349226Y1083538D01*
G03X1348617Y1083699I-609J-1071D01*
G01X1347540D01*
X1346543Y1084273D01*
X1346542Y1084272D01*
G03X1345068I-737J-1277D01*
G01X1345067D01*
G02X1342899Y1084238I-1115J1928D01*
G01X1342841Y1084272D01*
G03X1341367I-737J-1277D01*
G02X1339181Y1084248I-1114J1927D01*
G01X1339140Y1084272D01*
G03X1337666I-737J-1277D01*
G02X1335482Y1084248I-1113J1927D01*
G01X1335441Y1084272D01*
G03X1333967I-737J-1277D01*
G02X1331781Y1084248I-1114J1927D01*
G01X1331740Y1084272D01*
G02X1330628Y1086127I1113J1928D01*
G01Y1086200D01*
G03X1329925Y1087457I-1475J0D01*
G01X1329893Y1087475D01*
X1329890Y1087477D01*
G02X1328778Y1089365I1113J1927D01*
G01Y1089404D01*
G03X1328075Y1090661I-1475J0D01*
G01X1328040Y1090681D01*
X1327992Y1090709D01*
G02X1326927Y1092609I1161J1899D01*
G03X1326224Y1093866I-1475J0D01*
G01X1326189Y1093886D01*
G03X1324715I-737J-1277D01*
G01X1324657Y1093852D01*
G02X1322489Y1093886I-1054J1961D01*
G03X1321015I-737J-1277D01*
G01X1320957Y1093852D01*
G02X1318789Y1093886I-1054J1961D01*
G03X1317315I-737J-1277D01*
G01X1317257Y1093852D01*
G02X1315089Y1093886I-1054J1961D01*
G02X1314629Y1094239I1114J1927D01*
G01X1313614Y1095254D01*
Y1097664D01*
X1308929Y1102349D01*
Y1104544D01*
X1308314Y1105159D01*
X1307392D01*
X1307157Y1104924D01*
X1307065D01*
G01X1353204Y1082995D02*
G02X1352811Y1083095I17157J68249D01*
G02X1352480Y1083207I640J2436D01*
G01X1351297Y1083696D01*
G02X1350984Y1083849I1069J2583D01*
G01X1350190Y1084301D01*
G03X1349385Y1084465I-648J-1121D01*
G01X1349160Y1084438D01*
X1349141Y1084448D01*
X1347741D01*
X1346861Y1084955D01*
G03X1344691Y1084922I-1055J-1960D01*
G01X1344690Y1084923D01*
G02X1343216I-737J1277D01*
G01X1343158Y1084957D01*
G03X1340990Y1084923I-1053J-1962D01*
G01Y1084922D01*
G02X1339516I-737J1277D01*
G03X1337290I-1113J-1927D01*
G02X1335816I-737J1277D01*
G01X1335758Y1084956D01*
G03X1333590Y1084922I-1054J-1961D01*
G02X1332116I-737J1277D01*
G01Y1084923D01*
X1332081Y1084943D01*
G02X1331378Y1086200I772J1257D01*
G01Y1086239D01*
G03X1330266Y1088127I-2225J-39D01*
G01X1330231Y1088147D01*
G02X1329528Y1089404I772J1257D01*
G01Y1089443D01*
G03X1328416Y1091331I-2225J-39D01*
G01X1328413Y1091333D01*
X1328406Y1091337D01*
X1328403Y1091339D01*
X1328384Y1091349D01*
X1328381Y1091351D01*
G02X1327678Y1092608I772J1257D01*
G03X1326590Y1094522I-2226J1D01*
G01X1326566Y1094536D01*
G03X1324398Y1094570I-1114J-1927D01*
G01X1324340Y1094536D01*
G02X1322866I-737J1277D01*
G03X1320698Y1094570I-1114J-1927D01*
G01X1320640Y1094536D01*
G02X1319166I-737J1277D01*
G03X1316998Y1094570I-1114J-1927D01*
G01X1316940Y1094536D01*
G02X1315466I-737J1277D01*
G02X1315159Y1094769I731J1282D01*
G01X1314363Y1095565D01*
Y1097975D01*
X1309678Y1102660D01*
Y1104855D01*
X1308625Y1105908D01*
X1307393D01*
X1307157Y1106144D01*
X1307065D01*
G01X1353204Y1089404D02*
X1354435D01*
X1354661Y1089178D01*
G02X1353976Y1088147I-1458J225D01*
G01X1353941Y1088127D01*
G02X1352467I-737J1277D01*
G01X1352432Y1088147D01*
G02X1351729Y1089404I772J1257D01*
G03X1350640Y1091317I-2225J0D01*
G01X1350616Y1091331D01*
X1350558Y1091365D01*
G03X1348390Y1091331I-1054J-1961D01*
G02X1346916I-737J1277D01*
G01X1346858Y1091365D01*
G03X1344690Y1091331I-1054J-1961D01*
G02X1343216I-737J1277D01*
G01X1343158Y1091365D01*
G03X1340990Y1091331I-1054J-1961D01*
G02X1339516I-737J1277D01*
G01X1339458Y1091365D01*
G03X1337290Y1091331I-1054J-1961D01*
G02X1335816I-737J1277D01*
G02X1335079Y1092574I737J1277D01*
G01Y1092664D01*
G03X1333966Y1094536I-2225J-56D01*
G01X1333931Y1094556D01*
G02X1333228Y1095813I772J1257D01*
G01Y1095852D01*
G03X1332116Y1097740I-2225J-39D01*
G01X1332081Y1097760D01*
G02X1331378Y1099017I772J1257D01*
G01Y1099056D01*
G03X1330266Y1100944I-2225J-39D01*
G03X1328040I-1113J-1927D01*
G02X1326566I-737J1277D01*
G03X1324340I-1113J-1927D01*
G02X1322866I-737J1277D01*
G03X1320640I-1113J-1927D01*
G02X1319166I-737J1277D01*
G01X1319131Y1100964D01*
G02X1318428Y1102221I772J1257D01*
G01Y1102294D01*
G03X1317316Y1104149I-2225J-73D01*
G01X1317281Y1104169D01*
G02X1316578Y1105426I772J1257D01*
G01Y1105465D01*
G03X1315466Y1107353I-2225J-39D01*
G01X1315431Y1107373D01*
G02X1314728Y1108630I772J1257D01*
G01Y1108669D01*
G03X1313616Y1110557I-2225J-39D01*
G01Y1110558D01*
X1313560Y1110590D01*
G02X1313051Y1111142I794J1243D01*
G02X1312878Y1111795I1301J694D01*
G01Y1112271D01*
X1309814Y1115335D01*
X1307762D01*
X1306900Y1116197D01*
G01X1356471Y909057D02*
G02X1353161Y907419I-3069J2037D01*
G03X1350694Y907310I-739J-11250D01*
G03X1350183Y907130I226J-1457D01*
G01X1350125Y907096D01*
G02X1347957Y907130I-1054J1961D01*
G03X1346483I-737J-1277D01*
G01X1346425Y907096D01*
G02X1344257Y907130I-1054J1961D01*
G03X1342783I-737J-1277D01*
G01X1342725Y907096D01*
G02X1340557Y907130I-1054J1961D01*
G03X1339083I-737J-1277D01*
G01X1339025Y907096D01*
G02X1336857Y907130I-1054J1961D01*
G03X1334646Y905887I-737J-1277D01*
G01Y905814D01*
G02X1331308Y903926I-2225J39D01*
G03X1329834I-737J-1277D01*
G02X1327666Y903892I-1114J1927D01*
G01X1327608Y903926D01*
G03X1326134I-737J-1277D01*
G02X1323966Y903892I-1114J1927D01*
G01X1323908Y903926D01*
G03X1322434I-737J-1277D01*
G01X1322393Y903902D01*
G02X1320207Y903926I-1072J1952D01*
G03X1317996Y902683I-737J-1277D01*
G01Y902649D01*
X1317995Y902610D01*
G02X1314658Y900723I-2224J40D01*
G03X1313184I-737J-1277D01*
G01Y900722D01*
X1313143Y900698D01*
G02X1310959Y900722I-1071J1951D01*
G03X1308746Y899445I-738J-1277D01*
G01X1308745Y899446D01*
Y897914D01*
X1301997Y891166D01*
X1300865D01*
G01X1358320Y912262D02*
X1358319Y912261D01*
G02X1355386Y910656I-4206J4204D01*
G02X1355037Y910619I-345J1591D01*
G01X1349383D01*
G03X1348334Y910334I15J-2128D01*
G02X1346108I-1113J1928D01*
G03X1344634I-737J-1277D01*
G02X1342466Y910300I-1115J1928D01*
G01X1342408Y910334D01*
G03X1340934I-737J-1277D01*
G02X1338766Y910300I-1115J1928D01*
G01X1338708Y910334D01*
G03X1337234I-737J-1277D01*
G02X1335048Y910310I-1114J1928D01*
G01X1335007Y910334D01*
G03X1333533I-737J-1277D01*
G03X1332796Y909091I737J-1277D01*
G01Y909018D01*
G02X1331684Y907130I-2225J39D01*
G01X1331643Y907106D01*
G02X1329457Y907130I-1072J1951D01*
G03X1327983I-737J-1277D01*
G01X1327925Y907096D01*
G02X1325757Y907130I-1054J1961D01*
G03X1324283I-737J-1277D01*
G01X1324242Y907106D01*
G02X1322058Y907130I-1071J1951D01*
G01X1322015Y907155D01*
G03X1320584Y907131I-694J-1301D01*
G01X1320516Y907091D01*
G02X1318357Y907130I-1044J1967D01*
G03X1316883I-737J-1277D01*
G03X1316146Y905887I737J-1277D01*
G01Y905853D01*
X1316145Y905814D01*
G02X1315034Y903927I-2225J39D01*
G02X1312808I-1113J1927D01*
G03X1311334I-737J-1277D01*
G01X1311280Y903895D01*
G02X1309108Y903926I-1058J1959D01*
G03X1308371Y904126I-742J-1276D01*
G01X1307722D01*
X1306886Y903290D01*
Y900075D01*
X1301897Y895086D01*
X1300865D01*
G01X1358320Y918670D02*
G03X1356925Y918297I0J-2795D01*
G01X1355335Y917380D01*
G02X1353883Y917393I-715J1290D01*
G03X1351681Y917406I-1112J-1927D01*
G01X1351635Y917380D01*
G02X1350183Y917393I-715J1290D01*
G02X1348677Y918896I2061J3571D01*
G03X1347992Y919927I-1458J-225D01*
G01X1347957Y919947D01*
G03X1346483I-737J-1277D01*
G01X1346425Y919913D01*
G02X1344257Y919947I-1053J1962D01*
G03X1342783I-737J-1277D01*
G01X1342725Y919913D01*
G02X1340557Y919947I-1053J1962D01*
G03X1339083I-737J-1277D01*
G01X1339042Y919923D01*
G02X1336858Y919947I-1071J1952D01*
G03X1335384I-737J-1277D01*
G01X1335343Y919923D01*
G02X1333157Y919947I-1072J1952D01*
G03X1331683I-737J-1277D01*
G01X1331625Y919913D01*
G02X1329457Y919947I-1053J1962D01*
G03X1327983I-737J-1277D01*
G01X1327925Y919913D01*
G02X1325757Y919947I-1053J1962D01*
G03X1324283I-737J-1277D01*
G03X1323546Y918704I737J-1277D01*
G01Y918631D01*
G02X1322434Y916743I-2225J39D01*
G02X1320208I-1113J1927D01*
G01X1320165Y916768D01*
G03X1318734Y916744I-694J-1302D01*
G02X1316508I-1113J1928D01*
G03X1315077Y916768I-737J-1278D01*
G01X1315034Y916743D01*
G02X1312848Y916719I-1114J1928D01*
G01X1312807Y916743D01*
X1312779Y916759D01*
G03X1311334Y916744I-709J-1293D01*
G01X1311312Y916732D01*
G03X1310595Y915466I759J-1266D01*
G01Y915427D01*
G02X1308370Y913241I-2225J39D01*
G01X1305802D01*
X1304989Y912428D01*
Y908159D01*
X1302196Y905366D01*
X1301465D01*
G01X1356471Y915466D02*
X1357703D01*
X1357928Y915241D01*
G02X1355734Y914189I-1457J224D01*
G03X1353566Y914223I-1114J-1927D01*
G01X1353508Y914189D01*
G02X1352034I-737J1277D01*
G03X1349866Y914223I-1114J-1927D01*
G01X1349808Y914189D01*
G02X1348334I-737J1277D01*
G03X1346108I-1113J-1927D01*
G02X1344634I-737J1277D01*
G03X1342466Y914223I-1114J-1927D01*
G01X1342408Y914189D01*
G02X1340934I-737J1277D01*
G03X1338748Y914213I-1114J-1927D01*
G01X1338707Y914189D01*
G02X1337233I-737J1277D01*
G03X1335049Y914213I-1113J-1927D01*
G01X1335008Y914189D01*
G02X1333534I-737J1277D01*
G03X1330195Y912262I-1114J-1927D01*
G02X1330194Y912204I-1475J-4D01*
G02X1327983Y910985I-1474J59D01*
G01X1327925Y911019D01*
G03X1325757Y910985I-1053J-1962D01*
G02X1324283I-737J1277D01*
G01X1324242Y911009D01*
G03X1322058Y910985I-1071J-1952D01*
G02X1320584I-737J1277D01*
G03X1318358I-1113J-1927D01*
G02X1316884I-737J1277D01*
G03X1313546Y909097I-1113J-1927D01*
G01Y909058D01*
G02X1311334Y907781I-1475J0D01*
G01X1311293Y907805D01*
G03X1309107Y907781I-1072J-1951D01*
G02X1308370Y907581I-742J1276D01*
G01X1307775D01*
X1304504Y904310D01*
Y901816D01*
X1302679Y899991D01*
X1301792D01*
X1301557Y900226D01*
X1301465D01*
G01X1360171Y915466D02*
X1358939D01*
X1358681Y915208D01*
G02X1357607Y913553I-2210J258D01*
G01X1357586Y913541D01*
X1357583Y913539D01*
X1357525Y913505D01*
G02X1355357Y913539I-1054J1961D01*
G03X1353883I-737J-1277D01*
G01X1353825Y913505D01*
G02X1351657Y913539I-1054J1961D01*
G03X1350183I-737J-1277D01*
G01X1350142Y913515D01*
G02X1347958Y913539I-1071J1951D01*
G03X1346484I-737J-1277D01*
G01X1346443Y913515D01*
G02X1344257Y913539I-1072J1951D01*
G03X1342783I-737J-1277D01*
G01X1342725Y913505D01*
G02X1340557Y913539I-1054J1961D01*
G03X1339083I-737J-1277D01*
G02X1336857I-1113J1927D01*
G03X1335383I-737J-1277D01*
G01X1335325Y913505D01*
G02X1333157Y913539I-1054J1961D01*
G03X1331683I-737J-1277D01*
G01X1331677Y913536D01*
X1331648Y913519D01*
G03X1330945Y912262I772J-1257D01*
G01Y912175D01*
G02X1327666Y910300I-2225J87D01*
G01X1327608Y910334D01*
G03X1326134I-737J-1277D01*
G02X1323966Y910300I-1115J1928D01*
G01X1323908Y910334D01*
G03X1322434I-737J-1277D01*
G02X1320262Y910303I-1114J1928D01*
G01X1320208Y910335D01*
G03X1318734I-737J-1277D01*
G02X1316508I-1113J1927D01*
G03X1314296Y909058I-737J-1277D01*
G01Y909019D01*
G02X1310958Y907131I-2225J39D01*
G03X1309484I-737J-1277D01*
G02X1308370Y906832I-1114J1926D01*
G01X1308086D01*
X1305253Y903999D01*
Y901505D01*
X1302990Y899242D01*
X1301793D01*
X1301557Y899006D01*
X1301465D01*
G01X1356471Y921875D02*
G02X1353161Y920419I-6222J9654D01*
G02X1351761Y920519I-553J2110D01*
G02X1350527Y922101I799J1896D01*
G03X1349842Y923132I-1458J-225D01*
G01X1349807Y923152D01*
G03X1348333I-737J-1277D01*
G02X1346149Y923128I-1113J1927D01*
G01X1346108Y923152D01*
G03X1344634I-737J-1277D01*
G02X1342466Y923118I-1114J1927D01*
G01X1342408Y923152D01*
G03X1340934I-737J-1277D01*
G02X1338766Y923118I-1114J1927D01*
G01X1338708Y923152D01*
G03X1337234I-737J-1277D01*
G02X1335066Y923118I-1114J1927D01*
G01X1335008Y923152D01*
G03X1333534I-737J-1277D01*
G02X1331308I-1113J1927D01*
G03X1329834I-737J-1277D01*
G02X1327666Y923118I-1114J1927D01*
G01X1327608Y923152D01*
G03X1326134I-737J-1277D01*
G02X1323966Y923118I-1114J1927D01*
G01X1323908Y923152D01*
G03X1322434I-737J-1277D01*
G01X1322399Y923132D01*
G03X1321696Y921875I772J-1257D01*
G01X1321695Y921802D01*
G02X1320584Y919948I-2225J73D01*
G02X1318412Y919917I-1114J1928D01*
G01X1318358Y919949D01*
G03X1316927Y919973I-737J-1277D01*
G01X1316884Y919948D01*
G02X1314698Y919924I-1114J1927D01*
G01X1314657Y919948D01*
G03X1313217Y919967I-737J-1277D01*
G01X1313184Y919948D01*
G02X1310994Y919928I-1113J1928D01*
G01X1310959Y919949D01*
G03X1309528Y919973I-737J-1277D01*
G01X1309485Y919948D01*
X1309429Y919916D01*
G03X1308747Y918672I794J-1244D01*
G02X1306521Y916445I-2226J-1D01*
G01X1303409Y913333D01*
Y910161D01*
X1302534Y909286D01*
X1301465D01*
G01X1352771Y966735D02*
X1354002D01*
X1354228Y966961D01*
G03X1353543Y967992I-1458J-225D01*
G01X1353508Y968012D01*
X1353484Y968026D01*
G02X1352395Y969939I1136J1913D01*
G03X1351692Y971196I-1475J0D01*
G01X1351657Y971216D01*
G03X1350183I-737J-1277D01*
G03X1349446Y969973I737J-1277D01*
G01Y969900D01*
G02X1348334Y968012I-2225J39D01*
G02X1346108I-1113J1927D01*
G03X1344634I-737J-1277D01*
G02X1342448Y967988I-1114J1927D01*
G01X1342407Y968012D01*
G03X1340933I-737J-1277D01*
G02X1338749Y967988I-1113J1927D01*
G01X1338708Y968012D01*
G03X1337234I-737J-1277D01*
G02X1335048Y967988I-1114J1927D01*
G01X1335007Y968012D01*
G03X1333533I-737J-1277D01*
G02X1331349Y967988I-1113J1927D01*
G01X1331308Y968012D01*
G03X1329834I-737J-1277D01*
G02X1327666Y967978I-1114J1927D01*
G01X1327608Y968012D01*
G03X1326134I-737J-1277D01*
G02X1323966Y967978I-1114J1927D01*
G01X1323908Y968012D01*
G03X1322434I-737J-1277D01*
G02X1320208I-1113J1927D01*
G03X1318734I-737J-1277D01*
G02X1316508I-1113J1927D01*
G03X1315034I-737J-1277D01*
G02X1312808I-1113J1927D01*
G03X1311334I-737J-1277D01*
G02X1309108I-1113J1927D01*
G03X1307634I-737J-1277D01*
G01X1307499Y967877D01*
X1306547D01*
X1305879Y968545D01*
X1305326Y969880D01*
Y970405D01*
X1304649Y971082D01*
X1303667D01*
G01X1356904Y1076587D02*
X1355673D01*
X1355414Y1076328D01*
G02X1354340Y1074674I-2210J259D01*
G01X1354316Y1074660D01*
X1354258Y1074626D01*
G02X1352090Y1074660I-1054J1961D01*
G03X1350616I-737J-1277D01*
G02X1348390I-1113J1927D01*
G03X1346916I-737J-1277D01*
G01X1346858Y1074626D01*
G02X1344690Y1074660I-1054J1961D01*
G03X1343216I-737J-1277D01*
G01X1343158Y1074626D01*
G02X1340990Y1074660I-1054J1961D01*
G03X1339516I-737J-1277D01*
G01X1339458Y1074626D01*
G02X1337290Y1074660I-1054J1961D01*
G03X1335816I-737J-1277D01*
G01X1335775Y1074636D01*
G02X1333591Y1074660I-1071J1951D01*
G03X1332117I-737J-1277D01*
G02X1329931Y1074636I-1114J1927D01*
G01X1329890Y1074660D01*
G03X1328416I-737J-1277D01*
G02X1326232Y1074636I-1113J1927D01*
G01X1326191Y1074660D01*
X1326167Y1074674D01*
G02X1325078Y1076587I1136J1913D01*
G03X1324375Y1077844I-1475J0D01*
G01X1324340Y1077864D01*
G03X1322866I-737J-1277D01*
G02X1320640I-1113J1927D01*
G02X1319528Y1079752I1113J1927D01*
G01Y1079791D01*
G03X1318825Y1081048I-1475J0D01*
G01X1318790Y1081068D01*
G03X1317316I-737J-1277D01*
G02X1315148Y1081034I-1114J1927D01*
G01X1315090Y1081068D01*
X1315066Y1081082D01*
G02X1313977Y1082995I1136J1913D01*
G03X1313274Y1084252I-1475J0D01*
G01X1313239Y1084272D01*
G03X1311765I-737J-1277D01*
G02X1309539I-1113J1928D01*
G02X1308427Y1086127I1113J1928D01*
G01Y1086200D01*
G03X1307724Y1087457I-1475J0D01*
G01X1307657D01*
X1306800Y1088314D01*
Y1090078D01*
X1306405Y1090473D01*
X1305220D01*
X1304265Y1091428D01*
G01X1358753Y1079791D02*
X1356555Y1078092D01*
X1356228Y1077900D01*
G02X1353988Y1077894I-1125J1921D01*
G03X1352509Y1077889I-735J-1274D01*
G01X1352408Y1077830D01*
G02X1350240Y1077864I-1054J1961D01*
G03X1348766I-737J-1277D01*
G02X1346582Y1077840I-1113J1927D01*
G01X1346541Y1077864D01*
G03X1345067I-737J-1277D01*
G02X1342899Y1077830I-1114J1927D01*
G01X1342841Y1077864D01*
G03X1341367I-737J-1277D01*
G02X1339199Y1077830I-1114J1927D01*
G01X1339141Y1077864D01*
G03X1337667I-737J-1277D01*
G02X1335441I-1113J1927D01*
G03X1333967I-737J-1277D01*
G02X1331781Y1077840I-1114J1927D01*
G01X1331740Y1077864D01*
G03X1330266I-737J-1277D01*
G02X1328040I-1113J1927D01*
G02X1326928Y1079752I1113J1927D01*
G01Y1079791D01*
G03X1326225Y1081048I-1475J0D01*
G01X1326190Y1081068D01*
G03X1324716I-737J-1277D01*
G02X1322490I-1113J1927D01*
G01X1322442Y1081096D01*
G02X1321377Y1082995I1161J1899D01*
G03X1320674Y1084252I-1475J0D01*
G01X1320639Y1084272D01*
G03X1319165I-737J-1277D01*
G02X1316939I-1113J1928D01*
G02X1315827Y1086127I1113J1928D01*
G01Y1086200D01*
G03X1315124Y1087457I-1475J0D01*
G01X1315089Y1087477D01*
G03X1313615I-737J-1277D01*
G01X1313557Y1087443D01*
G02X1309791Y1089695I-1210J2252D01*
G01Y1092986D01*
X1306629Y1096148D01*
X1304265D01*
G01X1356904Y1082995D02*
X1356902D01*
X1355803Y1081929D01*
X1354334Y1081079D01*
X1354325Y1081073D01*
X1354320Y1081070D01*
X1354316Y1081068D01*
X1354258Y1081034D01*
G02X1352090Y1081068I-1054J1961D01*
G03X1350616I-737J-1277D01*
G01X1350558Y1081034D01*
G02X1348390Y1081068I-1054J1961D01*
G03X1346916I-737J-1277D01*
G01X1346858Y1081034D01*
G02X1344690Y1081068I-1054J1961D01*
G03X1343216I-737J-1277D01*
G01X1343158Y1081034D01*
G02X1340990Y1081068I-1054J1961D01*
G03X1339516I-737J-1277D01*
G02X1337332Y1081044I-1113J1927D01*
G01X1337291Y1081068D01*
G03X1335817I-737J-1277D01*
G01X1335776Y1081044D01*
G02X1333590Y1081068I-1072J1951D01*
G03X1332116I-737J-1277D01*
G02X1329890I-1113J1927D01*
G02X1328778Y1082956I1113J1927D01*
G01Y1082995D01*
G03X1328075Y1084252I-1475J0D01*
G01X1328043Y1084270D01*
X1328040Y1084272D01*
G02X1326928Y1086127I1113J1928D01*
G01Y1086200D01*
G03X1326225Y1087457I-1475J0D01*
G01X1326190Y1087477D01*
G03X1324716I-737J-1277D01*
G01X1324675Y1087453D01*
G02X1322489Y1087477I-1072J1951D01*
G03X1321015I-737J-1277D01*
G01X1320957Y1087443D01*
G02X1318789Y1087477I-1054J1961D01*
G02X1317678Y1089343I1114J1927D01*
G01Y1089404D01*
G03X1316975Y1090661I-1475J0D01*
G01X1316940Y1090681D01*
G03X1315466I-737J-1277D01*
G02X1312874Y1090944I-1114J1928D01*
G02X1312779Y1091033I1473J1668D01*
G01X1311604Y1092209D01*
Y1093831D01*
X1307243Y1098192D01*
Y1100867D01*
X1306312Y1101798D01*
X1305197D01*
X1304961Y1101562D01*
X1304869D01*
G01X1356904Y1089404D02*
X1355673D01*
X1355414Y1089145D01*
G02X1354340Y1087491I-2210J259D01*
G01X1354316Y1087477D01*
X1354258Y1087443D01*
G02X1352090Y1087477I-1054J1961D01*
G02X1350979Y1089343I1114J1927D01*
G01Y1089404D01*
G03X1350276Y1090661I-1475J0D01*
G01X1350241Y1090681D01*
G03X1348767I-737J-1277D01*
G02X1346599Y1090647I-1114J1927D01*
G01X1346541Y1090681D01*
G03X1345067I-737J-1277D01*
G02X1342899Y1090647I-1114J1927D01*
G01X1342841Y1090681D01*
G03X1341367I-737J-1277D01*
G02X1339199Y1090647I-1114J1927D01*
G01X1339141Y1090681D01*
G03X1337667I-737J-1277D01*
G02X1335481Y1090657I-1114J1927D01*
G01X1335440Y1090681D01*
G02X1334328Y1092569I1113J1927D01*
G01Y1092642D01*
G03X1333591Y1093885I-1474J-34D01*
G02X1332478Y1095757I1112J1928D01*
G01Y1095813D01*
G03X1331775Y1097070I-1475J0D01*
G01X1331740Y1097090D01*
G02X1330628Y1098978I1113J1927D01*
G01Y1099017D01*
G03X1329925Y1100274I-1475J0D01*
G01X1329890Y1100294D01*
G03X1328416I-737J-1277D01*
G02X1326190I-1113J1927D01*
G03X1324716I-737J-1277D01*
G02X1322490I-1113J1927D01*
G03X1321016I-737J-1277D01*
G02X1318790I-1113J1927D01*
G02X1317678Y1102182I1113J1927D01*
G01Y1102221D01*
G03X1316975Y1103478I-1475J0D01*
G01X1316940Y1103498D01*
G02X1315828Y1105353I1113J1928D01*
G01Y1105426D01*
G03X1315125Y1106683I-1475J0D01*
G01X1315090Y1106703D01*
G02X1313978Y1108591I1113J1927D01*
G01Y1108630D01*
G03X1313275Y1109887I-1475J0D01*
G01X1313240Y1109907D01*
G02X1312127Y1111797I1112J1928D01*
G01X1312128Y1111836D01*
Y1111961D01*
X1310404Y1113685D01*
X1307283D01*
G01X1358753Y1086200D02*
G03X1357437Y1085854I-1J-2670D01*
G01X1355768Y1084910D01*
G02X1354316Y1084923I-715J1290D01*
G03X1352114Y1084936I-1112J-1927D01*
G01X1352068Y1084910D01*
G02X1350616Y1084923I-715J1290D01*
G02X1349878Y1085489I1782J3087D01*
G02X1349593Y1085915I929J930D01*
G01X1349481Y1086186D01*
G03X1349223Y1086809I-881J0D01*
G01X1349098Y1086935D01*
G03X1348393Y1087476I-2405J-2405D01*
G01X1348391Y1087477D01*
G03X1346917I-737J-1277D01*
G01X1346876Y1087453D01*
G02X1344690Y1087477I-1072J1951D01*
G03X1343216I-737J-1277D01*
G01X1343158Y1087443D01*
G02X1340990Y1087477I-1054J1961D01*
G03X1339516I-737J-1277D01*
G01X1339458Y1087443D01*
G02X1337290Y1087477I-1054J1961D01*
G03X1335816I-737J-1277D01*
G02X1333590I-1113J1927D01*
G02X1332478Y1089365I1113J1927D01*
G01Y1089404D01*
G03X1331775Y1090661I-1475J0D01*
G01X1331740Y1090681D01*
X1331716Y1090695D01*
G02X1330628Y1092608I1138J1913D01*
G03X1329925Y1093865I-1475J0D01*
G01X1329890Y1093885D01*
G02X1328778Y1095740I1113J1928D01*
G01Y1095813D01*
G03X1328075Y1097070I-1475J0D01*
G01X1328040Y1097090D01*
G03X1326566I-737J-1277D01*
G02X1324340I-1113J1927D01*
G03X1322866I-737J-1277D01*
G02X1320640I-1113J1927D01*
G03X1319166I-737J-1277D01*
G02X1316940I-1113J1927D01*
G02X1315828Y1098978I1113J1927D01*
G01Y1099017D01*
G03X1315125Y1100274I-1475J0D01*
G01X1315090Y1100294D01*
G02X1313978Y1102182I1113J1927D01*
G01Y1102221D01*
G03X1313275Y1103478I-1475J0D01*
G01X1313240Y1103498D01*
G02X1312779Y1103852I1114J1928D01*
G01X1311700Y1104931D01*
Y1107458D01*
X1310974Y1108184D01*
X1309065D01*
G01X1360604Y1082995D02*
X1357759Y1084204D01*
X1357649Y1084268D01*
X1357641Y1084272D01*
G03X1356167I-737J-1277D01*
G01X1356132Y1084252D01*
G03X1355429Y1082995I772J-1257D01*
G01Y1082611D01*
X1355347Y1082532D01*
X1354043Y1081777D01*
X1353954Y1081726D01*
X1353948Y1081722D01*
X1353940Y1081718D01*
X1353941D01*
G02X1352467I-737J1277D01*
G03X1350299Y1081752I-1114J-1927D01*
G01X1350241Y1081718D01*
G02X1348767I-737J1277D01*
G03X1346599Y1081752I-1114J-1927D01*
G01X1346541Y1081718D01*
G02X1345067I-737J1277D01*
G03X1342899Y1081752I-1114J-1927D01*
G01X1342841Y1081718D01*
G02X1341367I-737J1277D01*
G03X1339181Y1081742I-1114J-1927D01*
G01X1339140Y1081718D01*
G02X1337666I-737J1277D01*
G01X1337625Y1081742D01*
G03X1335441Y1081718I-1071J-1951D01*
G02X1333967I-737J1277D01*
G03X1331781Y1081742I-1114J-1927D01*
G01X1331740Y1081718D01*
G02X1330266I-737J1277D01*
G01X1330231Y1081738D01*
G02X1329528Y1082995I772J1257D01*
G01Y1083068D01*
G03X1328416Y1084923I-2225J-73D01*
G01X1328381Y1084943D01*
G02X1327678Y1086200I772J1257D01*
G01Y1086239D01*
G03X1326566Y1088127I-2225J-39D01*
G03X1324340I-1113J-1927D01*
G02X1322866I-737J1277D01*
G03X1320698Y1088161I-1114J-1927D01*
G01X1320640Y1088127D01*
G02X1319166I-737J1277D01*
G01X1319131Y1088147D01*
G02X1318428Y1089404I772J1257D01*
G01Y1089460D01*
G03X1317315Y1091332I-2225J-56D01*
G01X1317257Y1091366D01*
G03X1315089Y1091332I-1053J-1962D01*
G02X1313615I-737J1277D01*
G02X1313308Y1091565I731J1282D01*
G01X1312353Y1092520D01*
Y1094142D01*
X1307992Y1098503D01*
Y1101178D01*
X1306623Y1102547D01*
X1305196D01*
X1304961Y1102782D01*
X1304869D01*
G01X1351353Y1002888D02*
X1348882Y1004749D01*
X1348766Y1004815D01*
X1348767Y1004816D01*
G03X1346599Y1004850I-1115J-1928D01*
G01X1346541Y1004816D01*
G02X1345067I-737J1277D01*
G03X1342899Y1004850I-1115J-1928D01*
G01X1342841Y1004816D01*
G02X1341367I-737J1277D01*
G03X1339181Y1004840I-1114J-1928D01*
G01X1339140Y1004816D01*
G02X1337666I-737J1277D01*
G01X1337625Y1004840D01*
G03X1335441Y1004816I-1071J-1952D01*
G02X1333967I-737J1277D01*
G03X1331781Y1004840I-1114J-1928D01*
G01X1331740Y1004816D01*
G02X1330266I-737J1277D01*
G03X1328082Y1004840I-1113J-1928D01*
G01X1328041Y1004816D01*
G02X1326567I-737J1277D01*
G03X1324381Y1004840I-1114J-1928D01*
G01X1324340Y1004816D01*
G02X1322866I-737J1277D01*
G03X1320640I-1113J-1928D01*
G02X1319166I-737J1277D01*
G03X1316940I-1113J-1928D01*
G02X1315466I-737J1277D01*
G03X1312779Y1004462I-1113J-1928D01*
G01X1309843Y1001526D01*
X1308563D01*
G01X1358753Y1002888D02*
G02X1356167Y1000961I-9545J10110D01*
G02X1353999Y1000927I-1114J1927D01*
G01X1353941Y1000961D01*
G03X1352467I-737J-1277D01*
G02X1350241I-1113J1927D01*
G01Y1000962D01*
G02X1349128Y1002888I1112J1927D01*
G03X1348391Y1004164I-1473J0D01*
G01X1348390Y1004165D01*
G03X1346916I-737J-1277D01*
G01X1346858Y1004131D01*
G02X1344690Y1004165I-1053J1962D01*
G03X1343216I-737J-1277D01*
G01X1343158Y1004131D01*
G02X1340990Y1004165I-1053J1962D01*
G03X1339516I-737J-1277D01*
G02X1337332Y1004141I-1113J1928D01*
G01X1337291Y1004165D01*
G03X1335817I-737J-1277D01*
G01X1335776Y1004141D01*
G02X1333590Y1004165I-1072J1952D01*
G03X1332116I-737J-1277D01*
G02X1329890I-1113J1928D01*
G03X1328416I-737J-1277D01*
G01X1328358Y1004131D01*
G02X1326190Y1004165I-1053J1962D01*
G03X1324716I-737J-1277D01*
G02X1322490I-1113J1928D01*
G03X1321016I-737J-1277D01*
G02X1318790I-1113J1928D01*
G03X1317316I-737J-1277D01*
G02X1315090I-1113J1928D01*
G03X1313616I-737J-1277D01*
G03X1313309Y1003932I731J-1282D01*
G01X1310144Y1000767D01*
Y1000512D01*
X1309188Y999556D01*
X1308563D01*
G01X1347220Y893036D02*
X1348451D01*
X1348677Y892810D01*
G02X1347992Y891779I-1458J225D01*
G01X1347957Y891759D01*
G02X1346483I-737J1277D01*
G01X1346425Y891793D01*
G03X1344257Y891759I-1054J-1961D01*
G01X1344258D01*
G03X1343146Y889871I1113J-1927D01*
G01Y889832D01*
G02X1342443Y888575I-1475J0D01*
G01X1342408Y888555D01*
G02X1340934I-737J1277D01*
G03X1338766Y888589I-1115J-1928D01*
G01X1338708Y888555D01*
G02X1337234I-737J1277D01*
G03X1335048Y888579I-1114J-1928D01*
G01X1335007Y888555D01*
G02X1333533I-737J1277D01*
G03X1331349Y888579I-1113J-1928D01*
G01X1331308Y888555D01*
G02X1329834I-737J1277D01*
G03X1327666Y888589I-1115J-1928D01*
G01X1327608Y888555D01*
G03X1326495Y886683I1112J-1928D01*
G01Y886593D01*
G02X1325758Y885350I-1474J34D01*
G03X1324646Y883462I1113J-1927D01*
G01Y883423D01*
G02X1323943Y882166I-1475J0D01*
G01X1323908Y882146D01*
G02X1322434I-737J1277D01*
G03X1320208I-1113J-1927D01*
G02X1318734I-737J1277D01*
G03X1316508I-1113J-1927D01*
G02X1315034I-737J1277D01*
G01X1314993Y882170D01*
G03X1312807Y882146I-1072J-1951D01*
G02X1311333I-737J1277D01*
G03X1309151Y882170I-1112J-1927D01*
G01X1309110Y882146D01*
G03X1308648Y881792I1110J-1927D01*
G01X1306147Y879291D01*
Y875805D01*
X1303559Y873217D01*
X1300865D01*
G01X1358320Y893036D02*
G02X1356038Y891284I-7800J7797D01*
G01X1355734Y891109D01*
G02X1353508I-1113J1927D01*
G03X1352034I-737J-1277D01*
G01X1351999Y891089D01*
G03X1351296Y889832I772J-1257D01*
G01Y889776D01*
G02X1350183Y887904I-2225J56D01*
G01X1350125Y887870D01*
G02X1347957Y887904I-1053J1962D01*
G03X1346483I-737J-1277D01*
G01X1346448Y887884D01*
G03X1345745Y886627I772J-1257D01*
G01Y886566D01*
G02X1344634Y884700I-2225J61D01*
G01X1344599Y884680D01*
G03X1343896Y883423I772J-1257D01*
G01Y883384D01*
G02X1342784Y881496I-2225J39D01*
G01X1342743Y881472D01*
G02X1340557Y881496I-1072J1951D01*
G02X1339446Y883362I1114J1927D01*
G01Y883423D01*
G03X1338743Y884680I-1475J0D01*
G01X1338708Y884700D01*
G03X1337234I-737J-1277D01*
G01X1337199Y884680D01*
G03X1336496Y883423I772J-1257D01*
G01Y883384D01*
G02X1335384Y881496I-2225J39D01*
G01X1335343Y881472D01*
G02X1333157Y881496I-1072J1951D01*
G02X1332046Y883362I1114J1927D01*
G01Y883423D01*
G03X1331343Y884680I-1475J0D01*
G01X1331308Y884700D01*
G03X1329834I-737J-1277D01*
G01X1329799Y884680D01*
G03X1329096Y883423I772J-1257D01*
G01Y883384D01*
G02X1327984Y881496I-2225J39D01*
G01X1327949Y881476D01*
G03X1327246Y880219I772J-1257D01*
G01Y880163D01*
G02X1326134Y878291I-2226J56D01*
G02X1323966Y878257I-1115J1928D01*
G01X1323908Y878291D01*
X1323875Y878310D01*
G03X1322435Y878291I-703J-1296D01*
G02X1320249Y878267I-1114J1928D01*
G01X1320208Y878291D01*
G03X1318734I-737J-1277D01*
G02X1316508I-1113J1928D01*
G03X1315034I-737J-1277D01*
G01X1314993Y878267D01*
G02X1312807Y878291I-1072J1952D01*
G03X1310595Y877014I-737J-1277D01*
G01Y871004D01*
X1304600Y865009D01*
G01X1349071Y896240D02*
X1348946Y896696D01*
X1348793Y896783D01*
G03X1348184Y896944I-609J-1071D01*
G01X1347107D01*
X1346110Y897518D01*
X1346109Y897517D01*
G03X1344635I-737J-1277D01*
G01X1344634D01*
G02X1342466Y897483I-1115J1928D01*
G01X1342408Y897517D01*
G03X1340934I-737J-1277D01*
G01X1340899Y897497D01*
G03X1340196Y896240I772J-1257D01*
G02X1339108Y894327I-2226J0D01*
G01X1339084Y894313D01*
G02X1336916Y894279I-1114J1927D01*
G01X1336858Y894313D01*
G03X1335384I-737J-1277D01*
G01X1335343Y894289D01*
G02X1333157Y894313I-1072J1951D01*
G03X1331683I-737J-1277D01*
G01X1331625Y894279D01*
G02X1329457Y894313I-1054J1961D01*
G03X1327983I-737J-1277D01*
G01X1327925Y894279D01*
G02X1325757Y894313I-1054J1961D01*
G03X1324283I-737J-1277D01*
G03X1323546Y893070I737J-1277D01*
G01Y892997D01*
G02X1322434Y891109I-2225J39D01*
G01X1322399Y891089D01*
G03X1321696Y889832I772J-1257D01*
G01Y889776D01*
G02X1320584Y887904I-2226J56D01*
G02X1318416Y887870I-1115J1928D01*
G01X1318358Y887904D01*
G03X1316884I-737J-1277D01*
G02X1314658I-1113J1928D01*
G03X1313184I-737J-1277D01*
G02X1311016Y887870I-1115J1928D01*
G01X1310919Y887927D01*
X1310911Y887931D01*
G03X1309482Y887904I-690J-1304D01*
G03X1309429Y887872I736J-1280D01*
G03X1309175Y887671I784J-1252D01*
G01X1303899Y882395D01*
Y879845D01*
X1302675Y878621D01*
X1301192D01*
X1300957Y878386D01*
X1300865D01*
G01X1352771Y902649D02*
G02X1349848Y903902I3540J12294D01*
G01X1349807Y903926D01*
G03X1348333I-737J-1277D01*
G02X1346149Y903902I-1113J1927D01*
G01X1346108Y903926D01*
G03X1344634I-737J-1277D01*
G02X1342466Y903892I-1114J1927D01*
G01X1342408Y903926D01*
G03X1340934I-737J-1277D01*
G02X1338766Y903892I-1114J1927D01*
G01X1338708Y903926D01*
G03X1337234I-737J-1277D01*
G01X1337199Y903906D01*
G03X1336496Y902649I772J-1257D01*
G01Y902610D01*
G02X1335384Y900722I-2225J39D01*
G01X1335343Y900698D01*
G02X1333157Y900722I-1072J1951D01*
G03X1331683I-737J-1277D01*
G01X1331625Y900688D01*
G02X1329457Y900722I-1054J1961D01*
G03X1327983I-737J-1277D01*
G01X1327925Y900688D01*
G02X1325757Y900722I-1054J1961D01*
G03X1324283I-737J-1277D01*
G01X1324242Y900698D01*
G02X1322058Y900722I-1071J1951D01*
G03X1320584I-737J-1277D01*
G01X1320549Y900702D01*
G03X1319846Y899445I772J-1257D01*
G01X1319845Y899389D01*
G02X1318733Y897518I-2225J56D01*
G03X1317996Y896301I737J-1278D01*
G01Y896240D01*
G02X1316907Y894327I-2225J0D01*
G01X1316883Y894313D01*
X1316842Y894289D01*
G02X1314658Y894313I-1071J1951D01*
G03X1313184I-737J-1277D01*
G02X1310998Y894289I-1114J1927D01*
G01X1310957Y894313D01*
G03X1309517Y894332I-737J-1277D01*
G01X1309484Y894313D01*
G03X1309177Y894079I733J-1279D01*
G01X1306381Y891283D01*
Y890070D01*
X1301797Y885486D01*
X1300865D01*
G01X1350920Y899445D02*
G03X1348333Y901372I-9531J-10095D01*
G03X1346149Y901396I-1113J-1927D01*
G01X1346108Y901372D01*
G02X1344634I-737J1277D01*
G03X1342466Y901406I-1114J-1927D01*
G01X1342408Y901372D01*
G02X1340934I-737J1277D01*
G03X1338766Y901406I-1114J-1927D01*
G01X1338708Y901372D01*
X1338684Y901358D01*
G03X1337595Y899445I1136J-1913D01*
G01Y899411D01*
G02X1336858Y898168I-1474J34D01*
G02X1335384I-737J1277D01*
G01X1335343Y898192D01*
G03X1333157Y898168I-1072J-1952D01*
G02X1331683I-737J1277D01*
G01X1331625Y898202D01*
G03X1329457Y898168I-1053J-1962D01*
G02X1327983I-737J1277D01*
G01X1327925Y898202D01*
G03X1325757Y898168I-1053J-1962D01*
G02X1324283I-737J1277D01*
G01X1324242Y898192D01*
G03X1322058Y898168I-1071J-1952D01*
G03X1320945Y896270I1113J-1928D01*
G01Y896240D01*
G02X1320242Y894983I-1475J0D01*
G01X1320207Y894963D01*
X1320183Y894949D01*
G03X1319095Y893036I1138J-1913D01*
G02X1318392Y891779I-1475J0D01*
G01X1318357Y891759D01*
G02X1316883I-737J1277D01*
G01X1316842Y891783D01*
G03X1314658Y891759I-1071J-1951D01*
G02X1313184I-737J1277D01*
G03X1310998Y891783I-1114J-1927D01*
G02X1310220Y891560I-780J1252D01*
G01X1308807D01*
X1307342Y890095D01*
Y889126D01*
X1301742Y883526D01*
X1300865D01*
G01X1352771Y896240D02*
G02X1351431Y896594I-1J2708D01*
G01X1349757Y897546D01*
G03X1348952Y897710I-648J-1121D01*
G01X1348727Y897683D01*
X1348708Y897693D01*
X1347308D01*
X1346428Y898200D01*
G03X1344258Y898167I-1055J-1960D01*
G01X1344257Y898168D01*
G02X1342783I-737J1277D01*
G01X1342725Y898202D01*
G03X1340557Y898168I-1053J-1962D01*
G03X1339445Y896296I1114J-1928D01*
G01Y896240D01*
G02X1338742Y894983I-1475J0D01*
G01X1338707Y894963D01*
G02X1337233I-737J1277D01*
G01X1337192Y894987D01*
G03X1335008Y894963I-1071J-1951D01*
G02X1333534I-737J1277D01*
G03X1331366Y894997I-1114J-1927D01*
G01X1331308Y894963D01*
G02X1329834I-737J1277D01*
G03X1327666Y894997I-1114J-1927D01*
G01X1327608Y894963D01*
G02X1326134I-737J1277D01*
G03X1323966Y894997I-1114J-1927D01*
G01X1323908Y894963D01*
X1323884Y894949D01*
G03X1322795Y893036I1136J-1913D01*
G01Y893002D01*
G02X1322058Y891759I-1474J34D01*
G01X1322010Y891731D01*
G03X1320945Y889832I1161J-1899D01*
G02X1320242Y888575I-1475J0D01*
G01X1320207Y888555D01*
G02X1318733I-737J1277D01*
G01X1318692Y888579D01*
G03X1316508Y888555I-1071J-1952D01*
G02X1315034I-737J1277D01*
G01X1314993Y888579D01*
G03X1312807Y888555I-1072J-1952D01*
G02X1311333I-737J1277D01*
G01X1311317Y888565D01*
X1311262Y888596D01*
G03X1309106Y888552I-1038J-1969D01*
G03X1309031Y888507I1108J-1931D01*
G03X1308646Y888203I1179J-1889D01*
G01X1308645Y888201D01*
X1303150Y882706D01*
Y880156D01*
X1302364Y879370D01*
X1301193D01*
X1300957Y879606D01*
X1300865D01*
G01X1352771Y928283D02*
G02X1350675Y927292I-2488J2550D01*
G03X1349866Y927040I245J-2213D01*
G01X1349808Y927006D01*
G02X1348334I-737J1277D01*
G03X1346166Y927040I-1114J-1927D01*
G01X1346108Y927006D01*
G02X1344634I-737J1277D01*
G03X1342466Y927040I-1114J-1927D01*
G01X1342408Y927006D01*
G02X1340934I-737J1277D01*
G03X1338766Y927040I-1114J-1927D01*
G01X1338708Y927006D01*
G02X1337234I-737J1277D01*
G03X1335048Y927030I-1114J-1927D01*
G01X1335007Y927006D01*
G02X1333533I-737J1277D01*
G01X1333492Y927030D01*
G03X1331308Y927006I-1071J-1951D01*
G02X1329834I-737J1277D01*
G03X1327666Y927040I-1114J-1927D01*
G01X1327608Y927006D01*
G02X1326134I-737J1277D01*
G03X1323966Y927040I-1114J-1927D01*
G01X1323908Y927006D01*
G02X1322477Y926982I-737J1277D01*
G01X1322434Y927007D01*
G03X1320208I-1113J-1927D01*
G01X1320160Y926979D01*
G03X1319095Y925079I1161J-1899D01*
G02X1318413Y923835I-1476J0D01*
G01X1318357Y923803D01*
X1318314Y923778D01*
G02X1316883Y923802I-694J1301D01*
G01X1316848Y923823D01*
G03X1314658Y923803I-1077J-1948D01*
G01X1314625Y923784D01*
G02X1313185Y923803I-703J1296D01*
G01X1313144Y923827D01*
G03X1310958Y923803I-1072J-1951D01*
G02X1309516Y923784I-738J1277D01*
G01X1309412Y923844D01*
G03X1306796Y923450I-1041J-1969D01*
G01X1306429Y923083D01*
X1305937Y921895D01*
Y920137D01*
X1302726Y916926D01*
X1301466D01*
G01X1350920Y931488D02*
G03X1347958Y930211I3980J-13306D01*
G02X1346484I-737J1277D01*
G01X1346443Y930235D01*
G03X1344257Y930211I-1072J-1952D01*
G02X1342783I-737J1277D01*
G01X1342725Y930245D01*
G03X1340557Y930211I-1053J-1962D01*
G02X1339083I-737J1277D01*
G01X1339025Y930245D01*
G03X1336857Y930211I-1053J-1962D01*
G02X1335383I-737J1277D01*
G03X1333157I-1113J-1928D01*
G02X1331683I-737J1277D01*
G01X1331625Y930245D01*
G03X1329457Y930211I-1053J-1962D01*
G02X1327983I-737J1277D01*
G01X1327942Y930235D01*
G03X1325758Y930211I-1071J-1952D01*
G02X1324284I-737J1277D01*
G03X1322058I-1113J-1928D01*
G02X1320584I-737J1277D01*
G03X1318358I-1113J-1927D01*
G03X1317246Y928323I1113J-1927D01*
G01Y928284D01*
G02X1316521Y927014I-1475J0D01*
G01X1316508Y927007D01*
X1316475Y926988D01*
G02X1315035Y927007I-703J1296D01*
G03X1312809I-1113J-1927D01*
G01X1312776Y926988D01*
G02X1311334Y927007I-704J1296D01*
G03X1309148Y927031I-1114J-1927D01*
G02X1308370Y926808I-780J1252D01*
G01X1307565D01*
X1305015Y924258D01*
Y923756D01*
X1304086Y921513D01*
X1303419Y920846D01*
X1301466D01*
G01X1349071Y934691D02*
X1348946Y935147D01*
X1348793Y935234D01*
G03X1348184Y935395I-609J-1071D01*
G01X1347107D01*
X1346110Y935969D01*
X1346109Y935968D01*
G03X1344635I-737J-1277D01*
G01X1344634D01*
G02X1342466Y935934I-1115J1928D01*
G01X1342408Y935968D01*
G03X1340934I-737J-1277D01*
G02X1338748Y935944I-1114J1928D01*
G01X1338707Y935968D01*
Y935969D01*
G03X1337233I-737J-1277D01*
G01X1337192Y935945D01*
G02X1335008Y935969I-1071J1951D01*
G03X1333534I-737J-1277D01*
G02X1331366Y935935I-1114J1927D01*
G01X1331308Y935969D01*
G03X1329834I-737J-1277D01*
G01Y935968D01*
G02X1327666Y935934I-1115J1928D01*
G01X1327608Y935968D01*
G03X1326134I-737J-1277D01*
G02X1323966Y935934I-1115J1928D01*
G01X1323908Y935968D01*
G03X1322434I-737J-1277D01*
G02X1320242Y935948I-1114J1928D01*
G01X1320207Y935969D01*
G03X1318733I-737J-1277D01*
G02X1316549Y935945I-1113J1927D01*
G01X1316508Y935969D01*
G03X1314296Y934692I-737J-1277D01*
G02X1313245Y932802I-2225J0D01*
G01X1313184Y932765D01*
G02X1311016Y932731I-1114J1927D01*
G01X1310958Y932765D01*
G03X1309484I-737J-1277D01*
G02X1307300Y932741I-1113J1927D01*
G01X1307301Y932742D01*
G03X1307150Y932814I-710J-1295D01*
G01X1307003D01*
X1305636Y931447D01*
Y930077D01*
X1305325Y929766D01*
Y927967D01*
X1303601Y926243D01*
X1302593D01*
X1302358Y926008D01*
X1302266D01*
G01X1352771Y934691D02*
G02X1351431Y935045I-1J2708D01*
G01X1349757Y935997D01*
G03X1348952Y936161I-648J-1121D01*
G01X1348727Y936134D01*
X1348708Y936144D01*
X1347308D01*
X1346428Y936651D01*
G03X1344258Y936618I-1055J-1960D01*
G01X1344257Y936619D01*
G02X1342783I-737J1277D01*
G01X1342725Y936653D01*
G03X1340557Y936619I-1053J-1962D01*
G02X1339083I-737J1277D01*
G03X1336899Y936643I-1113J-1927D01*
G01X1336858Y936619D01*
G02X1335384I-737J1277D01*
G01X1335343Y936643D01*
G03X1333157Y936619I-1072J-1951D01*
G02X1331683I-737J1277D01*
G01X1331625Y936653D01*
G03X1329457Y936619I-1054J-1961D01*
G02X1327983I-737J1277D01*
G01X1327925Y936653D01*
G03X1325757Y936619I-1053J-1962D01*
G02X1324283I-737J1277D01*
G01X1324242Y936643D01*
G03X1322058Y936619I-1071J-1952D01*
G02X1320584I-737J1277D01*
G03X1318398Y936643I-1114J-1927D01*
G01X1318357Y936619D01*
G02X1316883I-737J1277D01*
G03X1313545Y934692I-1113J-1927D01*
G02X1311333Y933415I-1475J0D01*
G01X1311275Y933449D01*
G03X1309107Y933415I-1054J-1961D01*
G02X1307661Y933399I-737J1277D01*
G03X1307283Y933563I-1071J-1951D01*
G01X1306692D01*
X1304887Y931758D01*
Y930388D01*
X1304576Y930077D01*
Y928278D01*
X1303290Y926992D01*
X1302594D01*
X1302358Y927228D01*
X1302266D01*
G01X1352771Y947509D02*
X1354002D01*
X1354228Y947283D01*
G02X1353543Y946252I-1458J225D01*
G01X1353508Y946232D01*
G02X1352034I-737J1277D01*
G03X1349866Y946266I-1115J-1928D01*
G01X1349808Y946232D01*
G02X1348334I-737J1277D01*
G03X1346166Y946266I-1115J-1928D01*
G01X1346108Y946232D01*
G02X1344634I-737J1277D01*
G03X1342466Y946266I-1115J-1928D01*
G01X1342408Y946232D01*
G02X1340934I-737J1277D01*
G03X1338766Y946266I-1115J-1928D01*
G01X1338708Y946232D01*
G02X1337234I-737J1277D01*
G03X1335048Y946256I-1114J-1928D01*
G01X1335007Y946232D01*
G02X1333533I-737J1277D01*
G01X1333492Y946256D01*
G03X1331308Y946232I-1071J-1952D01*
G02X1329834I-737J1277D01*
G03X1327666Y946266I-1115J-1928D01*
G01X1327608Y946232D01*
G02X1326134I-737J1277D01*
G03X1323966Y946266I-1115J-1928D01*
G01X1323908Y946232D01*
X1323875Y946213D01*
G02X1322433Y946232I-704J1296D01*
G03X1320245Y946256I-1115J-1928D01*
G01X1320204Y946232D01*
G02X1318764Y946213I-737J1277D01*
G01X1318731Y946232D01*
X1318649Y946280D01*
G03X1316505Y946232I-1028J-1976D01*
G02X1315076Y946205I-739J1277D01*
G01X1315029Y946232D01*
X1314988Y946256D01*
G03X1312802Y946232I-1072J-1952D01*
G02X1311328I-737J1277D01*
G01X1311287Y946256D01*
G03X1309101Y946232I-1072J-1952D01*
G03X1308640Y945879I1112J-1930D01*
G01X1306936Y944175D01*
X1306168Y942322D01*
X1304008Y940162D01*
X1303266D01*
G01X1352771Y941100D02*
G03X1350231Y942999I-9569J-10151D01*
G01X1350183Y943027D01*
G03X1347957I-1113J-1927D01*
G02X1346483I-737J1277D01*
G01X1346425Y943061D01*
G03X1344257Y943027I-1054J-1961D01*
G02X1342783I-737J1277D01*
G01X1342725Y943061D01*
G03X1340557Y943027I-1054J-1961D01*
G02X1339083I-737J1277D01*
G01X1339025Y943061D01*
G03X1336857Y943027I-1054J-1961D01*
G02X1335383I-737J1277D01*
G01X1335342Y943051D01*
G03X1333158Y943027I-1071J-1951D01*
G02X1331684I-737J1277D01*
G01X1331643Y943051D01*
G03X1329457Y943027I-1072J-1951D01*
G02X1327983I-737J1277D01*
G01X1327925Y943061D01*
G03X1325757Y943027I-1054J-1961D01*
G02X1324283I-737J1277D01*
G01X1324225Y943061D01*
G03X1322057Y943027I-1054J-1961D01*
G02X1320583I-737J1277D01*
G01X1320525Y943061D01*
G03X1318357Y943027I-1054J-1961D01*
G02X1316883I-737J1277D01*
G01X1316825Y943061D01*
G03X1314657Y943027I-1054J-1961D01*
G02X1313183I-737J1277D01*
G01X1313125Y943061D01*
G03X1310957Y943027I-1054J-1961D01*
G03X1309846Y941161I1114J-1927D01*
G01Y941100D01*
X1309847D01*
Y941069D01*
G02X1308371Y939625I-1476J32D01*
G01X1306447D01*
X1303489Y936667D01*
Y935417D01*
X1303140Y935068D01*
X1302266D01*
G01X1350920Y937896D02*
G03X1348333Y939823I-9531J-10095D01*
G03X1346149Y939847I-1113J-1927D01*
G01X1346108Y939823D01*
G02X1344634I-737J1277D01*
G03X1342466Y939857I-1114J-1927D01*
G01X1342408Y939823D01*
G02X1340934I-737J1277D01*
G03X1338766Y939857I-1114J-1927D01*
G01X1338708Y939823D01*
G02X1337234I-737J1277D01*
G03X1335008I-1113J-1927D01*
G02X1333534I-737J1277D01*
G03X1331366Y939857I-1114J-1927D01*
G01X1331308Y939823D01*
G02X1329834I-737J1277D01*
G03X1327666Y939857I-1114J-1927D01*
G01X1327608Y939823D01*
G02X1326134I-737J1277D01*
G03X1323966Y939857I-1114J-1927D01*
G01X1323908Y939823D01*
G02X1322434I-737J1277D01*
G03X1320208I-1113J-1927D01*
G02X1318734I-737J1277D01*
G01X1318676Y939857D01*
G03X1316508Y939823I-1054J-1961D01*
G02X1315034I-737J1277D01*
G01X1314976Y939857D01*
G03X1312808Y939823I-1054J-1961D01*
G03X1311697Y937957I1114J-1927D01*
G01Y937896D01*
G02X1311007Y936647I-1475J0D01*
G01X1310958Y936619D01*
X1310911Y936592D01*
G02X1309484Y936619I-689J1304D01*
G03X1308370Y936918I-1114J-1926D01*
G01X1306113D01*
X1305162Y935967D01*
Y934184D01*
X1303306Y932328D01*
Y931497D01*
X1302957Y931148D01*
X1302266D01*
G01X1350920Y950713D02*
G02X1348895Y949729I-2435J2435D01*
G01X1348805Y949718D01*
G03X1347958Y949436I265J-2209D01*
G02X1346484I-737J1277D01*
G01X1346443Y949460D01*
G03X1344257Y949436I-1072J-1951D01*
G02X1342783I-737J1277D01*
G01X1342725Y949470D01*
G03X1340557Y949436I-1054J-1961D01*
G02X1339083I-737J1277D01*
G01X1339025Y949470D01*
G03X1336857Y949436I-1054J-1961D01*
G02X1335383I-737J1277D01*
G03X1333157I-1113J-1927D01*
G02X1331683I-737J1277D01*
G01X1331625Y949470D01*
G03X1329457Y949436I-1054J-1961D01*
G02X1327983I-737J1277D01*
G01X1327925Y949470D01*
G03X1325757Y949436I-1054J-1961D01*
G02X1324283I-737J1277D01*
G01X1324242Y949460D01*
G03X1322058Y949436I-1071J-1951D01*
G02X1320584I-737J1277D01*
G03X1318358I-1113J-1927D01*
G02X1316884I-737J1277D01*
G01X1316843Y949460D01*
G03X1314657Y949436I-1072J-1951D01*
G02X1313183I-737J1277D01*
G01X1313125Y949470D01*
G03X1310957Y949436I-1054J-1961D01*
G02X1310221Y949237I-740J1277D01*
G01X1309124D01*
X1305158Y945271D01*
Y944845D01*
X1304438Y944125D01*
X1303266D01*
G01X1349071Y953917D02*
X1348946Y954373D01*
X1348793Y954460D01*
G03X1348184Y954621I-609J-1071D01*
G01X1347107D01*
X1346110Y955195D01*
X1346109Y955194D01*
G03X1344635I-737J-1277D01*
G01X1344634D01*
G02X1342466Y955160I-1115J1928D01*
G01X1342408Y955194D01*
G03X1340934I-737J-1277D01*
G02X1338766Y955160I-1115J1928D01*
G01X1338708Y955194D01*
Y955195D01*
G03X1337269Y955215I-737J-1277D01*
G01X1337235Y955196D01*
G02X1335006I-1115J1926D01*
G01X1334974Y955215D01*
G03X1333532Y955195I-703J-1297D01*
G02X1331305Y955196I-1113J1927D01*
G01X1331259Y955224D01*
G03X1329833Y955195I-687J-1306D01*
G02X1327605Y955196I-1113J1927D01*
G01X1327559Y955224D01*
G03X1326133Y955195I-687J-1306D01*
G02X1323905Y955196I-1113J1927D01*
G01X1323873Y955215D01*
G03X1322433Y955195I-702J-1297D01*
G01X1322435Y955194D01*
G02X1320207I-1114J1928D01*
G03X1318733I-737J-1277D01*
G01X1318692Y955170D01*
G02X1316508Y955194I-1071J1952D01*
G03X1315034I-737J-1277D01*
G01X1314993Y955170D01*
G02X1312807Y955194I-1072J1952D01*
G03X1311333I-737J-1277D01*
G01X1311275Y955160D01*
G02X1309107Y955194I-1053J1962D01*
G03X1307633I-737J-1277D01*
G03X1307326Y954961I731J-1282D01*
G01X1306867Y954502D01*
Y951845D01*
X1304575Y949553D01*
X1303593D01*
X1303358Y949318D01*
X1303266D01*
G01X1352771Y953917D02*
G02X1351431Y954271I-1J2708D01*
G01X1349757Y955223D01*
G03X1348952Y955387I-648J-1121D01*
G01X1348727Y955360D01*
X1348708Y955370D01*
X1347308D01*
X1346428Y955877D01*
G03X1344258Y955844I-1055J-1960D01*
G01X1344257Y955845D01*
G02X1342783I-737J1277D01*
G01X1342725Y955879D01*
G03X1340557Y955845I-1053J-1962D01*
G02X1339083I-737J1277D01*
G03X1336899Y955869I-1113J-1927D01*
G01X1336858Y955845D01*
G02X1335384I-737J1277D01*
G01X1335343Y955869D01*
G03X1333157Y955845I-1072J-1951D01*
G02X1331683I-737J1277D01*
G01X1331625Y955879D01*
G03X1329457Y955845I-1054J-1961D01*
G02X1327983I-737J1277D01*
G01X1327925Y955879D01*
G03X1325757Y955845I-1054J-1961D01*
G02X1324283I-737J1277D01*
G01X1324242Y955869D01*
G03X1322058Y955845I-1071J-1951D01*
G02X1320584I-737J1277D01*
G03X1318416Y955879I-1115J-1928D01*
G01X1318358Y955845D01*
G02X1316884I-737J1277D01*
G03X1314658I-1113J-1928D01*
G02X1313184I-737J1277D01*
G03X1311016Y955879I-1115J-1928D01*
G01X1310958Y955845D01*
G02X1309484I-737J1277D01*
G03X1306796Y955491I-1113J-1928D01*
G01X1306118Y954813D01*
Y952156D01*
X1304264Y950302D01*
X1303594D01*
X1303358Y950538D01*
X1303266D01*
G01X1352771Y960326D02*
X1352612Y960167D01*
X1351455D01*
X1351296Y960326D01*
G03X1350231Y962225I-2226J0D01*
G01X1350183Y962253D01*
G03X1347957I-1113J-1927D01*
G02X1346483I-737J1277D01*
G01X1346425Y962287D01*
G03X1344257Y962253I-1054J-1961D01*
G02X1342783I-737J1277D01*
G01X1342742Y962277D01*
G03X1340558Y962253I-1071J-1951D01*
G02X1339084I-737J1277D01*
G01X1339043Y962277D01*
G03X1336857Y962253I-1072J-1951D01*
G02X1335383I-737J1277D01*
G01X1335342Y962277D01*
G03X1333158Y962253I-1071J-1951D01*
G02X1331684I-737J1277D01*
G01X1331643Y962277D01*
G03X1329457Y962253I-1072J-1951D01*
G02X1327983I-737J1277D01*
G01X1327925Y962287D01*
G03X1325757Y962253I-1054J-1961D01*
G02X1324283I-737J1277D01*
G01X1324225Y962287D01*
G03X1322057Y962253I-1054J-1961D01*
G02X1320583I-737J1277D01*
G03X1318357I-1113J-1927D01*
G02X1316883I-737J1277D01*
G03X1314657I-1113J-1927D01*
G02X1313183I-737J1277D01*
G03X1310957I-1113J-1927D01*
G02X1309483I-737J1277D01*
G03X1307734Y962459I-1114J-1927D01*
G01X1303266D01*
G01X1350920Y957122D02*
X1350919D01*
G03X1348744Y958807I-7720J-7719D01*
G01X1348333Y959049D01*
X1348310Y959062D01*
G03X1346108Y959049I-1090J-1940D01*
G02X1344656Y959036I-737J1277D01*
G01X1344610Y959062D01*
G03X1342408Y959049I-1090J-1940D01*
G02X1340956Y959036I-737J1277D01*
G01X1340910Y959062D01*
G03X1338708Y959049I-1090J-1940D01*
G02X1337256Y959036I-737J1277D01*
G01X1337210Y959062D01*
G03X1335008Y959049I-1090J-1940D01*
G02X1333556Y959036I-737J1277D01*
G01X1333510Y959062D01*
G03X1331308Y959049I-1090J-1940D01*
G02X1329856Y959036I-737J1277D01*
G01X1329810Y959062D01*
G03X1327608Y959049I-1090J-1940D01*
G02X1326156Y959036I-737J1277D01*
G01X1326133Y959049D01*
X1326115Y959059D01*
G03X1323908Y959049I-1095J-1937D01*
G02X1322434I-737J1277D01*
G01X1322393Y959073D01*
G03X1320207Y959049I-1072J-1951D01*
G02X1318733I-737J1277D01*
G01X1318675Y959083D01*
G03X1316507Y959049I-1054J-1961D01*
G02X1315033I-737J1277D01*
G01X1314975Y959083D01*
G03X1312807Y959049I-1054J-1961D01*
G02X1311333I-737J1277D01*
G01X1311275Y959083D01*
G03X1309107Y959049I-1054J-1961D01*
G02X1307633I-737J1277D01*
G01X1307280Y959253D01*
X1306738D01*
X1305902Y958417D01*
X1303266D01*
G01X1353204Y999684D02*
X1354436D01*
X1354661Y999459D01*
G02X1353989Y998435I-1458J224D01*
G01X1353940Y998407D01*
X1353893Y998380D01*
G02X1352466Y998407I-689J1304D01*
G03X1350298Y998441I-1114J-1927D01*
G01X1350240Y998407D01*
G02X1348766I-737J1277D01*
G02X1348029Y999650I737J1277D01*
G01Y999684D01*
G03X1346940Y1001597I-2225J0D01*
G01X1346916Y1001611D01*
X1346858Y1001645D01*
G03X1344690Y1001611I-1054J-1961D01*
G02X1343216I-737J1277D01*
G01X1343158Y1001645D01*
G03X1340990Y1001611I-1054J-1961D01*
G02X1339516I-737J1277D01*
G01X1339475Y1001635D01*
G03X1337291Y1001611I-1071J-1951D01*
G02X1335817I-737J1277D01*
G01X1335776Y1001635D01*
G03X1333590Y1001611I-1072J-1951D01*
G02X1332116I-737J1277D01*
G03X1329890I-1113J-1927D01*
G02X1328416I-737J1277D01*
G03X1326190I-1113J-1927D01*
G02X1324716I-737J1277D01*
G03X1322490I-1113J-1927D01*
G02X1321016I-737J1277D01*
G03X1318790I-1113J-1927D01*
G02X1317316I-737J1277D01*
G03X1315090I-1113J-1927D01*
G03X1314837Y1001441I1112J-1928D01*
G03X1313807Y1000535I6487J-8413D01*
G01X1310845Y997571D01*
X1308563D01*
G01X1356904Y999684D02*
X1355672D01*
X1355414Y999426D01*
G02X1354340Y997771I-2210J258D01*
G01X1354316Y997757D01*
X1354258Y997723D01*
G02X1352090Y997757I-1054J1961D01*
G03X1350648Y997776I-738J-1277D01*
G01X1350615Y997757D01*
X1350557Y997723D01*
G02X1348389Y997757I-1054J1961D01*
G02X1347278Y999623I1114J1927D01*
G01Y999718D01*
G03X1346541Y1000961I-1474J-34D01*
G03X1345067I-737J-1277D01*
G02X1342899Y1000927I-1114J1927D01*
G01X1342841Y1000961D01*
G03X1341367I-737J-1277D01*
G02X1339199Y1000927I-1114J1927D01*
G01X1339141Y1000961D01*
G03X1337667I-737J-1277D01*
G02X1335441I-1113J1927D01*
G03X1333967I-737J-1277D01*
G02X1331781Y1000937I-1114J1927D01*
G01X1331740Y1000961D01*
G03X1330266I-737J-1277D01*
G02X1328040I-1113J1927D01*
G03X1326566I-737J-1277D01*
G02X1324340I-1113J1927D01*
G03X1322866I-737J-1277D01*
G02X1320640I-1113J1927D01*
G03X1319166I-737J-1277D01*
G02X1316940I-1113J1927D01*
G03X1315466I-737J-1277D01*
G03X1315159Y1000728I731J-1282D01*
G01X1310036Y995605D01*
X1308563D01*
G01X1351353Y1022114D02*
X1349129Y1020399D01*
X1348766Y1020187D01*
G02X1346582Y1020163I-1113J1927D01*
G01X1346541Y1020187D01*
G03X1345067I-737J-1277D01*
G02X1342899Y1020153I-1114J1927D01*
G01X1342841Y1020187D01*
G03X1341367I-737J-1277D01*
G02X1339199Y1020153I-1114J1927D01*
G01X1339141Y1020187D01*
G03X1337667I-737J-1277D01*
G02X1335441I-1113J1927D01*
G03X1333967I-737J-1277D01*
G02X1331781Y1020163I-1114J1927D01*
G01X1331740Y1020187D01*
G03X1330266I-737J-1277D01*
G02X1328040I-1113J1927D01*
G03X1326566I-737J-1277D01*
G02X1324340I-1113J1927D01*
G03X1322866I-737J-1277D01*
G02X1320640I-1113J1927D01*
G03X1319166I-737J-1277D01*
G02X1316940I-1113J1927D01*
G03X1315466I-737J-1277D01*
G02X1313240I-1113J1927D01*
G03X1311766I-737J-1277D01*
G02X1309540I-1113J1927D01*
G03X1308541Y1020361I-737J-1277D01*
G01X1306401D01*
X1304086Y1022676D01*
X1303263D01*
G01X1353204Y1018910D02*
X1354435D01*
X1354661Y1019136D01*
G03X1353976Y1020167I-1458J-225D01*
G01X1353941Y1020187D01*
G03X1352467I-737J-1277D01*
G01X1352432Y1020167D01*
G03X1351729Y1018910I772J-1257D01*
G01Y1018880D01*
G02X1350616Y1016982I-2226J30D01*
G02X1348390I-1113J1928D01*
G03X1346916I-737J-1277D01*
G01X1346858Y1016948D01*
G02X1344690Y1016982I-1053J1962D01*
G03X1343216I-737J-1277D01*
G01X1343175Y1016958D01*
G02X1340991Y1016982I-1071J1952D01*
G03X1339517I-737J-1277D01*
G01X1339476Y1016958D01*
G02X1337290Y1016982I-1072J1952D01*
G03X1335816I-737J-1277D01*
G01X1335775Y1016958D01*
G02X1333591Y1016982I-1071J1952D01*
G03X1332117I-737J-1277D01*
G02X1329931Y1016958I-1114J1928D01*
G01X1329890Y1016982D01*
G03X1328416I-737J-1277D01*
G02X1326190I-1113J1928D01*
G03X1324716I-737J-1277D01*
G02X1322490I-1113J1928D01*
G03X1321016I-737J-1277D01*
G02X1318790I-1113J1928D01*
G03X1317316I-737J-1277D01*
G02X1315090I-1113J1928D01*
G03X1313616I-737J-1277D01*
G02X1311390I-1113J1928D01*
G03X1309916I-737J-1277D01*
G02X1307690I-1113J1928D01*
G03X1306953Y1017182I-742J-1276D01*
G01X1306485D01*
X1305030Y1018637D01*
X1303263D01*
G01X1351353Y1028523D02*
G02X1348390Y1029800I3974J13297D01*
G03X1346916I-737J-1277D01*
G01X1346858Y1029766D01*
G02X1344690Y1029800I-1054J1961D01*
G03X1343216I-737J-1277D01*
G01X1343158Y1029766D01*
G02X1340990Y1029800I-1054J1961D01*
G03X1339516I-737J-1277D01*
G01X1339458Y1029766D01*
G02X1337290Y1029800I-1054J1961D01*
G03X1335816I-737J-1277D01*
G02X1333590I-1113J1927D01*
G03X1332116I-737J-1277D01*
G02X1329890I-1113J1927D01*
G03X1328459Y1029824I-737J-1277D01*
G01X1328416Y1029799D01*
X1328358Y1029765D01*
G02X1326190Y1029799I-1054J1961D01*
G01X1326147Y1029824D01*
G03X1324716Y1029800I-694J-1301D01*
G02X1322490I-1113J1927D01*
G03X1321016I-737J-1277D01*
G02X1318790I-1113J1927D01*
G03X1317316I-737J-1277D01*
G02X1315090I-1113J1927D01*
G03X1313616I-737J-1277D01*
G02X1311390I-1113J1927D01*
G03X1309916I-737J-1277D01*
G02X1307690I-1113J1927D01*
G03X1306953Y1029999I-740J-1276D01*
G01X1306059D01*
X1302997Y1033061D01*
X1301568D01*
G01X1353204Y1025318D02*
G03X1351862Y1024964I0J-2721D01*
G01X1350188Y1024012D01*
G02X1349383Y1023848I-648J1121D01*
G01X1349158Y1023875D01*
X1349139Y1023865D01*
X1347739D01*
X1346859Y1023358D01*
G02X1344689Y1023391I-1055J1960D01*
G01X1344690D01*
G03X1343216I-737J-1277D01*
G01X1343158Y1023357D01*
G02X1340990Y1023391I-1054J1961D01*
G03X1339516I-737J-1277D01*
G02X1337332Y1023367I-1113J1927D01*
G01X1337291Y1023391D01*
G03X1335817I-737J-1277D01*
G01X1335776Y1023367D01*
G02X1333590Y1023391I-1072J1951D01*
G03X1332116I-737J-1277D01*
G01X1332058Y1023357D01*
G02X1329890Y1023391I-1054J1961D01*
G03X1328416I-737J-1277D01*
G01X1328358Y1023357D01*
G02X1326190Y1023391I-1054J1961D01*
G03X1324716I-737J-1277D01*
G02X1322490I-1113J1927D01*
G03X1321016I-737J-1277D01*
G02X1318790I-1113J1927D01*
G03X1317316I-737J-1277D01*
G02X1315090I-1113J1927D01*
G03X1313616I-737J-1277D01*
G02X1311390I-1113J1927D01*
G03X1309916I-737J-1277D01*
G02X1307690I-1113J1927D01*
G02X1307437Y1023561I1112J1928D01*
G02X1307230Y1023742I1359J1763D01*
G01X1306827Y1024141D01*
X1306144D01*
X1303387Y1026898D01*
X1301895D01*
X1301659Y1026662D01*
X1301567D01*
G01X1349502Y1025318D02*
X1349377Y1024862D01*
X1349224Y1024775D01*
G02X1348615Y1024614I-609J1071D01*
G01X1347538D01*
X1346541Y1024040D01*
X1346540Y1024041D01*
G02X1345066I-737J1277D01*
G01X1345067D01*
G03X1342899Y1024075I-1114J-1927D01*
G01X1342841Y1024041D01*
G02X1341367I-737J1277D01*
G03X1339181Y1024065I-1114J-1927D01*
G01X1339140Y1024041D01*
G02X1337666I-737J1277D01*
G01X1337625Y1024065D01*
G03X1335441Y1024041I-1071J-1951D01*
G02X1333967I-737J1277D01*
G03X1331799Y1024075I-1114J-1927D01*
G01X1331741Y1024041D01*
G02X1330267I-737J1277D01*
G03X1328099Y1024075I-1114J-1927D01*
G01X1328041Y1024041D01*
G02X1326567I-737J1277D01*
G03X1324381Y1024065I-1114J-1927D01*
G01X1324340Y1024041D01*
G02X1322866I-737J1277D01*
G03X1320640I-1113J-1927D01*
G02X1319166I-737J1277D01*
G03X1316940I-1113J-1927D01*
G02X1315466I-737J1277D01*
G03X1313240I-1113J-1927D01*
G02X1311766I-737J1277D01*
G03X1309540I-1113J-1927D01*
G02X1308066I-737J1277D01*
G02X1307759Y1024274I731J1282D01*
G01X1307757Y1024275D01*
X1307136Y1024890D01*
X1306455D01*
X1303698Y1027647D01*
X1301894D01*
X1301659Y1027882D01*
X1301567D01*
G01X1353204Y1031727D02*
X1354435D01*
X1354661Y1031953D01*
G03X1353976Y1032984I-1458J-225D01*
G01X1353941Y1033004D01*
G03X1352467I-737J-1277D01*
G02X1350299Y1032970I-1114J1927D01*
G01X1350241Y1033004D01*
G03X1348767I-737J-1277D01*
G02X1346599Y1032970I-1114J1927D01*
G01X1346541Y1033004D01*
G03X1345067I-737J-1277D01*
G02X1342899Y1032970I-1114J1927D01*
G01X1342841Y1033004D01*
G03X1341367I-737J-1277D01*
G02X1339199Y1032970I-1114J1927D01*
G01X1339141Y1033004D01*
G03X1337667I-737J-1277D01*
G02X1335481Y1032980I-1114J1927D01*
G01X1335440Y1033004D01*
G03X1333966I-737J-1277D01*
G01X1333908Y1032970D01*
G02X1331740Y1033004I-1054J1961D01*
G03X1330266I-737J-1277D01*
G02X1328040I-1113J1927D01*
G03X1326566I-737J-1277D01*
G01X1326567D01*
G02X1324381Y1032980I-1114J1927D01*
G01X1324340Y1033004D01*
G03X1322866I-737J-1277D01*
G02X1320640I-1113J1927D01*
G03X1319166I-737J-1277D01*
G02X1316940I-1113J1927D01*
G03X1315466I-737J-1277D01*
G02X1313240I-1113J1927D01*
G03X1311766I-737J-1277D01*
G02X1309540I-1113J1927D01*
G03X1308875Y1033200I-738J-1277D01*
G02X1307903Y1033630I70J1473D01*
G01X1304499Y1037034D01*
X1301568D01*
G01X1351353Y1041340D02*
X1349892Y1040943D01*
X1348390Y1040063D01*
G02X1346916I-737J1277D01*
G01X1346858Y1040097D01*
G03X1344690Y1040063I-1054J-1961D01*
G02X1343216I-737J1277D01*
G01X1343158Y1040097D01*
G03X1340990Y1040063I-1054J-1961D01*
G02X1339516I-737J1277D01*
G01X1339475Y1040087D01*
G03X1337291Y1040063I-1071J-1951D01*
G02X1335817I-737J1277D01*
G01X1335776Y1040087D01*
G03X1333590Y1040063I-1072J-1951D01*
G02X1332116I-737J1277D01*
G03X1329890I-1113J-1927D01*
G02X1328416I-737J1277D01*
G03X1326190I-1113J-1927D01*
G02X1324716I-737J1277D01*
G03X1322490I-1113J-1927D01*
G02X1321016I-737J1277D01*
G03X1318790I-1113J-1927D01*
G02X1317316I-737J1277D01*
G03X1315090I-1113J-1927D01*
G02X1313616I-737J1277D01*
G03X1311390I-1113J-1927D01*
G02X1309916I-737J1277D01*
G02X1309609Y1040296I731J1282D01*
G01X1308873Y1041032D01*
Y1042339D01*
X1307285Y1043927D01*
Y1046341D01*
X1305052Y1048574D01*
X1303068D01*
G01X1353204Y1038136D02*
X1354435D01*
X1354661Y1037909D01*
G02X1353941Y1036858I-1458J226D01*
G02X1352489Y1036845I-737J1277D01*
G01X1352466Y1036858D01*
X1352443Y1036872D01*
G03X1350241Y1036858I-1089J-1941D01*
G02X1348789Y1036845I-737J1277D01*
G01X1348766Y1036858D01*
X1348743Y1036872D01*
G03X1346541Y1036858I-1089J-1941D01*
G02X1345089Y1036845I-737J1277D01*
G01X1345066Y1036858D01*
X1345043Y1036872D01*
G03X1342841Y1036858I-1089J-1941D01*
G02X1341389Y1036845I-737J1277D01*
G01X1341366Y1036858D01*
X1341343Y1036872D01*
G03X1339141Y1036858I-1089J-1941D01*
G02X1337689Y1036845I-737J1277D01*
G01X1337666Y1036858D01*
X1337643Y1036872D01*
G03X1335441Y1036858I-1089J-1941D01*
G02X1333989Y1036845I-737J1277D01*
G01X1333966Y1036858D01*
X1333943Y1036872D01*
G03X1331741Y1036858I-1089J-1941D01*
G02X1330283Y1036848I-738J1277D01*
G01X1330266Y1036858D01*
G03X1328041I-1112J-1927D01*
G02X1326581Y1036850I-737J1278D01*
G01X1326566Y1036858D01*
X1326543Y1036872D01*
G03X1324341Y1036858I-1089J-1941D01*
G01X1324340Y1036859D01*
G02X1322866I-737J1277D01*
G03X1320640I-1113J-1928D01*
G02X1319166I-737J1277D01*
G03X1316940I-1113J-1928D01*
G02X1315466I-737J1277D01*
G03X1313240I-1113J-1928D01*
G02X1311766I-737J1277D01*
G03X1310177Y1037106I-1113J-1928D01*
G02X1308128Y1037707I-475J2175D01*
G01X1307715Y1038120D01*
Y1039831D01*
X1305481Y1042065D01*
Y1043396D01*
X1304655Y1044222D01*
X1303068D01*
G01X1351353Y1047749D02*
X1351352D01*
X1350689Y1048412D01*
G03X1349888Y1049027I-2740J-2740D01*
G01X1348767Y1049675D01*
Y1049676D01*
G03X1346599Y1049710I-1114J-1927D01*
G01X1346541Y1049676D01*
G02X1345067I-737J1276D01*
G03X1342899Y1049710I-1114J-1927D01*
G01X1342841Y1049676D01*
G02X1341367I-737J1276D01*
G03X1339199Y1049710I-1114J-1927D01*
G01X1339141Y1049676D01*
G02X1337667I-737J1276D01*
G03X1335481Y1049700I-1114J-1927D01*
G01X1335440Y1049676D01*
G02X1333966I-737J1276D01*
G03X1331740I-1113J-1927D01*
G02X1330266I-737J1276D01*
G03X1328040I-1113J-1927D01*
G02X1326566I-737J1276D01*
G03X1324340I-1113J-1927D01*
G02X1322866I-737J1276D01*
G03X1320640I-1113J-1927D01*
G02X1319166I-737J1276D01*
G03X1316940I-1113J-1927D01*
G02X1315466I-737J1276D01*
G03X1313240I-1113J-1927D01*
G02X1311766I-737J1276D01*
G01X1311710Y1049708D01*
G02X1311028Y1050952I794J1244D01*
G01Y1051025D01*
G03X1309916Y1052880I-2225J-73D01*
G02X1309609Y1053113I731J1282D01*
G01Y1055415D01*
X1305668Y1059356D01*
X1303068D01*
G01X1349504Y1044544D02*
X1349379Y1045000D01*
X1349226Y1045087D01*
G03X1348617Y1045248I-609J-1071D01*
G01X1347540D01*
X1346543Y1045822D01*
X1346542Y1045821D01*
G03X1345068I-737J-1277D01*
G01X1345067D01*
G02X1342899Y1045787I-1115J1928D01*
G01X1342841Y1045821D01*
G03X1341367I-737J-1277D01*
G02X1339181Y1045797I-1114J1927D01*
G01X1339140Y1045821D01*
G03X1337666I-737J-1277D01*
G02X1335482Y1045797I-1113J1927D01*
G01X1335441Y1045821D01*
G03X1333967I-737J-1277D01*
G02X1331781Y1045797I-1114J1927D01*
G01X1331740Y1045821D01*
G03X1330266I-737J-1277D01*
G02X1328040I-1113J1927D01*
G03X1326566I-737J-1277D01*
G02X1324340I-1113J1927D01*
G03X1322866I-737J-1277D01*
G02X1320640I-1113J1928D01*
G03X1319166I-737J-1277D01*
G02X1316940I-1113J1928D01*
G03X1315466I-737J-1277D01*
G02X1312779Y1046175I-1113J1928D01*
G01X1311934Y1047020D01*
X1310652D01*
X1307049Y1050623D01*
Y1052614D01*
X1305684Y1053979D01*
X1303395D01*
X1303160Y1053744D01*
X1303068D01*
G01X1353204Y1044544D02*
G02X1351864Y1044898I-1J2708D01*
G01X1350190Y1045850D01*
G03X1349385Y1046014I-648J-1121D01*
G01X1349160Y1045987D01*
X1349141Y1045997D01*
X1347741D01*
X1346861Y1046504D01*
G03X1344691Y1046471I-1055J-1960D01*
G01X1344690Y1046472D01*
G02X1343216I-737J1277D01*
G01X1343158Y1046506D01*
G03X1340990Y1046472I-1053J-1962D01*
G01Y1046471D01*
G02X1339516I-737J1277D01*
G03X1337290I-1113J-1927D01*
G02X1335816I-737J1277D01*
G01X1335758Y1046505D01*
G03X1333590Y1046471I-1054J-1961D01*
G02X1332116I-737J1277D01*
G03X1329890I-1113J-1927D01*
G02X1328416I-737J1277D01*
G03X1326190I-1113J-1927D01*
G02X1324716I-737J1277D01*
G01Y1046472D01*
G03X1322490I-1113J-1928D01*
G02X1321016I-737J1277D01*
G03X1318790I-1113J-1928D01*
G02X1317316I-737J1277D01*
G03X1315090I-1113J-1928D01*
G02X1313616I-737J1277D01*
G02X1313309Y1046705I731J1282D01*
G01X1312245Y1047769D01*
X1310963D01*
X1307798Y1050934D01*
Y1052925D01*
X1305995Y1054728D01*
X1303396D01*
X1303160Y1054964D01*
X1303068D01*
G01X1353204Y1050952D02*
G03X1352406Y1052399I-1709J1D01*
G01X1352392Y1052408D01*
G03X1352060Y1052522I-407J-646D01*
G01X1351333Y1052594D01*
G02X1350995Y1052688I101J1017D01*
G01X1350730Y1052815D01*
X1350616Y1052880D01*
X1350558Y1052914D01*
G03X1348390Y1052880I-1053J-1962D01*
G02X1346916I-737J1277D01*
G01X1346858Y1052914D01*
G03X1344690Y1052880I-1053J-1962D01*
G02X1343216I-737J1277D01*
G01X1343158Y1052914D01*
G03X1340990Y1052880I-1053J-1962D01*
G02X1339516I-737J1277D01*
G01X1339458Y1052914D01*
G03X1337290Y1052880I-1053J-1962D01*
G02X1335816I-737J1277D01*
G03X1333632Y1052904I-1113J-1928D01*
G01X1333591Y1052880D01*
G02X1332117I-737J1277D01*
G03X1329931Y1052904I-1114J-1928D01*
G01X1329890Y1052880D01*
G02X1328416I-737J1277D01*
G03X1326190I-1113J-1928D01*
G02X1324716I-737J1277D01*
G03X1322490I-1113J-1928D01*
G02X1321016I-737J1277D01*
G03X1318790I-1113J-1928D01*
G02X1317316I-737J1277D01*
G03X1315090I-1113J-1928D01*
G02X1313616I-737J1277D01*
G01X1313581Y1052900D01*
G02X1312878Y1054157I772J1257D01*
G01Y1054196D01*
G03X1311766Y1056084I-2225J-39D01*
G02X1311459Y1056317I731J1282D01*
G01X1306583Y1061193D01*
Y1062942D01*
X1306045Y1063480D01*
X1304264D01*
G01X1353204Y1057361D02*
X1354435D01*
X1354661Y1057135D01*
G02X1353976Y1056104I-1458J225D01*
G01X1353941Y1056084D01*
G02X1352467I-737J1277D01*
G03X1350281Y1056108I-1114J-1927D01*
G01X1350240Y1056084D01*
G02X1348766I-737J1277D01*
G03X1346582Y1056108I-1113J-1927D01*
G01X1346541Y1056084D01*
G02X1345067I-737J1277D01*
G03X1342899Y1056118I-1114J-1927D01*
G01X1342841Y1056084D01*
G02X1341367I-737J1277D01*
G03X1339199Y1056118I-1114J-1927D01*
G01X1339141Y1056084D01*
G02X1337667I-737J1277D01*
G03X1335499Y1056118I-1114J-1927D01*
G01X1335441Y1056084D01*
G02X1333967I-737J1277D01*
G01X1333926Y1056108D01*
G03X1331740Y1056084I-1072J-1951D01*
G02X1330266I-737J1277D01*
G03X1328040I-1113J-1927D01*
G02X1326566I-737J1277D01*
G03X1324340I-1113J-1927D01*
G02X1322866I-737J1277D01*
G03X1320640I-1113J-1927D01*
G02X1319166I-737J1277D01*
G03X1316940I-1113J-1927D01*
G02X1315466I-737J1277D01*
G01X1315431Y1056104D01*
G02X1314728Y1057361I772J1257D01*
G01Y1057400D01*
G03X1313616Y1059288I-2225J-39D01*
G02X1313309Y1059521I731J1282D01*
G01X1311561Y1061269D01*
X1309223D01*
X1308377Y1062115D01*
Y1064811D01*
X1305448Y1067740D01*
Y1068293D01*
X1305099Y1068642D01*
X1304264D01*
G01X1351353Y1060565D02*
X1349892Y1060168D01*
X1348390Y1059288D01*
G02X1346916I-737J1277D01*
G01X1346858Y1059322D01*
G03X1344690Y1059288I-1054J-1961D01*
G02X1343216I-737J1277D01*
G01X1343158Y1059322D01*
G03X1340990Y1059288I-1054J-1961D01*
G02X1339516I-737J1277D01*
G01X1339475Y1059312D01*
G03X1337291Y1059288I-1071J-1951D01*
G02X1335817I-737J1277D01*
G01X1335776Y1059312D01*
G03X1333590Y1059288I-1072J-1951D01*
G02X1332116I-737J1277D01*
G03X1329890I-1113J-1927D01*
G02X1328416I-737J1277D01*
G03X1326190I-1113J-1927D01*
G02X1324716I-737J1277D01*
G03X1322490I-1113J-1927D01*
G02X1321016I-737J1277D01*
G03X1318790I-1113J-1927D01*
G02X1317316I-737J1277D01*
G01X1317281Y1059308D01*
G02X1316578Y1060565I772J1257D01*
G01Y1060638D01*
G03X1315466Y1062493I-2225J-73D01*
G02X1315159Y1062726I731J1282D01*
G01X1314216Y1063669D01*
X1312823D01*
X1311064Y1065428D01*
X1310072D01*
X1307025Y1068475D01*
Y1070775D01*
X1304960Y1072840D01*
X1304264D01*
G01X1349504Y1063770D02*
X1349379Y1064226D01*
X1349226Y1064313D01*
G03X1348617Y1064474I-609J-1071D01*
G01X1347540D01*
X1346543Y1065048D01*
X1346542Y1065047D01*
G03X1345068I-737J-1277D01*
G01X1345067D01*
G02X1342899Y1065013I-1114J1927D01*
G01X1342841Y1065047D01*
G03X1341367I-737J-1277D01*
G02X1339181Y1065023I-1114J1927D01*
G01X1339140Y1065047D01*
G03X1337666I-737J-1277D01*
G02X1335482Y1065023I-1113J1927D01*
G01X1335441Y1065047D01*
G03X1333967I-737J-1277D01*
G02X1331781Y1065023I-1114J1927D01*
G01X1331740Y1065047D01*
G03X1330266I-737J-1277D01*
G02X1328040I-1113J1927D01*
G03X1326566I-737J-1277D01*
G02X1324340I-1113J1927D01*
G03X1322866I-737J-1277D01*
G02X1319572Y1066528I-1114J1927D01*
G01X1319528Y1066743D01*
Y1066974D01*
G03X1318825Y1068231I-1475J0D01*
G01X1318790Y1068251D01*
G03X1317316I-737J-1277D01*
G01X1317258Y1068217D01*
G02X1315090Y1068251I-1054J1961D01*
G02X1313979Y1070117I1114J1927D01*
G01Y1070178D01*
G03X1313276Y1071435I-1475J0D01*
G03X1312600Y1071626I-676J-1100D01*
G01X1311369D01*
X1308729Y1074266D01*
Y1076135D01*
X1306585Y1078279D01*
X1304591D01*
X1304356Y1078044D01*
X1304264D01*
G01X1353204Y1070178D02*
G03X1352406Y1071625I-1709J1D01*
G01X1352392Y1071634D01*
G03X1352060Y1071748I-407J-646D01*
G01X1351333Y1071820D01*
G02X1350995Y1071914I101J1017D01*
G01X1350730Y1072041D01*
X1350616Y1072106D01*
X1350558Y1072140D01*
G03X1348390Y1072106I-1053J-1962D01*
G02X1346916I-737J1277D01*
G01X1346858Y1072140D01*
G03X1344690Y1072106I-1053J-1962D01*
G02X1343216I-737J1277D01*
G01X1343158Y1072140D01*
G03X1340990Y1072106I-1053J-1962D01*
G02X1339516I-737J1277D01*
G01X1339458Y1072140D01*
G03X1337290Y1072106I-1053J-1962D01*
G02X1335816I-737J1277D01*
G03X1333632Y1072130I-1113J-1928D01*
G01X1333591Y1072106D01*
G02X1332117I-737J1277D01*
G03X1329931Y1072130I-1114J-1928D01*
G01X1329890Y1072106D01*
G02X1328416I-737J1277D01*
G01X1328375Y1072130D01*
G03X1326191Y1072106I-1071J-1952D01*
G02X1324717I-737J1277D01*
G01X1324682Y1072126D01*
G02X1323979Y1073383I772J1257D01*
G03X1322914Y1075282I-2226J0D01*
G01X1322866Y1075310D01*
G03X1320640I-1113J-1927D01*
G02X1319166I-737J1277D01*
G02X1318429Y1076553I737J1277D01*
G01Y1076587D01*
G03X1317340Y1078500I-2225J0D01*
G01X1317316Y1078514D01*
X1317258Y1078548D01*
G03X1315090Y1078514I-1054J-1961D01*
G02X1313616I-737J1277D01*
G02X1313310Y1078748I735J1278D01*
G01X1312794Y1079264D01*
Y1080521D01*
X1310189Y1083126D01*
X1309380D01*
X1304864Y1087642D01*
X1304264D01*
G01X1351353Y1066974D02*
X1349117Y1068694D01*
X1348767Y1068901D01*
G03X1346541I-1113J-1927D01*
G02X1345067I-737J1277D01*
G03X1342899Y1068935I-1114J-1927D01*
G01X1342841Y1068901D01*
G02X1341367I-737J1277D01*
G03X1339199Y1068935I-1114J-1927D01*
G01X1339141Y1068901D01*
G02X1337667I-737J1277D01*
G03X1335481Y1068925I-1114J-1927D01*
G01X1335440Y1068901D01*
G02X1333966I-737J1277D01*
G03X1331740I-1113J-1927D01*
G02X1330266I-737J1277D01*
G03X1328082Y1068925I-1113J-1927D01*
G01X1328041Y1068901D01*
G02X1326567I-737J1277D01*
G03X1324381Y1068925I-1114J-1927D01*
G01X1324340Y1068901D01*
G02X1322866I-737J1277D01*
G01X1322831Y1068921D01*
G02X1322128Y1070178I772J1257D01*
G01Y1070251D01*
G03X1321016Y1072106I-2225J-73D01*
G03X1318832Y1072130I-1113J-1928D01*
G01X1318791Y1072106D01*
G02X1317317I-737J1277D01*
G01X1317282Y1072126D01*
G02X1316579Y1073383I772J1257D01*
G03X1315491Y1075296I-2226J0D01*
G01X1315467Y1075310D01*
G03X1313299Y1075344I-1114J-1927D01*
G01X1313241Y1075310D01*
G02X1311767I-737J1277D01*
G02X1311487Y1075795I280J485D01*
G01Y1077506D01*
G03X1311357Y1077820I-444J0D01*
G01X1305643Y1083534D01*
X1304264D01*
G01X1353204Y1063770D02*
G02X1351864Y1064124I-1J2708D01*
G01X1350190Y1065076D01*
G03X1349385Y1065240I-648J-1121D01*
G01X1349160Y1065213D01*
X1349141Y1065223D01*
X1347741D01*
X1346861Y1065730D01*
G03X1344691Y1065697I-1055J-1960D01*
G01X1344690D01*
G02X1343216I-737J1277D01*
G01X1343158Y1065731D01*
G03X1340990Y1065697I-1054J-1961D01*
G02X1339516I-737J1277D01*
G03X1337290I-1113J-1927D01*
G02X1335816I-737J1277D01*
G01X1335758Y1065731D01*
G03X1333590Y1065697I-1054J-1961D01*
G02X1332116I-737J1277D01*
G03X1329890I-1113J-1927D01*
G02X1328416I-737J1277D01*
G03X1326190I-1113J-1927D01*
G02X1324716I-737J1277D01*
G03X1322490I-1113J-1927D01*
G02X1320306Y1066680I-738J1278D01*
G01X1320278Y1066817D01*
Y1067013D01*
G03X1319166Y1068901I-2225J-39D01*
G03X1316982Y1068925I-1113J-1927D01*
G01X1316941Y1068901D01*
G02X1315467I-737J1277D01*
G01X1315432Y1068921D01*
G02X1314729Y1070178I772J1257D01*
G01Y1070239D01*
G03X1313669Y1072073I-2224J-62D01*
G03X1312599Y1072375I-1068J-1738D01*
G01X1311680D01*
X1309478Y1074577D01*
Y1076446D01*
X1306896Y1079028D01*
X1304592D01*
X1304356Y1079264D01*
X1304264D01*
G01X1362020Y893036D02*
G02X1360620Y893411I0J2801D01*
G01X1359057Y894313D01*
G03X1357583I-737J-1277D01*
G01X1357217Y894099D01*
G03X1356973Y893853I343J-585D01*
G01X1356318Y892718D01*
G02X1355358Y891759I-2271J1313D01*
G02X1353884I-737J1277D01*
G01X1353843Y891783D01*
G03X1351657Y891759I-1072J-1951D01*
G03X1350546Y889893I1114J-1927D01*
G01Y889832D01*
G02X1349843Y888575I-1475J0D01*
G01X1349808Y888555D01*
G02X1348334I-737J1277D01*
G03X1346166Y888589I-1115J-1928D01*
G01X1346108Y888555D01*
G03X1344995Y886683I1112J-1928D01*
G01Y886627D01*
G02X1344292Y885370I-1475J0D01*
G01X1344257Y885350D01*
G03X1343146Y883484I1114J-1927D01*
G01Y883423D01*
G02X1342443Y882166I-1475J0D01*
G01X1342408Y882146D01*
G02X1340934I-737J1277D01*
G01X1340899Y882166D01*
G02X1340196Y883423I772J1257D01*
G03X1339107Y885336I-2225J0D01*
G01X1339083Y885350D01*
X1339025Y885384D01*
G03X1336857Y885350I-1054J-1961D01*
G03X1335746Y883484I1114J-1927D01*
G01Y883423D01*
G02X1335043Y882166I-1475J0D01*
G01X1335008Y882146D01*
G02X1333534I-737J1277D01*
G01X1333499Y882166D01*
G02X1332796Y883423I772J1257D01*
G03X1331707Y885336I-2225J0D01*
G01X1331683Y885350D01*
X1331625Y885384D01*
G03X1329457Y885350I-1054J-1961D01*
G03X1328346Y883484I1114J-1927D01*
G01Y883423D01*
G02X1327643Y882166I-1475J0D01*
G01X1327608Y882146D01*
X1327560Y882118D01*
G03X1326495Y880219I1161J-1899D01*
G02X1325792Y878962I-1475J0D01*
G01X1325757Y878942D01*
G02X1324317Y878923I-737J1277D01*
G01X1324284Y878942D01*
X1324226Y878976D01*
G03X1322058Y878942I-1053J-1962D01*
G02X1320584I-737J1277D01*
G03X1318358I-1113J-1928D01*
G02X1316884I-737J1277D01*
G03X1314658I-1113J-1928D01*
G02X1313184I-737J1277D01*
G03X1311016Y878976I-1115J-1928D01*
G01X1310958Y878942D01*
G03X1309845Y877070I1112J-1928D01*
G01Y873090D01*
X1303182Y866427D01*
G01X1350920Y893036D02*
X1349689D01*
X1349431Y892778D01*
G02X1348334Y891109I-2211J258D01*
G02X1346166Y891075I-1114J1927D01*
G01X1346108Y891109D01*
G03X1344634I-737J-1277D01*
G01X1344599Y891089D01*
G03X1343896Y889832I772J-1257D01*
G01Y889776D01*
G02X1342783Y887904I-2225J56D01*
G01X1342725Y887870D01*
G02X1340557Y887904I-1053J1962D01*
G03X1339083I-737J-1277D01*
G01X1339025Y887870D01*
G02X1336857Y887904I-1053J1962D01*
G03X1335383I-737J-1277D01*
G02X1333157I-1113J1928D01*
G03X1331683I-737J-1277D01*
G01X1331625Y887870D01*
G02X1329457Y887904I-1053J1962D01*
G03X1327983I-737J-1277D01*
G03X1327246Y886661I737J-1277D01*
G01Y886588D01*
G02X1326134Y884700I-2225J39D01*
G01X1326099Y884680D01*
G03X1325396Y883423I772J-1257D01*
G02X1324307Y881510I-2225J0D01*
G01X1324283Y881496D01*
X1324242Y881472D01*
G02X1322058Y881496I-1071J1951D01*
G03X1320584I-737J-1277D01*
G02X1318358I-1113J1927D01*
G03X1316884I-737J-1277D01*
G02X1314658I-1113J1927D01*
G03X1313184I-737J-1277D01*
G02X1311016Y881462I-1114J1927D01*
G01X1310958Y881496D01*
G03X1309518Y881515I-737J-1277D01*
G01X1309485Y881496D01*
G03X1309178Y881262I733J-1279D01*
G01X1306896Y878980D01*
Y874347D01*
X1302816Y870267D01*
X1300865D01*
G01X1356471Y896240D02*
X1356346Y895784D01*
X1356193Y895697D01*
G02X1355584Y895536I-609J1071D01*
G01X1354507D01*
X1353508Y894963D01*
G02X1352034I-737J1277D01*
G03X1349866Y894997I-1114J-1927D01*
G01X1349808Y894963D01*
G02X1348334I-737J1277D01*
G03X1346166Y894997I-1114J-1927D01*
G01X1346108Y894963D01*
G02X1344634I-737J1277D01*
G03X1342466Y894997I-1114J-1927D01*
G01X1342408Y894963D01*
G03X1341296Y893075I1113J-1927D01*
G01Y893036D01*
G02X1340593Y891779I-1475J0D01*
G01X1340558Y891759D01*
G02X1339084I-737J1277D01*
G03X1336858I-1113J-1927D01*
G02X1335384I-737J1277D01*
G03X1333198Y891783I-1114J-1927D01*
G01X1333157Y891759D01*
G02X1331683I-737J1277D01*
G01X1331625Y891793D01*
G03X1329457Y891759I-1054J-1961D01*
G02X1327983I-737J1277D01*
G01X1327925Y891793D01*
G03X1325757Y891759I-1054J-1961D01*
G03X1324646Y889893I1114J-1927D01*
G01Y889832D01*
G02X1323943Y888575I-1475J0D01*
G01X1323908Y888555D01*
G03X1322796Y886700I1113J-1928D01*
G01Y886627D01*
G02X1322093Y885370I-1475J0D01*
G01X1322058Y885350D01*
G02X1320584I-737J1277D01*
G03X1318358I-1113J-1927D01*
G02X1316884I-737J1277D01*
G03X1314658I-1113J-1927D01*
G02X1313184I-737J1277D01*
G03X1311016Y885384I-1114J-1927D01*
G01X1310958Y885350D01*
G02X1310315Y885154I-740J1276D01*
G02X1310222Y885151I-94J1472D01*
G01X1309417D01*
X1304649Y880383D01*
Y877170D01*
X1303641Y876162D01*
X1301192D01*
X1300957Y876397D01*
X1300865D01*
G01X1360171Y896240D02*
G03X1358831Y895886I-1J-2708D01*
G01X1357157Y894934D01*
G02X1356352Y894770I-648J1121D01*
G01X1356127Y894797D01*
X1356108Y894787D01*
X1354708D01*
X1353843Y894289D01*
G02X1351657Y894313I-1072J1951D01*
G03X1350183I-737J-1277D01*
G01X1350125Y894279D01*
G02X1347957Y894313I-1054J1961D01*
G03X1346483I-737J-1277D01*
G01X1346425Y894279D01*
G02X1344257Y894313I-1054J1961D01*
G03X1342783I-737J-1277D01*
G01X1342784D01*
X1342749Y894293D01*
G03X1342046Y893036I772J-1257D01*
G01Y892997D01*
G02X1340934Y891109I-2225J39D01*
G02X1338708I-1113J1927D01*
G03X1337234I-737J-1277D01*
G01X1337193Y891085D01*
G02X1335007Y891109I-1072J1951D01*
G03X1333533I-737J-1277D01*
G02X1331349Y891085I-1113J1927D01*
G01X1331308Y891109D01*
G03X1329834I-737J-1277D01*
G02X1327666Y891075I-1114J1927D01*
G01X1327608Y891109D01*
G03X1326134I-737J-1277D01*
G01X1326099Y891089D01*
G03X1325396Y889832I772J-1257D01*
G01Y889759D01*
G02X1324284Y887904I-2225J73D01*
G01X1324249Y887884D01*
G03X1323546Y886627I772J-1257D01*
G01Y886588D01*
G02X1322434Y884700I-2225J39D01*
G02X1320208I-1113J1927D01*
G03X1318734I-737J-1277D01*
G02X1316508I-1113J1927D01*
G03X1315034I-737J-1277D01*
G01X1314993Y884676D01*
G02X1312807Y884700I-1072J1951D01*
G03X1311333I-737J-1277D01*
G02X1310365Y884406I-1114J1926D01*
G01X1310362D01*
G02X1310222Y884402I-133J2220D01*
G01X1309728D01*
X1305398Y880072D01*
Y876859D01*
X1303952Y875413D01*
X1301193D01*
X1300957Y875177D01*
X1300865D01*
G01X1356471Y902649D02*
G03X1353661Y904219I-2668J-1476D01*
G02X1350675Y904399I-653J14026D01*
G02X1350183Y904576I245J1454D01*
G03X1347957I-1113J-1927D01*
G02X1346483I-737J1277D01*
G01X1346425Y904610D01*
G03X1344257Y904576I-1054J-1961D01*
G02X1342783I-737J1277D01*
G01X1342725Y904610D01*
G03X1340557Y904576I-1054J-1961D01*
G02X1339083I-737J1277D01*
G01X1339025Y904610D01*
G03X1336857Y904576I-1054J-1961D01*
G03X1335746Y902710I1114J-1927D01*
G01Y902649D01*
G02X1335043Y901392I-1475J0D01*
G01X1335008Y901372D01*
G02X1333534I-737J1277D01*
G03X1331366Y901406I-1114J-1927D01*
G01X1331308Y901372D01*
G02X1329834I-737J1277D01*
G03X1327666Y901406I-1114J-1927D01*
G01X1327608Y901372D01*
G02X1326134I-737J1277D01*
G03X1323966Y901406I-1114J-1927D01*
G01X1323908Y901372D01*
G02X1322434I-737J1277D01*
G01X1322393Y901396D01*
G03X1320207Y901372I-1072J-1951D01*
G03X1319097Y899507I1115J-1926D01*
G01X1319096Y899446D01*
Y899418D01*
G02X1318358Y898168I-1475J28D01*
G03X1317245Y896296I1112J-1928D01*
G01Y896206D01*
G02X1316508Y894963I-1474J34D01*
G02X1315034I-737J1277D01*
G01X1314993Y894987D01*
G03X1312807Y894963I-1072J-1951D01*
G02X1311333I-737J1277D01*
G03X1309149Y894987I-1113J-1927D01*
G01X1309108Y894963D01*
G03X1308647Y894609I1113J-1926D01*
G01X1301484Y887446D01*
X1300865D01*
G01X1358320Y899445D02*
X1355470Y900657D01*
X1355358Y900722D01*
G03X1353884I-737J-1276D01*
G01X1352757Y900071D01*
G03X1352395Y899445I360J-626D01*
G02X1351658Y898169I-1473J0D01*
G01X1351657Y898168D01*
G02X1350184I-737J1276D01*
G01X1350183D01*
X1349058Y898818D01*
G02X1348695Y899445I361J628D01*
G03X1347958Y900721I-1473J0D01*
G01X1347957Y900722D01*
G03X1346483I-737J-1277D01*
G01X1346425Y900688D01*
G02X1344257Y900722I-1054J1961D01*
G03X1342783I-737J-1277D01*
G01X1342725Y900688D01*
G02X1340557Y900722I-1054J1961D01*
G03X1339083I-737J-1277D01*
G03X1338346Y899479I737J-1277D01*
G01Y899389D01*
G02X1337233Y897517I-2225J56D01*
G01X1337192Y897493D01*
G02X1335008Y897517I-1071J1952D01*
G03X1333534I-737J-1277D01*
G02X1331366Y897483I-1115J1928D01*
G01X1331308Y897517D01*
G03X1329834I-737J-1277D01*
G02X1327666Y897483I-1115J1928D01*
G01X1327608Y897517D01*
G03X1326134I-737J-1277D01*
G02X1323966Y897483I-1115J1928D01*
G01X1323908Y897517D01*
G03X1322434I-737J-1277D01*
G01X1322399Y897497D01*
G03X1321696Y896240I772J-1257D01*
G02X1320608Y894327I-2226J0D01*
G01X1320584Y894313D01*
X1320549Y894293D01*
G03X1319846Y893036I772J-1257D01*
G02X1318781Y891137I-2226J0D01*
G01X1318733Y891109D01*
G02X1316549Y891085I-1113J1927D01*
G01X1316508Y891109D01*
G03X1315034I-737J-1277D01*
G01X1314993Y891085D01*
G02X1312807Y891109I-1072J1951D01*
G03X1311333I-737J-1277D01*
G02X1310220Y890811I-1112J1927D01*
G01X1309118D01*
X1308091Y889784D01*
Y888717D01*
X1302401Y883027D01*
Y882164D01*
X1301803Y881566D01*
X1300865D01*
G01X1358320Y931488D02*
G02X1354532Y929919I-3788J3788D01*
G03X1350661Y929819I0J-74973D01*
G03X1348334Y929560I-868J-2787D01*
G02X1346108I-1113J1928D01*
G03X1344634I-737J-1277D01*
G02X1342466Y929526I-1115J1928D01*
G01X1342408Y929560D01*
G03X1340934I-737J-1277D01*
G02X1338766Y929526I-1115J1928D01*
G01X1338708Y929560D01*
G03X1337234I-737J-1277D01*
G02X1335048Y929536I-1114J1928D01*
G01X1335007Y929560D01*
G03X1333533I-737J-1277D01*
G02X1331349Y929536I-1113J1928D01*
G01X1331308Y929560D01*
G03X1329834I-737J-1277D01*
G02X1327666Y929526I-1115J1928D01*
G01X1327608Y929560D01*
G03X1326134I-737J-1277D01*
G02X1323908I-1113J1928D01*
G03X1322434I-737J-1277D01*
G02X1320262Y929529I-1114J1928D01*
G01X1320208Y929561D01*
G03X1318734I-737J-1277D01*
G03X1317997Y928318I737J-1277D01*
G01Y928228D01*
G02X1316884Y926356I-2225J56D01*
G02X1314694Y926336I-1113J1928D01*
G01X1314659Y926357D01*
G03X1313185I-737J-1277D01*
G01X1313144Y926333D01*
G02X1310958Y926357I-1072J1951D01*
G03X1309516Y926376I-738J-1277D01*
G01X1309483Y926357D01*
G02X1308370Y926059I-1112J1927D01*
G01X1307876D01*
X1305764Y923947D01*
Y923546D01*
X1304657Y920872D01*
X1302671Y918886D01*
X1301466D01*
G01X1356471Y928283D02*
G02X1351163Y926533I-4318J4173D01*
G03X1350183Y926356I-243J-1454D01*
G01X1350125Y926322D01*
G02X1347957Y926356I-1054J1961D01*
G03X1346483I-737J-1277D01*
G01X1346425Y926322D01*
G02X1344257Y926356I-1054J1961D01*
G03X1342783I-737J-1277D01*
G01X1342725Y926322D01*
G02X1340557Y926356I-1054J1961D01*
G03X1339083I-737J-1277D01*
G01X1339025Y926322D01*
G02X1336857Y926356I-1054J1961D01*
G03X1335383I-737J-1277D01*
G02X1333199Y926332I-1113J1927D01*
G01X1333158Y926356D01*
G03X1331684I-737J-1277D01*
G01X1331643Y926332D01*
G02X1329457Y926356I-1072J1951D01*
G03X1327983I-737J-1277D01*
G01X1327925Y926322D01*
G02X1325757Y926356I-1054J1961D01*
G03X1324283I-737J-1277D01*
G01X1324242Y926332D01*
G02X1322058Y926356I-1071J1951D01*
G01X1322015Y926381D01*
G03X1320584Y926357I-694J-1301D01*
G01X1320549Y926337D01*
G03X1319846Y925080I772J-1257D01*
G02X1318758Y923166I-2226J-1D01*
G01X1318734Y923152D01*
G02X1316548Y923128I-1114J1927D01*
G01X1316507Y923152D01*
G03X1315067Y923171I-737J-1277D01*
G01X1315034Y923152D01*
G02X1312844Y923132I-1113J1928D01*
G01X1312809Y923153D01*
X1312776Y923172D01*
G03X1311334Y923153I-704J-1296D01*
G02X1309130Y923139I-1114J1927D01*
G01X1309108Y923152D01*
X1309075Y923171D01*
G03X1307633Y923152I-704J-1296D01*
G03X1307326Y922920I729J-1284D01*
G01X1307086Y922680D01*
X1306686Y921714D01*
Y919553D01*
X1302099Y914966D01*
X1301466D01*
G01X1358320Y937896D02*
G03X1356924Y937522I0J-2792D01*
G01X1355335Y936605D01*
G02X1353883Y936618I-715J1291D01*
G03X1351761Y936419I-921J-1596D01*
G02X1350207Y936605I-562J1886D01*
G01X1350125Y936653D01*
G02X1349261Y937719I984J1680D01*
G03X1347957Y939173I-2873J-1265D01*
G03X1346483I-737J-1277D01*
G01X1346425Y939139D01*
G02X1344257Y939173I-1054J1961D01*
G03X1342783I-737J-1277D01*
G01X1342725Y939139D01*
G02X1340557Y939173I-1054J1961D01*
G03X1339083I-737J-1277D01*
G01X1339042Y939149D01*
G02X1336858Y939173I-1071J1951D01*
G03X1335384I-737J-1277D01*
G01X1335343Y939149D01*
G02X1333157Y939173I-1072J1951D01*
G03X1331683I-737J-1277D01*
G01X1331625Y939139D01*
G02X1329457Y939173I-1054J1961D01*
G03X1327983I-737J-1277D01*
G01X1327925Y939139D01*
G02X1325757Y939173I-1054J1961D01*
G03X1324283I-737J-1277D01*
G01X1324242Y939149D01*
G02X1322058Y939173I-1071J1951D01*
G03X1320584I-737J-1277D01*
G02X1318400Y939149I-1113J1927D01*
G01X1318359Y939173D01*
G03X1316885I-737J-1277D01*
G02X1314717Y939139I-1114J1927D01*
G01X1314659Y939173D01*
G03X1313185I-737J-1277D01*
G01X1313150Y939153D01*
G03X1312447Y937896I772J-1257D01*
G02X1311358Y935983I-2225J0D01*
G01X1311334Y935969D01*
X1311276Y935935D01*
G02X1309108Y935969I-1054J1961D01*
G03X1308370Y936169I-742J-1276D01*
G01X1306424D01*
X1305911Y935656D01*
Y933867D01*
X1304067Y932023D01*
Y931074D01*
X1303726Y930733D01*
Y929783D01*
X1303131Y929188D01*
X1302266D01*
G01X1356471Y934691D02*
X1357703D01*
X1357928Y934466D01*
G02X1355734Y933415I-1457J225D01*
G03X1353566Y933449I-1114J-1927D01*
G01X1353508Y933415D01*
G02X1352034I-737J1276D01*
G03X1349866Y933449I-1114J-1927D01*
G01X1349808Y933415D01*
G02X1348334I-737J1276D01*
G03X1346108I-1113J-1927D01*
G02X1344634I-737J1276D01*
G03X1342466Y933449I-1114J-1927D01*
G01X1342408Y933415D01*
G02X1340934I-737J1276D01*
G03X1338748Y933439I-1114J-1927D01*
G01X1338707Y933415D01*
G02X1337233I-737J1276D01*
G03X1335049Y933439I-1113J-1927D01*
G01X1335008Y933415D01*
G02X1333534I-737J1276D01*
G03X1331366Y933449I-1114J-1927D01*
G01X1331308Y933415D01*
G02X1329834I-737J1276D01*
G03X1327666Y933449I-1114J-1927D01*
G01X1327608Y933415D01*
G02X1326134I-737J1276D01*
G03X1323908I-1113J-1927D01*
G02X1322434I-737J1276D01*
G01X1322393Y933439D01*
G03X1320207Y933415I-1072J-1951D01*
G02X1318733I-737J1277D01*
G01X1318692Y933439D01*
G03X1315396Y931527I-1071J-1951D01*
G01Y931488D01*
G02X1313184Y930211I-1475J0D01*
G01X1313126Y930245D01*
G03X1310958Y930211I-1054J-1961D01*
G02X1309484I-737J1277D01*
G03X1308370Y930510I-1114J-1926D01*
G01X1307565D01*
X1306262Y929207D01*
Y927781D01*
X1303461Y924980D01*
Y924199D01*
X1303053Y923791D01*
X1302593D01*
X1302358Y924026D01*
X1302266D01*
G01X1360171Y934691D02*
X1358939D01*
X1358681Y934433D01*
G02X1357607Y932778I-2210J258D01*
G01X1357583Y932764D01*
X1357525Y932730D01*
G02X1355357Y932764I-1054J1961D01*
G03X1353883I-737J-1276D01*
G01X1353825Y932730D01*
G02X1351657Y932764I-1054J1961D01*
G03X1350183I-737J-1276D01*
G01X1350142Y932740D01*
G02X1347958Y932764I-1071J1951D01*
G03X1346484I-737J-1276D01*
G01X1346443Y932740D01*
G02X1344257Y932764I-1072J1951D01*
G03X1342783I-737J-1276D01*
G01X1342725Y932730D01*
G02X1340557Y932764I-1054J1961D01*
G03X1339083I-737J-1276D01*
G02X1336857I-1113J1927D01*
G03X1335383I-737J-1276D01*
G01X1335325Y932730D01*
G02X1333157Y932764I-1054J1961D01*
G03X1331683I-737J-1276D01*
G01X1331625Y932730D01*
G02X1329457Y932764I-1054J1961D01*
G03X1327983I-737J-1276D01*
G01X1327942Y932740D01*
G02X1325758Y932764I-1071J1951D01*
G03X1324284I-737J-1276D01*
G02X1322058I-1113J1927D01*
G01X1322015Y932789D01*
G03X1320584Y932765I-694J-1301D01*
G02X1318416Y932731I-1114J1927D01*
G01X1318358Y932765D01*
G03X1316146Y931488I-737J-1277D01*
G01Y931449D01*
G02X1312867Y929527I-2225J38D01*
G01X1312809Y929561D01*
G03X1311335I-737J-1277D01*
G02X1309107I-1114J1927D01*
G03X1308370Y929761I-742J-1276D01*
G01X1307876D01*
X1307011Y928896D01*
Y927470D01*
X1304210Y924669D01*
Y923888D01*
X1303364Y923042D01*
X1302594D01*
X1302358Y922806D01*
X1302266D01*
G01X1356471Y941100D02*
G02X1353164Y939540I-2877J1813D01*
G01X1351761Y939719D01*
G02X1350545Y941100I176J1381D01*
G03X1349842Y942357I-1475J0D01*
G01X1349807Y942377D01*
G03X1348333I-737J-1277D01*
G02X1346149Y942353I-1113J1927D01*
G01X1346108Y942377D01*
G03X1344634I-737J-1277D01*
G02X1342466Y942343I-1114J1927D01*
G01X1342408Y942377D01*
G03X1340934I-737J-1277D01*
G02X1338766Y942343I-1114J1927D01*
G01X1338708Y942377D01*
G03X1337234I-737J-1277D01*
G02X1335066Y942343I-1114J1927D01*
G01X1335008Y942377D01*
G03X1333534I-737J-1277D01*
G02X1331308I-1113J1927D01*
G03X1329834I-737J-1277D01*
G02X1327666Y942343I-1114J1927D01*
G01X1327608Y942377D01*
G03X1326134I-737J-1277D01*
G02X1323966Y942343I-1114J1927D01*
G01X1323908Y942377D01*
G03X1322434I-737J-1277D01*
G02X1320266Y942343I-1114J1927D01*
G01X1320208Y942377D01*
G03X1318734I-737J-1277D01*
G02X1316566Y942343I-1114J1927D01*
G01X1316508Y942377D01*
G03X1315034I-737J-1277D01*
G02X1312866Y942343I-1114J1927D01*
G01X1312808Y942377D01*
G03X1311334I-737J-1277D01*
G01X1311299Y942357D01*
G03X1310596Y941100I772J-1257D01*
G01Y941061D01*
G02X1308371Y938875I-2225J39D01*
G01X1308370Y938876D01*
X1306758D01*
X1304238Y936356D01*
Y934340D01*
X1303006Y933108D01*
X1302266D01*
G01X1356471Y947509D02*
X1355240D01*
X1354982Y947251D01*
G02X1353883Y945581I-2211J258D01*
G01X1353825Y945547D01*
G02X1351657Y945581I-1053J1962D01*
G03X1350183I-737J-1277D01*
G01X1350125Y945547D01*
G02X1347957Y945581I-1053J1962D01*
G03X1346483I-737J-1277D01*
G01X1346425Y945547D01*
G02X1344257Y945581I-1053J1962D01*
G03X1342783I-737J-1277D01*
G01X1342725Y945547D01*
G02X1340557Y945581I-1053J1962D01*
G03X1339083I-737J-1277D01*
G01X1339025Y945547D01*
G02X1336857Y945581I-1053J1962D01*
G03X1335383I-737J-1277D01*
G02X1333199Y945557I-1113J1928D01*
G01X1333158Y945581D01*
G03X1331684I-737J-1277D01*
G01X1331643Y945557D01*
G02X1329457Y945581I-1072J1952D01*
G03X1327983I-737J-1277D01*
G01X1327925Y945547D01*
G02X1325757Y945581I-1053J1962D01*
G03X1324283I-737J-1277D01*
G01X1324212Y945540D01*
G02X1322056Y945581I-1041J1969D01*
G03X1320614Y945600I-738J-1277D01*
G01X1320581Y945581D01*
G02X1318427Y945540I-1114J1928D01*
G01X1318356Y945581D01*
X1318299Y945614D01*
G03X1316881Y945581I-679J-1310D01*
G02X1314711Y945547I-1115J1928D01*
G01X1314653Y945581D01*
G03X1313179I-737J-1277D01*
G02X1310993Y945557I-1114J1928D01*
G01X1310952Y945581D01*
G03X1309478I-737J-1277D01*
G03X1309170Y945349I726J-1285D01*
G01Y945348D01*
X1308085Y944263D01*
X1307154Y942016D01*
X1303326Y938188D01*
X1302266D01*
G01X1358320Y950713D02*
X1357089D01*
X1356831Y950455D01*
G02X1355734Y948786I-2211J258D01*
G02X1353566Y948752I-1114J1927D01*
G01X1353508Y948786D01*
G03X1352034I-737J-1277D01*
G02X1349866Y948752I-1114J1927D01*
G01X1349808Y948786D01*
G03X1348334I-737J-1277D01*
G02X1346108I-1113J1927D01*
G03X1344634I-737J-1277D01*
G02X1342466Y948752I-1114J1927D01*
G01X1342408Y948786D01*
G03X1340934I-737J-1277D01*
G02X1338766Y948752I-1114J1927D01*
G01X1338708Y948786D01*
G03X1337234I-737J-1277D01*
G02X1335048Y948762I-1114J1927D01*
G01X1335007Y948786D01*
G03X1333533I-737J-1277D01*
G02X1331349Y948762I-1113J1927D01*
G01X1331308Y948786D01*
G03X1329834I-737J-1277D01*
G02X1327666Y948752I-1114J1927D01*
G01X1327608Y948786D01*
G03X1326134I-737J-1277D01*
G02X1323966Y948752I-1114J1927D01*
G01X1323908Y948786D01*
G03X1322434I-737J-1277D01*
G02X1320208I-1113J1927D01*
G03X1318734I-737J-1277D01*
G02X1316508I-1113J1927D01*
G03X1315034I-737J-1277D01*
G02X1312866Y948752I-1114J1927D01*
G01X1312808Y948786D01*
G03X1311334I-737J-1277D01*
G02X1310221Y948488I-1113J1928D01*
G01X1309435D01*
X1305998Y945051D01*
Y944174D01*
X1305672Y943387D01*
X1304436Y942151D01*
X1303266D01*
G01X1356471Y953917D02*
X1357703D01*
X1357928Y953692D01*
X1357929D01*
G02X1357230Y952652I-1458J225D01*
G01X1357208Y952640D01*
G02X1355734I-737J1277D01*
G01X1355733D01*
X1355732Y952639D01*
G03X1353506Y952638I-1112J-1926D01*
G01X1353459Y952610D01*
G02X1352032Y952639I-687J1307D01*
G03X1349806Y952638I-1112J-1926D01*
G01X1349773Y952619D01*
G02X1348333Y952639I-702J1298D01*
G03X1346107Y952638I-1112J-1926D01*
G01X1346074Y952619D01*
G02X1344632Y952639I-703J1298D01*
G03X1342406Y952638I-1112J-1926D01*
G01X1342359Y952610D01*
G02X1340932Y952639I-687J1307D01*
G03X1338706Y952638I-1112J-1926D01*
G01X1338659Y952610D01*
G02X1337232Y952639I-687J1307D01*
G03X1335006Y952638I-1112J-1926D01*
G01X1334959Y952610D01*
G02X1333532Y952639I-687J1307D01*
G03X1331306Y952638I-1112J-1926D01*
G01X1331259Y952610D01*
G02X1329832Y952639I-687J1307D01*
G03X1327606Y952638I-1112J-1926D01*
G01X1327559Y952610D01*
G02X1326132Y952639I-687J1307D01*
G03X1323948Y952662I-1112J-1926D01*
G01X1323861Y952611D01*
G02X1322433Y952639I-689J1306D01*
G03X1320209I-1112J-1926D01*
G02X1318782Y952610I-740J1278D01*
G01X1318735Y952638D01*
G03X1316507I-1114J-1925D01*
G01X1316460Y952610D01*
G02X1315031Y952639I-688J1307D01*
G03X1312876Y952680I-1115J-1926D01*
G01X1312732Y952596D01*
G02X1311666Y952495I-663J1321D01*
G03X1308749Y951736I-812J-2863D01*
G01X1308275Y951262D01*
G03X1307697Y950401I1904J-1903D01*
G02X1307439Y950018I-1100J463D01*
G01X1304502Y947081D01*
X1303593D01*
X1303358Y947316D01*
X1303266D01*
G01X1360171Y953917D02*
X1358939D01*
X1358681Y953659D01*
G02X1357607Y952004I-2210J258D01*
G01X1357583Y951990D01*
X1357525Y951956D01*
G02X1355357Y951990I-1054J1961D01*
G03X1353883I-737J-1277D01*
G01X1353825Y951956D01*
G02X1351657Y951990I-1054J1961D01*
G03X1350183I-737J-1277D01*
G01X1350142Y951966D01*
G02X1347958Y951990I-1071J1951D01*
G03X1346484I-737J-1277D01*
G01X1346443Y951966D01*
G02X1344257Y951990I-1072J1951D01*
G03X1342783I-737J-1277D01*
G01X1342725Y951956D01*
G02X1340557Y951990I-1054J1961D01*
G03X1339083I-737J-1277D01*
G01X1339025Y951956D01*
G02X1336857Y951990I-1054J1961D01*
G03X1335383I-737J-1277D01*
G01X1335325Y951956D01*
G02X1333157Y951990I-1054J1961D01*
G03X1331683I-737J-1277D01*
G01X1331625Y951956D01*
G02X1329457Y951990I-1054J1961D01*
G03X1327983I-737J-1277D01*
G01X1327925Y951956D01*
G02X1325757Y951990I-1054J1961D01*
G03X1324317Y952009I-737J-1277D01*
G01X1324226Y951956D01*
G02X1322058Y951990I-1054J1961D01*
G03X1320584I-737J-1277D01*
G02X1318416Y951956I-1114J1927D01*
G01X1318358Y951990D01*
G03X1316884I-737J-1277D01*
G01X1316826Y951956D01*
G02X1314656Y951990I-1055J1961D01*
G03X1313238Y952023I-739J-1277D01*
G01X1313089Y951937D01*
G02X1311462Y951774I-1020J1980D01*
G03X1309279Y951206I-608J-2142D01*
G01X1308805Y950732D01*
G03X1308387Y950109I1374J-1374D01*
G02X1307969Y949488I-1791J754D01*
G01X1304813Y946332D01*
X1303594D01*
X1303358Y946096D01*
X1303266D01*
G01X1356471Y960326D02*
X1356470D01*
X1355849Y959705D01*
G02X1353109Y958570I-2740J2740D01*
G01X1352965D01*
G02X1351196Y959303I0J2501D01*
G01X1350545Y959954D01*
Y960326D01*
G03X1349842Y961583I-1475J0D01*
G01X1349807Y961603D01*
G03X1348333I-737J-1277D01*
G02X1346149Y961579I-1113J1927D01*
G01X1346108Y961603D01*
G03X1344634I-737J-1277D01*
G02X1342466Y961569I-1114J1927D01*
G01X1342408Y961603D01*
G03X1340934I-737J-1277D01*
G02X1338708I-1113J1927D01*
G03X1337234I-737J-1277D01*
G02X1335066Y961569I-1114J1927D01*
G01X1335008Y961603D01*
G03X1333534I-737J-1277D01*
G02X1331308I-1113J1927D01*
G03X1329834I-737J-1277D01*
G02X1327666Y961569I-1114J1927D01*
G01X1327608Y961603D01*
G03X1326134I-737J-1277D01*
G02X1323966Y961569I-1114J1927D01*
G01X1323908Y961603D01*
G03X1322434I-737J-1277D01*
G02X1320248Y961579I-1114J1927D01*
G01X1320207Y961603D01*
G03X1318733I-737J-1277D01*
G02X1316507I-1113J1927D01*
G03X1315033I-737J-1277D01*
G02X1312807I-1113J1927D01*
G03X1311333I-737J-1277D01*
G02X1309448Y961441I-1115J1926D01*
G01X1307832D01*
X1306890Y960499D01*
X1303266D01*
G01X1358320Y957122D02*
G03X1356924Y956748I0J-2792D01*
G01X1355335Y955831D01*
G02X1353883Y955844I-715J1291D01*
G03X1351681Y955858I-1113J-1927D01*
G01X1351658Y955844D01*
X1351635Y955831D01*
G02X1350183Y955844I-715J1291D01*
G02X1349786Y956149I960J1661D01*
G01X1349392Y956543D01*
G02X1348740Y957416I2693J2691D01*
G01X1348516Y957827D01*
G03X1347978Y958388I-1296J-704D01*
G01X1347935Y958412D01*
G03X1346483Y958399I-715J-1290D01*
G02X1344281Y958386I-1112J1927D01*
G01X1344235Y958412D01*
G03X1342783Y958399I-715J-1290D01*
G02X1340581Y958386I-1112J1927D01*
G01X1340535Y958412D01*
G03X1339083Y958399I-715J-1290D01*
G02X1336881Y958386I-1112J1927D01*
G01X1336835Y958412D01*
G03X1335383Y958399I-715J-1290D01*
G02X1333181Y958386I-1112J1927D01*
G01X1333135Y958412D01*
G03X1331683Y958399I-715J-1290D01*
G02X1329481Y958386I-1112J1927D01*
G01X1329435Y958412D01*
G03X1327983Y958399I-715J-1290D01*
G02X1325781Y958386I-1112J1927D01*
G01X1325758Y958399D01*
X1325743Y958408D01*
G03X1324283Y958399I-722J-1286D01*
G01X1324242Y958375D01*
G02X1322058Y958399I-1071J1951D01*
G03X1320584I-737J-1277D01*
G02X1318416Y958365I-1114J1927D01*
G01X1318358Y958399D01*
G03X1316884I-737J-1277D01*
G02X1314716Y958365I-1114J1927D01*
G01X1314658Y958399D01*
G03X1313184I-737J-1277D01*
G02X1311016Y958365I-1114J1927D01*
G01X1310958Y958399D01*
G03X1309484I-737J-1277D01*
G02X1307316Y958365I-1114J1927D01*
G01X1306983D01*
X1304423Y955805D01*
X1303266D01*
G01X1356904Y1018910D02*
X1355673D01*
X1355414Y1019169D01*
G03X1354340Y1020823I-2210J-259D01*
G01X1354316Y1020837D01*
X1354258Y1020871D01*
G03X1352090Y1020837I-1054J-1961D01*
G01X1352066Y1020823D01*
G03X1350978Y1018910I1138J-1913D01*
G02X1350275Y1017653I-1475J0D01*
G01X1350240Y1017633D01*
G02X1348766I-737J1277D01*
G03X1346582Y1017657I-1113J-1928D01*
G01X1346541Y1017633D01*
G02X1345067I-737J1277D01*
G03X1342899Y1017667I-1115J-1928D01*
G01X1342841Y1017633D01*
G02X1341367I-737J1277D01*
G03X1339141I-1113J-1928D01*
G02X1337667I-737J1277D01*
G03X1335499Y1017667I-1115J-1928D01*
G01X1335441Y1017633D01*
G02X1333967I-737J1277D01*
G01X1333926Y1017657D01*
G03X1331740Y1017633I-1072J-1952D01*
G02X1330266I-737J1277D01*
G03X1328040I-1113J-1928D01*
G02X1326566I-737J1277D01*
G03X1324340I-1113J-1928D01*
G02X1322866I-737J1277D01*
G03X1320640I-1113J-1928D01*
G02X1319166I-737J1277D01*
G03X1316940I-1113J-1928D01*
G02X1315466I-737J1277D01*
G03X1313240I-1113J-1928D01*
G02X1311766I-737J1277D01*
G03X1309540I-1113J-1928D01*
G02X1308066I-737J1277D01*
G03X1306953Y1017931I-1113J-1928D01*
G01X1304277Y1020607D01*
X1303263D01*
G01X1358753Y1022114D02*
G03X1355655Y1023519I-3211J-2962D01*
G02X1355373Y1023553I35J1473D01*
G03X1354307Y1023387I-322J-1439D01*
G02X1353993Y1023235I-1060J1789D01*
G02X1352090Y1023391I-787J2082D01*
G03X1350616I-737J-1277D01*
G03X1349778Y1022394I953J-1652D01*
G02X1349554Y1022068I-6075J3934D01*
G01X1349342Y1021685D01*
X1348854Y1021162D01*
X1348556Y1020938D01*
X1348390Y1020837D01*
G02X1346916I-737J1277D01*
G01X1346858Y1020871D01*
G03X1344690Y1020837I-1054J-1961D01*
G02X1343216I-737J1277D01*
G01X1343158Y1020871D01*
G03X1340990Y1020837I-1054J-1961D01*
G02X1339516I-737J1277D01*
G01X1339475Y1020861D01*
G03X1337291Y1020837I-1071J-1951D01*
G02X1335817I-737J1277D01*
G01X1335776Y1020861D01*
G03X1333590Y1020837I-1072J-1951D01*
G02X1332116I-737J1277D01*
G03X1329890I-1113J-1927D01*
G02X1328416I-737J1277D01*
G03X1326190I-1113J-1927D01*
G02X1324716I-737J1277D01*
G03X1322490I-1113J-1927D01*
G02X1321016I-737J1277D01*
G03X1318790I-1113J-1927D01*
G02X1317316I-737J1277D01*
G03X1315090I-1113J-1927D01*
G02X1313616I-737J1277D01*
G03X1311390I-1113J-1927D01*
G02X1309916I-737J1277D01*
G03X1308620Y1021128I-1113J-1927D01*
G01X1306734D01*
X1303185Y1024677D01*
X1301567D01*
G01X1356902Y1025318D02*
X1358135D01*
X1358360Y1025543D01*
G03X1357698Y1026561I-1459J-224D01*
G01X1357639Y1026595D01*
G03X1356165I-737J-1277D01*
G02X1353941I-1112J1928D01*
G03X1352467I-737J-1277D01*
G02X1350239I-1114J1928D01*
G03X1348765I-737J-1277D01*
G02X1346541I-1112J1928D01*
G03X1345067I-737J-1277D01*
G02X1342899Y1026561I-1115J1928D01*
G01X1342841Y1026595D01*
G03X1341367I-737J-1277D01*
G02X1339181Y1026571I-1114J1928D01*
G01X1339140Y1026595D01*
G03X1337666I-737J-1277D01*
G02X1335482Y1026571I-1113J1928D01*
G01X1335441Y1026595D01*
G03X1333967I-737J-1277D01*
G02X1331799Y1026561I-1115J1928D01*
G01X1331741Y1026595D01*
G03X1330267I-737J-1277D01*
G02X1328099Y1026561I-1115J1928D01*
G01X1328041Y1026595D01*
G03X1326567I-737J-1277D01*
G02X1324381Y1026571I-1114J1928D01*
G01X1324340Y1026595D01*
G03X1322866I-737J-1277D01*
G02X1320640I-1113J1928D01*
G03X1319166I-737J-1277D01*
G02X1316940I-1113J1928D01*
G03X1315466I-737J-1277D01*
G02X1313240I-1113J1928D01*
G03X1311766I-737J-1277D01*
G02X1309540I-1113J1928D01*
G03X1308339Y1026721I-741J-1277D01*
G02X1306755Y1026641I-937J2824D01*
G02X1306082Y1027011I299J1341D01*
G01X1302986Y1030108D01*
X1301894D01*
X1301659Y1029873D01*
X1301567D01*
G01X1356904Y1031727D02*
X1355673D01*
X1355414Y1031986D01*
G03X1354340Y1033640I-2210J-259D01*
G01X1354316Y1033654D01*
X1354258Y1033688D01*
G03X1352090Y1033654I-1054J-1961D01*
G02X1350616I-737J1277D01*
G01X1350558Y1033688D01*
G03X1348390Y1033654I-1054J-1961D01*
G02X1346916I-737J1277D01*
G01X1346858Y1033688D01*
G03X1344690Y1033654I-1054J-1961D01*
G02X1343216I-737J1277D01*
G01X1343158Y1033688D01*
G03X1340990Y1033654I-1054J-1961D01*
G02X1339516I-737J1277D01*
G01X1339458Y1033688D01*
G03X1337290Y1033654I-1054J-1961D01*
G02X1335816I-737J1277D01*
G03X1333632Y1033678I-1113J-1927D01*
G01X1333591Y1033654D01*
G02X1332117I-737J1277D01*
G03X1329931Y1033678I-1114J-1927D01*
G01X1329890Y1033654D01*
G02X1328416I-737J1277D01*
G03X1326190I-1113J-1927D01*
G02X1324716I-737J1277D01*
G03X1322490I-1113J-1927D01*
G02X1321016I-737J1277D01*
G03X1318790I-1113J-1927D01*
G02X1317316I-737J1277D01*
G03X1315090I-1113J-1927D01*
G02X1313616I-737J1277D01*
G03X1311390I-1113J-1927D01*
G02X1309916I-737J1277D01*
G03X1309294Y1033899I-1117J-1925D01*
G02X1308211Y1034495I489J2170D01*
G01X1303654Y1039052D01*
X1301568D01*
G01X1358753Y1028523D02*
G03X1356167Y1030450I-9545J-10110D01*
G03X1353999Y1030484I-1114J-1927D01*
G01X1353941Y1030450D01*
G02X1352467I-737J1277D01*
G03X1350299Y1030484I-1114J-1927D01*
G01X1350241Y1030450D01*
G02X1348767I-737J1277D01*
G03X1346599Y1030484I-1114J-1927D01*
G01X1346541Y1030450D01*
G02X1345067I-737J1277D01*
G03X1342899Y1030484I-1114J-1927D01*
G01X1342841Y1030450D01*
G02X1341367I-737J1277D01*
G03X1339199Y1030484I-1114J-1927D01*
G01X1339141Y1030450D01*
G02X1337667I-737J1277D01*
G03X1335481Y1030474I-1114J-1927D01*
G01X1335440Y1030450D01*
G02X1333966I-737J1277D01*
G03X1331740I-1113J-1927D01*
G02X1330266I-737J1277D01*
G03X1328082Y1030474I-1113J-1927D01*
G01X1328041Y1030450D01*
G02X1326567I-737J1276D01*
G03X1324381Y1030474I-1114J-1927D01*
G01X1324340Y1030450D01*
G02X1322866I-737J1277D01*
G03X1320640I-1113J-1927D01*
G02X1319166I-737J1277D01*
G03X1316940I-1113J-1927D01*
G02X1315466I-737J1277D01*
G03X1313240I-1113J-1927D01*
G02X1311766I-737J1277D01*
G03X1309540I-1113J-1927D01*
G02X1308066I-737J1277D01*
G03X1306953Y1030748I-1112J-1927D01*
G01X1306511D01*
X1305614Y1031645D01*
Y1033504D01*
X1304090Y1035028D01*
X1301568D01*
G01X1360604Y1025318D02*
X1359371D01*
X1359114Y1025575D01*
G03X1359103Y1025658I-2213J-251D01*
G03X1358016Y1027246I-2201J-340D01*
G03X1355848Y1027280I-1115J-1928D01*
G01X1355790Y1027246D01*
G02X1354316I-737J1277D01*
G01X1354258Y1027280D01*
G03X1352090Y1027246I-1053J-1962D01*
G02X1350616I-737J1277D01*
G03X1348448Y1027280I-1115J-1928D01*
G01X1348390Y1027246D01*
G02X1346916I-737J1277D01*
G01X1346858Y1027280D01*
G03X1344690Y1027246I-1053J-1962D01*
G02X1343216I-737J1277D01*
G01X1343158Y1027280D01*
G03X1340990Y1027246I-1053J-1962D01*
G02X1339516I-737J1277D01*
G03X1337290I-1113J-1928D01*
G02X1335816I-737J1277D01*
G01X1335758Y1027280D01*
G03X1333590Y1027246I-1053J-1962D01*
G02X1332116I-737J1277D01*
G01X1332058Y1027280D01*
G03X1329890Y1027246I-1053J-1962D01*
G02X1328416I-737J1277D01*
G01X1328358Y1027280D01*
G03X1326190Y1027246I-1053J-1962D01*
G02X1324716I-737J1277D01*
G03X1322490I-1113J-1928D01*
G02X1321016I-737J1277D01*
G03X1318790I-1113J-1928D01*
G02X1317316I-737J1277D01*
G03X1315090I-1113J-1928D01*
G02X1313616I-737J1277D01*
G03X1311390I-1113J-1928D01*
G02X1309916I-737J1277D01*
G03X1308103Y1027432I-1114J-1928D01*
G02X1306919Y1027372I-701J2113D01*
G02X1306613Y1027541I137J609D01*
G01X1303297Y1030857D01*
X1301895D01*
X1301659Y1031093D01*
X1301567D01*
G01X1358753Y1041340D02*
X1356555Y1039641D01*
X1356228Y1039449D01*
G02X1353988Y1039443I-1125J1921D01*
G03X1352509Y1039438I-735J-1274D01*
G01X1352408Y1039379D01*
G02X1350240Y1039413I-1054J1961D01*
G03X1348766I-737J-1277D01*
G02X1346582Y1039389I-1113J1927D01*
G01X1346541Y1039413D01*
G03X1345067I-737J-1277D01*
G02X1342899Y1039379I-1114J1927D01*
G01X1342841Y1039413D01*
G03X1341367I-737J-1277D01*
G02X1339199Y1039379I-1114J1927D01*
G01X1339141Y1039413D01*
G03X1337667I-737J-1277D01*
G02X1335441I-1113J1927D01*
G03X1333967I-737J-1277D01*
G02X1331781Y1039389I-1114J1927D01*
G01X1331740Y1039413D01*
G03X1330266I-737J-1277D01*
G02X1328040I-1113J1927D01*
G03X1326566I-737J-1277D01*
G02X1324340I-1113J1927D01*
G03X1322866I-737J-1277D01*
G02X1320640I-1113J1927D01*
G03X1319166I-737J-1277D01*
G02X1316940I-1113J1927D01*
G03X1315466I-737J-1277D01*
G02X1313240I-1113J1927D01*
G03X1311766I-737J-1277D01*
G02X1309540I-1113J1927D01*
G02X1309079Y1039766I1111J1928D01*
G01X1308063Y1040782D01*
Y1042089D01*
X1306425Y1043727D01*
Y1045316D01*
X1305236Y1046505D01*
X1303068D01*
G01X1356904Y1038136D02*
X1355672D01*
X1355413Y1037877D01*
G02X1354316Y1036209I-2210J259D01*
G02X1352114Y1036195I-1113J1927D01*
G01X1352091Y1036208D01*
X1352068Y1036222D01*
G03X1350616Y1036209I-715J-1291D01*
G02X1348414Y1036195I-1113J1927D01*
G01X1348391Y1036208D01*
X1348368Y1036222D01*
G03X1346916Y1036209I-715J-1291D01*
G02X1344714Y1036195I-1113J1927D01*
G01X1344691Y1036208D01*
X1344668Y1036222D01*
G03X1343216Y1036209I-715J-1291D01*
G02X1341014Y1036195I-1113J1927D01*
G01X1340991Y1036208D01*
X1340968Y1036222D01*
G03X1339516Y1036209I-715J-1291D01*
G02X1337314Y1036195I-1113J1927D01*
G01X1337291Y1036208D01*
X1337268Y1036222D01*
G03X1335816Y1036209I-715J-1291D01*
G02X1333614Y1036195I-1113J1927D01*
G01X1333591Y1036208D01*
X1333568Y1036222D01*
G03X1332116Y1036209I-715J-1291D01*
G02X1329905Y1036200I-1113J1927D01*
G01X1329891Y1036208D01*
G03X1328416I-737J-1277D01*
G02X1326209Y1036198I-1112J1927D01*
G01X1326191Y1036208D01*
X1326168Y1036222D01*
G03X1324716Y1036209I-715J-1291D01*
G01Y1036208D01*
G02X1322490I-1113J1928D01*
G03X1321016I-737J-1277D01*
G02X1318790I-1113J1928D01*
G03X1317316I-737J-1277D01*
G02X1315090I-1113J1928D01*
G03X1313616I-737J-1277D01*
G02X1311390I-1113J1928D01*
G03X1310028Y1036267I-738J-1277D01*
G02X1308845Y1036239I-623J1335D01*
G01X1308094Y1036546D01*
G02X1307805Y1036738I332J813D01*
G01X1306871Y1037672D01*
Y1039445D01*
X1304116Y1042200D01*
X1303068D01*
G01X1358753Y1047749D02*
G03X1357440Y1047404I-1J-2666D01*
G01X1355768Y1046458D01*
G02X1354316Y1046471I-715J1290D01*
G03X1352114Y1046484I-1112J-1927D01*
G01X1352068Y1046458D01*
G02X1350616Y1046471I-715J1290D01*
G02X1349878Y1047037I1782J3087D01*
G02X1349593Y1047463I929J930D01*
G01X1349481Y1047734D01*
G03X1348908Y1048726I-1145J0D01*
G01X1348390Y1049025D01*
G03X1346916I-737J-1276D01*
G01X1346858Y1048991D01*
G02X1344690Y1049025I-1054J1961D01*
G03X1343216I-737J-1276D01*
G01X1343158Y1048991D01*
G02X1340990Y1049025I-1054J1961D01*
G03X1339516I-737J-1276D01*
G01X1339458Y1048991D01*
G02X1337290Y1049025I-1054J1961D01*
G03X1335816I-737J-1276D01*
G02X1333590I-1113J1927D01*
G03X1332116I-737J-1276D01*
G02X1329890I-1113J1927D01*
G03X1328416I-737J-1276D01*
G02X1326190I-1113J1927D01*
G03X1324716I-737J-1276D01*
G02X1322490I-1113J1927D01*
G03X1321016I-737J-1276D01*
G02X1318790I-1113J1927D01*
G03X1317316I-737J-1276D01*
G02X1315090I-1113J1927D01*
G03X1313616I-737J-1276D01*
G02X1311390I-1113J1927D01*
G02X1310278Y1050913I1113J1927D01*
G01Y1050952D01*
G03X1309575Y1052209I-1475J0D01*
G02X1309079Y1052583I1079J1947D01*
G01X1308625Y1053037D01*
Y1054778D01*
X1306397Y1057006D01*
X1303068D01*
G01X1356904Y1044544D02*
X1358135D01*
X1358361Y1044318D01*
G02X1356167Y1043267I-1457J225D01*
G03X1353999Y1043301I-1114J-1927D01*
G01X1353941Y1043267D01*
G02X1352467I-737J1277D01*
G03X1350299Y1043301I-1114J-1927D01*
G01X1350241Y1043267D01*
G02X1348767I-737J1277D01*
G03X1346599Y1043301I-1114J-1927D01*
G01X1346541Y1043267D01*
G02X1345067I-737J1277D01*
G03X1342899Y1043301I-1114J-1927D01*
G01X1342841Y1043267D01*
G02X1341367I-737J1277D01*
G03X1339181Y1043291I-1114J-1927D01*
G01X1339140Y1043267D01*
G02X1337666I-737J1277D01*
G01X1337625Y1043291D01*
G03X1335441Y1043267I-1071J-1951D01*
G02X1333967I-737J1277D01*
G03X1331781Y1043291I-1114J-1927D01*
G01X1331740Y1043267D01*
G02X1330266I-737J1277D01*
G03X1328040I-1113J-1927D01*
G02X1326566I-737J1277D01*
G03X1324340I-1113J-1927D01*
G02X1322866I-737J1277D01*
G03X1320640I-1113J-1927D01*
G02X1319166I-737J1277D01*
G03X1316940I-1113J-1927D01*
G02X1315466I-737J1277D01*
G03X1313240I-1113J-1927D01*
G02X1311028Y1044544I-737J1277D01*
G01Y1044583D01*
G03X1309916Y1046471I-2225J-39D01*
G02X1309609Y1046705I733J1281D01*
G01X1304795Y1051519D01*
X1303396D01*
X1303160Y1051755D01*
X1303068D01*
G01X1360604Y1044544D02*
X1359373D01*
X1359114Y1044285D01*
G02X1359103Y1044203I-2210J255D01*
G02X1358040Y1042631I-2199J341D01*
G01X1358019Y1042619D01*
X1358016Y1042617D01*
X1357958Y1042583D01*
G02X1355790Y1042617I-1054J1961D01*
G03X1354316I-737J-1277D01*
G01X1354258Y1042583D01*
G02X1352090Y1042617I-1054J1961D01*
G03X1350616I-737J-1277D01*
G01X1350558Y1042583D01*
G02X1348390Y1042617I-1054J1961D01*
G03X1346916I-737J-1277D01*
G01X1346858Y1042583D01*
G02X1344690Y1042617I-1054J1961D01*
G03X1343216I-737J-1277D01*
G01X1343158Y1042583D01*
G02X1340990Y1042617I-1054J1961D01*
G03X1339516I-737J-1277D01*
G02X1337332Y1042593I-1113J1927D01*
G01X1337291Y1042617D01*
G03X1335817I-737J-1277D01*
G01X1335776Y1042593D01*
G02X1333590Y1042617I-1072J1951D01*
G03X1332116I-737J-1277D01*
G02X1329890I-1113J1927D01*
G03X1328416I-737J-1277D01*
G02X1326190I-1113J1927D01*
G03X1324716I-737J-1277D01*
G02X1322490I-1113J1927D01*
G03X1321016I-737J-1277D01*
G02X1318790I-1113J1927D01*
G03X1317316I-737J-1277D01*
G02X1315090I-1113J1927D01*
G03X1313616I-737J-1277D01*
G02X1310278Y1044505I-1113J1927D01*
G01Y1044544D01*
G03X1309575Y1045801I-1475J0D01*
G01X1309540Y1045821D01*
G02X1309079Y1046175I1114J1928D01*
G01X1304484Y1050770D01*
X1303395D01*
X1303160Y1050535D01*
X1303068D01*
G01X1356904Y1050952D02*
X1354435Y1049093D01*
X1354316Y1049025D01*
X1354258Y1048991D01*
G02X1352090Y1049025I-1054J1961D01*
G02X1350979Y1050891I1114J1927D01*
G01Y1050952D01*
G03X1350276Y1052209I-1475J0D01*
G01X1350241Y1052229D01*
G03X1348767I-737J-1277D01*
G02X1346599Y1052195I-1115J1928D01*
G01X1346541Y1052229D01*
G03X1345067I-737J-1277D01*
G02X1342899Y1052195I-1115J1928D01*
G01X1342841Y1052229D01*
G03X1341367I-737J-1277D01*
G02X1339199Y1052195I-1115J1928D01*
G01X1339141Y1052229D01*
G03X1337667I-737J-1277D01*
G02X1335481Y1052205I-1114J1928D01*
G01X1335440Y1052229D01*
G03X1333966I-737J-1277D01*
G01X1333908Y1052195D01*
G02X1331740Y1052229I-1053J1962D01*
G03X1330266I-737J-1277D01*
G02X1328082Y1052205I-1113J1928D01*
G01X1328040Y1052229D01*
G03X1326566I-737J-1277D01*
G02X1324340I-1113J1928D01*
G03X1322866I-737J-1277D01*
G02X1320640I-1113J1928D01*
G03X1319166I-737J-1277D01*
G02X1316940I-1113J1928D01*
G03X1315466I-737J-1277D01*
G02X1313240I-1113J1928D01*
G02X1312128Y1054084I1113J1928D01*
G01Y1054157D01*
G03X1311425Y1055414I-1475J0D01*
G02X1310929Y1055787I1077J1948D01*
G01X1305390Y1061326D01*
X1303068D01*
G01X1356904Y1057361D02*
X1355673D01*
X1355414Y1057102D01*
G02X1354340Y1055448I-2210J259D01*
G01X1354316Y1055434D01*
X1354258Y1055400D01*
G02X1352090Y1055434I-1054J1961D01*
G03X1350616I-737J-1277D01*
G02X1348390I-1113J1927D01*
G03X1346916I-737J-1277D01*
G01X1346858Y1055400D01*
G02X1344690Y1055434I-1054J1961D01*
G03X1343216I-737J-1277D01*
G01X1343158Y1055400D01*
G02X1340990Y1055434I-1054J1961D01*
G03X1339516I-737J-1277D01*
G01X1339458Y1055400D01*
G02X1337290Y1055434I-1054J1961D01*
G03X1335816I-737J-1277D01*
G01X1335775Y1055410D01*
G02X1333591Y1055434I-1071J1951D01*
G03X1332117I-737J-1277D01*
G02X1329931Y1055410I-1114J1927D01*
G01X1329890Y1055434D01*
G03X1328416I-737J-1277D01*
G02X1326190I-1113J1927D01*
G03X1324716I-737J-1277D01*
G02X1322490I-1113J1927D01*
G03X1321016I-737J-1277D01*
G02X1318790I-1113J1927D01*
G03X1317316I-737J-1277D01*
G02X1315090I-1113J1927D01*
G02X1313978Y1057322I1113J1927D01*
G01Y1057361D01*
G03X1313275Y1058618I-1475J0D01*
G02X1312779Y1058991I1077J1948D01*
G01X1311250Y1060520D01*
X1308912D01*
X1307567Y1061865D01*
Y1064381D01*
X1305270Y1066678D01*
X1304264D01*
G01X1358753Y1060565D02*
X1356555Y1058866D01*
X1356228Y1058674D01*
G02X1353988Y1058668I-1125J1921D01*
G03X1352509Y1058663I-735J-1274D01*
G01X1352408Y1058604D01*
G02X1350240Y1058638I-1054J1961D01*
G03X1348766I-737J-1277D01*
G02X1346582Y1058614I-1113J1927D01*
G01X1346541Y1058638D01*
G03X1345067I-737J-1277D01*
G02X1342899Y1058604I-1114J1927D01*
G01X1342841Y1058638D01*
G03X1341367I-737J-1277D01*
G02X1339199Y1058604I-1114J1927D01*
G01X1339141Y1058638D01*
G03X1337667I-737J-1277D01*
G02X1335441I-1113J1927D01*
G03X1333967I-737J-1277D01*
G02X1331781Y1058614I-1114J1927D01*
G01X1331740Y1058638D01*
G03X1330266I-737J-1277D01*
G02X1328040I-1113J1927D01*
G03X1326566I-737J-1277D01*
G02X1324340I-1113J1927D01*
G03X1322866I-737J-1277D01*
G02X1320640I-1113J1927D01*
G03X1319166I-737J-1277D01*
G02X1316940I-1113J1927D01*
G02X1315828Y1060526I1113J1927D01*
G01Y1060565D01*
G03X1315125Y1061822I-1475J0D01*
G02X1314629Y1062196I1079J1947D01*
G01X1313905Y1062920D01*
X1312512D01*
X1310764Y1064668D01*
X1309739D01*
X1306247Y1068160D01*
Y1069662D01*
X1305182Y1070727D01*
X1304264D01*
G01X1360604Y1063770D02*
X1357759Y1064979D01*
X1357649Y1065043D01*
X1357641Y1065047D01*
G03X1356167I-737J-1277D01*
G01X1356132Y1065027D01*
G03X1355429Y1063770I772J-1257D01*
G01Y1063384D01*
X1355348Y1063306D01*
X1353940Y1062493D01*
X1353941D01*
G02X1352467I-737J1277D01*
G03X1350299Y1062527I-1115J-1928D01*
G01X1350241Y1062493D01*
G02X1348767I-737J1277D01*
G03X1346599Y1062527I-1115J-1928D01*
G01X1346541Y1062493D01*
G02X1345067I-737J1277D01*
G03X1342899Y1062527I-1115J-1928D01*
G01X1342841Y1062493D01*
G02X1341367I-737J1277D01*
G03X1339181Y1062517I-1114J-1928D01*
G01X1339140Y1062493D01*
G02X1337666I-737J1277D01*
G01X1337625Y1062517D01*
G03X1335441Y1062493I-1071J-1952D01*
G02X1333967I-737J1277D01*
G03X1331781Y1062517I-1114J-1928D01*
G01X1331740Y1062493D01*
G02X1330266I-737J1277D01*
G03X1328040I-1113J-1928D01*
G02X1326566I-737J1277D01*
G03X1324340I-1113J-1928D01*
G02X1322866I-737J1277D01*
G03X1320640I-1113J-1928D01*
G02X1319166I-737J1277D01*
G01X1319131Y1062513D01*
G02X1318428Y1063770I772J1257D01*
G01Y1063809D01*
G03X1317316Y1065697I-2225J-39D01*
G03X1315090I-1113J-1927D01*
G02X1313616I-737J1277D01*
G01X1313581Y1065717D01*
G02X1312878Y1066974I772J1257D01*
G01Y1066993D01*
X1312877Y1066994D01*
G03X1310655Y1069199I-2225J-20D01*
G01X1309863D01*
X1308540Y1070522D01*
Y1071414D01*
X1306783Y1073171D01*
Y1074695D01*
X1305682Y1075796D01*
X1304592D01*
X1304356Y1076032D01*
X1304264D01*
G01X1356904Y1063770D02*
X1355804Y1062703D01*
X1354328Y1061850D01*
X1354325Y1061848D01*
X1354258Y1061809D01*
G02X1352090Y1061843I-1054J1961D01*
G01Y1061842D01*
G03X1350616I-737J-1277D01*
G01X1350558Y1061808D01*
G02X1348390Y1061842I-1053J1962D01*
G03X1346916I-737J-1277D01*
G01X1346858Y1061808D01*
G02X1344690Y1061842I-1053J1962D01*
G03X1343216I-737J-1277D01*
G01X1343158Y1061808D01*
G02X1340990Y1061842I-1053J1962D01*
G03X1339516I-737J-1277D01*
G02X1337332Y1061818I-1113J1928D01*
G01X1337291Y1061842D01*
G03X1335817I-737J-1277D01*
G01X1335776Y1061818D01*
G02X1333590Y1061842I-1072J1952D01*
G03X1332116I-737J-1277D01*
G02X1329890I-1113J1928D01*
G03X1328416I-737J-1277D01*
G02X1326190I-1113J1928D01*
G03X1324716I-737J-1277D01*
G02X1322490I-1113J1928D01*
G03X1321016I-737J-1277D01*
G02X1318790I-1113J1928D01*
G02X1317678Y1063697I1113J1928D01*
G01Y1063770D01*
G03X1316975Y1065027I-1475J0D01*
G01X1316940Y1065047D01*
G03X1315466I-737J-1277D01*
G02X1313240I-1113J1927D01*
G02X1312128Y1066935I1113J1927D01*
G01Y1066974D01*
G03X1310654Y1068450I-1476J0D01*
G01X1309552D01*
X1307791Y1070211D01*
Y1071103D01*
X1306034Y1072860D01*
Y1074384D01*
X1305371Y1075047D01*
X1304591D01*
X1304356Y1074812D01*
X1304264D01*
G01X1356904Y1070178D02*
X1354435Y1068319D01*
X1354316Y1068251D01*
X1354258Y1068217D01*
G02X1352090Y1068251I-1054J1961D01*
G02X1350979Y1070117I1114J1927D01*
G01Y1070178D01*
G03X1350276Y1071435I-1475J0D01*
G01X1350241Y1071455D01*
G03X1348767I-737J-1277D01*
G02X1346599Y1071421I-1115J1928D01*
G01X1346541Y1071455D01*
G03X1345067I-737J-1277D01*
G02X1342899Y1071421I-1115J1928D01*
G01X1342841Y1071455D01*
G03X1341367I-737J-1277D01*
G02X1339199Y1071421I-1115J1928D01*
G01X1339141Y1071455D01*
G03X1337667I-737J-1277D01*
G02X1335481Y1071431I-1114J1928D01*
G01X1335440Y1071455D01*
G03X1333966I-737J-1277D01*
G01X1333908Y1071421D01*
G02X1331740Y1071455I-1053J1962D01*
G03X1330266I-737J-1277D01*
G02X1328082Y1071431I-1113J1928D01*
G01X1328041Y1071455D01*
G03X1326567I-737J-1277D01*
G01X1326526Y1071431D01*
G02X1324340Y1071455I-1072J1952D01*
G02X1323228Y1073327I1114J1928D01*
G01Y1073383D01*
G03X1322525Y1074640I-1475J0D01*
G01X1322490Y1074660D01*
G03X1321016I-737J-1277D01*
G02X1318832Y1074636I-1113J1927D01*
G01X1318791Y1074660D01*
X1318767Y1074674D01*
G02X1317678Y1076587I1136J1913D01*
G01Y1076621D01*
G03X1316941Y1077864I-1474J-34D01*
G03X1315467I-737J-1277D01*
G02X1313299Y1077830I-1114J1927D01*
G01X1313241Y1077864D01*
G02X1312141Y1078635I3860J6678D01*
G01X1311917Y1078859D01*
Y1080106D01*
X1310088Y1081935D01*
X1308799D01*
X1305176Y1085558D01*
X1304264D01*
G01X1358753Y1066974D02*
G03X1357437Y1066628I-1J-2670D01*
G01X1355768Y1065684D01*
G02X1354316Y1065697I-715J1290D01*
G03X1352114Y1065710I-1112J-1927D01*
G01X1352068Y1065684D01*
G02X1350616Y1065697I-715J1290D01*
G02X1349878Y1066263I1782J3087D01*
G02X1349593Y1066689I929J930D01*
G01X1349481Y1066960D01*
G03X1349223Y1067583I-881J0D01*
G01X1349098Y1067709D01*
G03X1348393Y1068250I-2405J-2405D01*
G01X1348391Y1068251D01*
G03X1346917I-737J-1277D01*
G01X1346876Y1068227D01*
G02X1344690Y1068251I-1072J1951D01*
G03X1343216I-737J-1277D01*
G01X1343158Y1068217D01*
G02X1340990Y1068251I-1054J1961D01*
G03X1339516I-737J-1277D01*
G01X1339458Y1068217D01*
G02X1337290Y1068251I-1054J1961D01*
G03X1335816I-737J-1277D01*
G02X1333590I-1113J1927D01*
G03X1332116I-737J-1277D01*
G02X1329890I-1113J1927D01*
G03X1328416I-737J-1277D01*
G01X1328358Y1068217D01*
G02X1326190Y1068251I-1054J1961D01*
G03X1324716I-737J-1277D01*
G02X1322490I-1113J1927D01*
G02X1321378Y1070139I1113J1927D01*
G01Y1070178D01*
G03X1320675Y1071435I-1475J0D01*
G01X1320640Y1071455D01*
G03X1319166I-737J-1277D01*
G01X1319108Y1071421D01*
G02X1316940Y1071455I-1053J1962D01*
G02X1315828Y1073327I1114J1928D01*
G01Y1073383D01*
G03X1315125Y1074640I-1475J0D01*
G01X1315090Y1074660D01*
G03X1313616I-737J-1277D01*
G01X1313575Y1074636D01*
G02X1311391Y1074660I-1071J1951D01*
G02X1310930Y1075013I1111J1928D01*
G01X1310660Y1075665D01*
Y1077376D01*
X1306465Y1081571D01*
X1304264D01*
G01X1366153Y1002888D02*
X1363410Y1001727D01*
X1363268Y1001654D01*
X1363167Y1001597D01*
X1363034Y1001515D01*
X1362840Y1001365D01*
X1362664Y1001194D01*
X1362508Y1001004D01*
X1362374Y1000798D01*
X1362263Y1000579D01*
X1362177Y1000349D01*
X1362117Y1000112D01*
X1362083Y999868D01*
X1362079Y999715D01*
Y998287D01*
X1360112Y996320D01*
Y995202D01*
G01X1369853Y1002888D02*
X1367921Y1002019D01*
G02X1365121Y1001189I-2131J2051D01*
G03X1363566Y1000961I-487J-2098D01*
G01X1363531Y1000941D01*
G03X1362828Y999684I772J-1257D01*
G01Y997636D01*
X1362094Y996902D01*
Y995202D01*
G01X1364304Y999684D02*
X1364303Y996189D01*
Y995202D01*
G01X1371704Y999684D02*
X1370312Y998292D01*
Y995202D01*
G01X1374971Y973143D02*
X1372251Y975015D01*
G02X1371982Y975238I1083J1580D01*
G01X1371594Y975626D01*
G02X1371401Y975915I634J632D01*
G03X1370157Y977624I-2545J-545D01*
G03X1368683I-737J-1277D01*
G01X1368625Y977590D01*
G02X1366457Y977624I-1053J1962D01*
G03X1364983I-737J-1277D01*
G01X1364942Y977600D01*
G02X1362758Y977624I-1071J1952D01*
G03X1361284I-737J-1277D01*
G01X1361243Y977600D01*
G02X1359057Y977624I-1072J1952D01*
G03X1357583I-737J-1277D01*
G01X1357542Y977600D01*
G02X1355358Y977624I-1071J1952D01*
G03X1353884I-737J-1277D01*
G01X1353843Y977600D01*
G02X1351657Y977624I-1072J1952D01*
G03X1350183I-737J-1277D01*
G02X1347957I-1113J1928D01*
G03X1346483I-737J-1277D01*
G01X1346425Y977590D01*
G02X1344257Y977624I-1053J1962D01*
G03X1342783I-737J-1277D01*
G01X1342725Y977590D01*
G02X1340557Y977624I-1053J1962D01*
G03X1339083I-737J-1277D01*
G01X1339042Y977600D01*
G02X1336858Y977624I-1071J1952D01*
G03X1335384I-737J-1277D01*
G01X1335343Y977600D01*
G02X1333157Y977624I-1072J1952D01*
G03X1331683I-737J-1277D01*
G01X1331642Y977600D01*
G02X1329458Y977624I-1071J1952D01*
G03X1327984I-737J-1277D01*
G01X1327943Y977600D01*
G02X1325757Y977624I-1072J1952D01*
G03X1324283I-737J-1277D01*
G01X1324242Y977600D01*
G02X1322058Y977624I-1071J1952D01*
G03X1320584I-737J-1277D01*
G02X1318358I-1113J1928D01*
G02X1317246Y979479I1113J1928D01*
G01Y979552D01*
G03X1316543Y980809I-1475J0D01*
G01X1316508Y980829D01*
G03X1315034I-737J-1277D01*
G02X1312866Y980795I-1114J1927D01*
G01X1312808Y980829D01*
G02X1312347Y981183I1113J1926D01*
G01X1312044Y981486D01*
X1304963D01*
G01X1378671Y979552D02*
X1376021Y978455D01*
X1376019D01*
X1375707Y978275D01*
G02X1374233I-737J1277D01*
G03X1372049Y978299I-1113J-1928D01*
G01X1372008Y978275D01*
G02X1370534I-737J1277D01*
G03X1368366Y978309I-1115J-1928D01*
G01X1368308Y978275D01*
G02X1366834I-737J1277D01*
G03X1364666Y978309I-1115J-1928D01*
G01X1364639Y978293D01*
X1364608Y978275D01*
G02X1363134I-737J1277D01*
G03X1360908I-1113J-1928D01*
G02X1359434I-737J1277D01*
G03X1357266Y978309I-1115J-1928D01*
G01X1357208Y978275D01*
G02X1355734I-737J1277D01*
G03X1353508I-1113J-1928D01*
G02X1352034I-737J1277D01*
G03X1349848Y978299I-1114J-1928D01*
G01X1349807Y978275D01*
G02X1348333I-737J1277D01*
G03X1346149Y978299I-1113J-1928D01*
G01X1346108Y978275D01*
G02X1344634I-737J1277D01*
G03X1342466Y978309I-1115J-1928D01*
G01X1342408Y978275D01*
G02X1340934I-737J1277D01*
G03X1338766Y978309I-1115J-1928D01*
G01X1338708Y978275D01*
G02X1337234I-737J1277D01*
G03X1335008I-1113J-1928D01*
G02X1333534I-737J1277D01*
G03X1331366Y978309I-1115J-1928D01*
G01X1331308Y978275D01*
G02X1329834I-737J1277D01*
G03X1327608I-1113J-1928D01*
G02X1326134I-737J1277D01*
G03X1323966Y978309I-1115J-1928D01*
G01X1323908Y978275D01*
G02X1322434I-737J1277D01*
G03X1320208I-1113J-1928D01*
G02X1318734I-737J1277D01*
G01X1318699Y978295D01*
G02X1317996Y979552I772J1257D01*
G03X1316907Y981465I-2225J0D01*
G01X1316883Y981479D01*
X1316825Y981513D01*
G03X1314657Y981479I-1054J-1961D01*
G02X1313183I-737J1277D01*
G02X1312877Y981713I735J1278D01*
G01X1310634Y983956D01*
X1304963D01*
G01X1376820Y976347D02*
X1377436Y975280D01*
X1377341Y974929D01*
G03X1376446Y973204I1330J-1785D01*
G01Y973143D01*
G02X1375743Y971886I-1475J0D01*
G01X1375708Y971866D01*
G02X1374234I-737J1277D01*
G03X1372008I-1113J-1927D01*
G02X1370534I-737J1277D01*
G01X1370499Y971886D01*
G02X1369796Y973143I772J1257D01*
G03X1368707Y975056I-2225J0D01*
G01X1368683Y975070D01*
X1368625Y975104D01*
G03X1366457Y975070I-1054J-1961D01*
G02X1364983I-737J1277D01*
G03X1362799Y975094I-1113J-1927D01*
G01X1362758Y975070D01*
G02X1361284I-737J1277D01*
G01X1361243Y975094D01*
G03X1359057Y975070I-1072J-1951D01*
G02X1357583I-737J1277D01*
G03X1355399Y975094I-1113J-1927D01*
G01X1355358Y975070D01*
G02X1353884I-737J1277D01*
G01X1353843Y975094D01*
G03X1351657Y975070I-1072J-1951D01*
G02X1350183I-737J1277D01*
G01X1350125Y975104D01*
G03X1347957Y975070I-1054J-1961D01*
G02X1346483I-737J1277D01*
G01X1346425Y975104D01*
G03X1344257Y975070I-1054J-1961D01*
G02X1342783I-737J1277D01*
G01X1342725Y975104D01*
G03X1340557Y975070I-1054J-1961D01*
G02X1339083I-737J1277D01*
G03X1336899Y975094I-1113J-1927D01*
G01X1336858Y975070D01*
G02X1335384I-737J1277D01*
G01X1335343Y975094D01*
G03X1333157Y975070I-1072J-1951D01*
G02X1331683I-737J1277D01*
G03X1329499Y975094I-1113J-1927D01*
G01X1329458Y975070D01*
G02X1327984I-737J1277D01*
G01X1327943Y975094D01*
G03X1325757Y975070I-1072J-1951D01*
G02X1324283I-737J1277D01*
G01X1324242Y975094D01*
G03X1322058Y975070I-1071J-1951D01*
G02X1320584I-737J1277D01*
G03X1318358I-1113J-1927D01*
G02X1316884I-737J1277D01*
G03X1314658I-1113J-1927D01*
G02X1313184I-737J1277D01*
G03X1310958I-1113J-1927D01*
G02X1309484I-737J1277D01*
G02X1309177Y975303I731J1282D01*
G01X1307316Y977164D01*
X1306283Y977592D01*
X1304963D01*
G01X1378671Y973143D02*
X1378055Y974210D01*
X1377747Y974292D01*
G03X1377196Y973143I924J-1150D01*
G02X1376107Y971230I-2225J0D01*
G01X1376083Y971216D01*
X1376042Y971192D01*
G02X1373858Y971216I-1071J1951D01*
G03X1372384I-737J-1277D01*
G01X1372343Y971192D01*
G02X1370157Y971216I-1072J1951D01*
G02X1369046Y973082I1114J1927D01*
G01Y973143D01*
G03X1368343Y974400I-1475J0D01*
G01X1368308Y974420D01*
G03X1366834I-737J-1277D01*
G02X1364648Y974396I-1114J1927D01*
G01X1364639Y974401D01*
X1364607Y974420D01*
G03X1363133I-737J-1277D01*
G01X1363092Y974396D01*
G02X1360908Y974420I-1071J1951D01*
G03X1359434I-737J-1277D01*
G02X1357248Y974396I-1114J1927D01*
G01X1357207Y974420D01*
G03X1355733I-737J-1277D01*
G01X1355692Y974396D01*
G02X1353508Y974420I-1071J1951D01*
G03X1352034I-737J-1277D01*
G02X1349866Y974386I-1114J1927D01*
G01X1349808Y974420D01*
G03X1348334I-737J-1277D01*
G02X1346166Y974386I-1114J1927D01*
G01X1346108Y974420D01*
G03X1344634I-737J-1277D01*
G02X1342466Y974386I-1114J1927D01*
G01X1342408Y974420D01*
G03X1340934I-737J-1277D01*
G02X1338748Y974396I-1114J1927D01*
G01X1338707Y974420D01*
G03X1337233I-737J-1277D01*
G01X1337192Y974396D01*
G02X1335008Y974420I-1071J1951D01*
G03X1333534I-737J-1277D01*
G02X1331348Y974396I-1114J1927D01*
G01X1331307Y974420D01*
G03X1329833I-737J-1277D01*
G01X1329792Y974396D01*
G02X1327608Y974420I-1071J1951D01*
G03X1326134I-737J-1277D01*
G02X1323966Y974386I-1114J1927D01*
G01X1323908Y974420D01*
G03X1322434I-737J-1277D01*
G02X1320208I-1113J1927D01*
G03X1318734I-737J-1277D01*
G02X1316508I-1113J1927D01*
G03X1315034I-737J-1277D01*
G02X1312808I-1113J1927D01*
G03X1311334I-737J-1277D01*
G02X1309108I-1113J1927D01*
G02X1308647Y974773I1111J1928D01*
G01X1307260Y976160D01*
X1304963D01*
G01X1525009Y883785D02*
X1522955Y885839D01*
Y886949D01*
X1521810Y888094D01*
Y888095D01*
X1515295Y894610D01*
G03X1514834Y894963I-1572J-1575D01*
G03X1512608I-1113J-1927D01*
G02X1511134I-737J1277D01*
G03X1508908I-1113J-1927D01*
G02X1507434I-737J1277D01*
G03X1505266Y894997I-1114J-1927D01*
G01X1505208Y894963D01*
G02X1503734I-737J1277D01*
G03X1501508I-1113J-1927D01*
G02X1500034I-737J1277D01*
G03X1497866Y894997I-1114J-1927D01*
G01X1497808Y894963D01*
G02X1496334I-737J1277D01*
G03X1494166Y894997I-1114J-1927D01*
G01X1494108Y894963D01*
G02X1492634I-737J1277D01*
G03X1490408I-1113J-1927D01*
G02X1488934I-737J1277D01*
G03X1486766Y894997I-1114J-1927D01*
G01X1486708Y894963D01*
G02X1485234I-737J1277D01*
G01X1485199Y894983D01*
G02X1484496Y896240I772J1257D01*
G01Y896270D01*
G03X1483383Y898168I-2226J-30D01*
G01X1483348Y898188D01*
G02X1482645Y899445I772J1257D01*
G01Y899506D01*
G03X1481534Y901372I-2225J-61D01*
G03X1479137Y901235I-1094J-1893D01*
G01X1476720Y899445D01*
G01X1527565Y904731D02*
X1526746D01*
X1526368Y905109D01*
Y906516D01*
X1525493Y907391D01*
X1524085D01*
X1520845Y910631D01*
G03X1518158Y910985I-1574J-1574D01*
G02X1516684I-737J1277D01*
G03X1514458I-1113J-1928D01*
G02X1512984I-737J1277D01*
G03X1510758I-1113J-1928D01*
G02X1509284I-737J1277D01*
G03X1507058I-1113J-1928D01*
G02X1505584I-737J1277D01*
G03X1503358I-1113J-1928D01*
G02X1501884I-737J1277D01*
G01X1501843Y911009D01*
G03X1499657Y910985I-1072J-1952D01*
G02X1498183I-737J1277D01*
G03X1495957I-1113J-1928D01*
G02X1494483I-737J1277D01*
G01X1494448Y911005D01*
G02X1493745Y912262I772J1257D01*
G01Y912323D01*
G03X1492634Y914189I-2225J-61D01*
G03X1490466Y914223I-1114J-1927D01*
G01X1490408Y914189D01*
G02X1488934I-737J1277D01*
G03X1486766Y914223I-1114J-1927D01*
G01X1486708Y914189D01*
G02X1485234I-737J1277D01*
G03X1483008I-1113J-1927D01*
G02X1481534I-737J1277D01*
G03X1479366Y914223I-1114J-1927D01*
G01X1479308Y914189D01*
X1479189Y914121D01*
X1476720Y912262D01*
G01X1524465Y900764D02*
X1523916D01*
X1523303Y901377D01*
Y903119D01*
X1518995Y907427D01*
G03X1518534Y907780I-1572J-1575D01*
G03X1516308I-1113J-1927D01*
G02X1514834I-737J1277D01*
G03X1512608I-1113J-1927D01*
G02X1511134I-737J1277D01*
G03X1508908I-1113J-1927D01*
G02X1507434I-737J1277D01*
G03X1505208I-1113J-1927D01*
G02X1503734I-737J1277D01*
G03X1501508I-1113J-1927D01*
G02X1500034I-737J1277D01*
G03X1497848Y907804I-1114J-1927D01*
G01X1497807Y907780D01*
G02X1496333I-737J1277D01*
G01X1496292Y907804D01*
G03X1494108Y907780I-1071J-1951D01*
G02X1492634I-737J1277D01*
G01X1492599Y907800D01*
G02X1491896Y909057I772J1257D01*
G01Y909113D01*
G03X1490783Y910985I-2225J-56D01*
G01X1490725Y911019D01*
G03X1488557Y910985I-1053J-1962D01*
G02X1487083I-737J1277D01*
G01X1487042Y911009D01*
G03X1484858Y910985I-1071J-1952D01*
G02X1483384I-737J1277D01*
G01X1483343Y911009D01*
G03X1481157Y910985I-1072J-1952D01*
G02X1479683I-737J1277D01*
G01X1479625Y911019D01*
G03X1477457Y910985I-1053J-1962D01*
G01X1477348Y910923D01*
X1475131Y909253D01*
X1474871Y909057D01*
G01X1526989Y887795D02*
X1526494Y888290D01*
X1526064D01*
X1521960Y892394D01*
X1521531Y893428D01*
X1517145Y897814D01*
G03X1516684Y898168I-1575J-1574D01*
G03X1514458I-1113J-1928D01*
G02X1512984I-737J1277D01*
G03X1510758I-1113J-1928D01*
G02X1509284I-737J1277D01*
G01X1509243Y898192D01*
G03X1507057Y898168I-1072J-1952D01*
G02X1505583I-737J1277D01*
G01X1505542Y898192D01*
G03X1503358Y898168I-1071J-1952D01*
G02X1501884I-737J1277D01*
G03X1499658I-1113J-1928D01*
G02X1498184I-737J1277D01*
G01X1498143Y898192D01*
G03X1495957Y898168I-1072J-1952D01*
G02X1494483I-737J1277D01*
G01X1494425Y898202D01*
G03X1492257Y898168I-1053J-1962D01*
G02X1490783I-737J1277D01*
G01X1490725Y898202D01*
G03X1488557Y898168I-1053J-1962D01*
G02X1487083I-737J1277D01*
G01X1487048Y898188D01*
G02X1486345Y899445I772J1257D01*
G01Y899484D01*
G03X1485233Y901372I-2225J-39D01*
G02X1484569Y902190I737J1277D01*
G01X1483685Y903151D01*
G03X1483008Y903926I-1509J-635D01*
G03X1481534I-737J-1277D01*
G02X1479366Y903892I-1114J1927D01*
G01X1479308Y903926D01*
G03X1477834I-737J-1277D01*
G01X1477721Y903860D01*
X1474871Y902649D01*
G01X1524373Y895563D02*
X1524138Y895798D01*
X1523323D01*
X1520128Y898993D01*
Y901702D01*
X1518203Y903627D01*
X1517421D01*
G02X1517228Y903635I-4J2226D01*
G02X1516308Y903926I195J2218D01*
G03X1514834I-737J-1277D01*
G02X1512608I-1113J1927D01*
G03X1511134I-737J-1277D01*
G02X1508908I-1113J1927D01*
G03X1507434I-737J-1277D01*
G02X1505208I-1113J1927D01*
G03X1503734I-737J-1277D01*
G02X1501508I-1113J1927D01*
G03X1500034I-737J-1277D01*
G02X1497866Y903892I-1114J1927D01*
G01X1497808Y903926D01*
G03X1496334I-737J-1277D01*
G02X1494108I-1113J1927D01*
G03X1492634I-737J-1277D01*
G02X1490466Y903892I-1114J1927D01*
G01X1490408Y903926D01*
X1490405Y903928D01*
X1490384Y903940D01*
G02X1489295Y905853I1136J1913D01*
G03X1488592Y907110I-1475J0D01*
G01X1488557Y907130D01*
G03X1487083I-737J-1277D01*
G01X1487025Y907096D01*
G02X1484857Y907130I-1054J1961D01*
G03X1483383I-737J-1277D01*
G01X1483325Y907096D01*
G02X1481157Y907130I-1054J1961D01*
G03X1479683I-737J-1277D01*
G01X1479625Y907096D01*
G02X1477457Y907130I-1054J1961D01*
G03X1475983I-737J-1277D01*
G01X1475977Y907127D01*
X1475948Y907110D01*
G03X1475263Y906078I773J-1256D01*
G01X1475488Y905853D01*
X1476720D01*
G01X1524373Y896783D02*
X1524137Y896547D01*
X1523634D01*
X1520877Y899304D01*
Y902013D01*
X1518514Y904376D01*
X1517421D01*
G02X1517295Y904382I7J1476D01*
G02X1516684Y904576I130J1470D01*
G03X1514458I-1113J-1927D01*
G02X1512984I-737J1277D01*
G03X1510758I-1113J-1927D01*
G02X1509284I-737J1277D01*
G03X1507058I-1113J-1927D01*
G02X1505584I-737J1277D01*
G03X1503358I-1113J-1927D01*
G02X1501884I-737J1277D01*
G01X1501843Y904600D01*
G03X1499657Y904576I-1072J-1951D01*
G02X1498183I-737J1277D01*
G01X1498142Y904600D01*
G03X1495958Y904576I-1071J-1951D01*
G02X1494484I-737J1277D01*
G01X1494443Y904600D01*
G03X1492257Y904576I-1072J-1951D01*
G02X1490783I-737J1277D01*
G01X1490777Y904579D01*
X1490748Y904596D01*
G02X1490045Y905853I772J1257D01*
G01Y905914D01*
G03X1488934Y907780I-2225J-61D01*
G03X1486766Y907814I-1114J-1927D01*
G01X1486708Y907780D01*
G02X1485234I-737J1277D01*
G03X1483066Y907814I-1114J-1927D01*
G01X1483008Y907780D01*
G02X1481534I-737J1277D01*
G03X1479366Y907814I-1114J-1927D01*
G01X1479308Y907780D01*
G02X1477834I-737J1277D01*
G03X1475666Y907814I-1114J-1927D01*
G01X1475608Y907780D01*
X1475605Y907778D01*
X1475584Y907766D01*
G03X1474510Y906111I1136J-1913D01*
G01X1474252Y905853D01*
X1473020D01*
G01X1528199Y926926D02*
X1527326D01*
X1525010Y929242D01*
X1524820D01*
X1524604Y929272D01*
G02X1523708Y929560I218J2215D01*
G02X1522595Y931432I1112J1928D01*
G01Y931488D01*
G03X1521913Y932732I-1476J0D01*
G01X1521857Y932764D01*
G03X1520383I-737J-1276D01*
G01X1520325Y932730D01*
G02X1518157Y932764I-1054J1961D01*
G03X1516683I-737J-1276D01*
G01X1516625Y932730D01*
G02X1514457Y932764I-1054J1961D01*
G03X1512983I-737J-1276D01*
G01X1512925Y932730D01*
G02X1510757Y932764I-1054J1961D01*
G03X1509283I-737J-1276D01*
G01X1509242Y932740D01*
G02X1507058Y932764I-1071J1951D01*
G03X1505584I-737J-1276D01*
G02X1503358I-1113J1927D01*
G03X1501884I-737J-1276D01*
G02X1499698Y932740I-1114J1927D01*
G01X1499657Y932764D01*
G03X1498183I-737J-1276D01*
G01X1498125Y932730D01*
G02X1495957Y932764I-1054J1961D01*
G03X1494483I-737J-1276D01*
G01X1494425Y932730D01*
G02X1492257Y932764I-1054J1961D01*
G03X1490783I-737J-1276D01*
G01X1490725Y932730D01*
G02X1488557Y932764I-1054J1961D01*
G03X1487083I-737J-1276D01*
G01X1487042Y932740D01*
G02X1484858Y932764I-1071J1951D01*
G03X1483384I-737J-1276D01*
G01X1483328Y932732D01*
G03X1482646Y931488I794J-1244D01*
G01Y931230D01*
X1481853Y930437D01*
G02X1478036Y930376I-1940J1939D01*
G01X1476720Y931488D01*
G01X1528009Y912518D02*
X1527484D01*
X1527049Y912953D01*
Y913366D01*
X1524821Y915594D01*
X1523980Y916499D01*
G03X1522913Y916940I-1013J-941D01*
G03X1522234Y916743I59J-1473D01*
G02X1520008I-1113J1927D01*
G03X1518534I-737J-1277D01*
G02X1516308I-1113J1927D01*
G02X1515196Y918631I1113J1927D01*
G01Y918670D01*
G03X1514493Y919927I-1475J0D01*
G01X1514458Y919947D01*
G03X1512984I-737J-1277D01*
G02X1510758I-1113J1928D01*
G03X1509284I-737J-1277D01*
G02X1507058I-1113J1928D01*
G03X1505584I-737J-1277D01*
G02X1503358I-1113J1928D01*
G03X1501884I-737J-1277D01*
G02X1499658I-1113J1928D01*
G03X1498184I-737J-1277D01*
G01X1498143Y919923D01*
G02X1495957Y919947I-1072J1952D01*
G03X1494483I-737J-1277D01*
G01X1494425Y919913D01*
G02X1492257Y919947I-1053J1962D01*
G03X1490783I-737J-1277D01*
G01X1490725Y919913D01*
G02X1488557Y919947I-1053J1962D01*
G03X1487083I-737J-1277D01*
G02X1484857I-1113J1928D01*
G03X1483383I-737J-1277D01*
G01X1483325Y919913D01*
G02X1481157Y919947I-1053J1962D01*
G03X1479683I-737J-1277D01*
G01X1479625Y919913D01*
G02X1477457Y919947I-1053J1962D01*
G01X1477348Y920009D01*
X1474871Y921875D01*
G01X1527565Y908461D02*
X1526080D01*
X1523312Y911229D01*
G02X1523188Y911557I298J300D01*
G02X1523249Y911991I2956J-194D01*
G03X1522431Y913307I-1087J237D01*
G02X1521858Y913539I541J2159D01*
G03X1520384I-737J-1277D01*
G02X1518158I-1113J1927D01*
G03X1516684I-737J-1277D01*
G02X1514458I-1113J1927D01*
G02X1513346Y915427I1113J1927D01*
G01Y915466D01*
G03X1512643Y916723I-1475J0D01*
G01X1512608Y916743D01*
G03X1511134I-737J-1277D01*
G02X1508908I-1113J1927D01*
G03X1507434I-737J-1277D01*
G02X1505208I-1113J1927D01*
G03X1503734I-737J-1277D01*
G01X1503693Y916719D01*
G02X1501507Y916743I-1072J1951D01*
G03X1500033I-737J-1277D01*
G01X1499992Y916719D01*
G02X1497808Y916743I-1071J1951D01*
G03X1496334I-737J-1277D01*
G02X1494166Y916709I-1114J1927D01*
G01X1494108Y916743D01*
G03X1492634I-737J-1277D01*
G02X1490466Y916709I-1114J1927D01*
G01X1490408Y916743D01*
G03X1488934I-737J-1277D01*
G02X1486766Y916709I-1114J1927D01*
G01X1486708Y916743D01*
G03X1485234I-737J-1277D01*
G02X1483066Y916709I-1114J1927D01*
G01X1483008Y916743D01*
G03X1481534I-737J-1277D01*
G02X1479366Y916709I-1114J1927D01*
G01X1479308Y916743D01*
X1479284Y916757D01*
G02X1478210Y918411I1136J1913D01*
G01X1477951Y918670D01*
X1476720D01*
G01X1527566Y922991D02*
X1526776D01*
X1526296Y923471D01*
Y925792D01*
X1525533Y926555D01*
X1524820D01*
G03X1524083Y926356I3J-1475D01*
G01X1524025Y926322D01*
G02X1521857Y926356I-1054J1961D01*
G02X1520746Y928222I1114J1927D01*
G01Y928283D01*
G03X1518534Y929560I-1475J0D01*
G02X1516366Y929526I-1115J1928D01*
G01X1516308Y929560D01*
G03X1514834I-737J-1277D01*
G02X1512666Y929526I-1115J1928D01*
G01X1512608Y929560D01*
G03X1511134I-737J-1277D01*
G02X1508966Y929526I-1115J1928D01*
G01X1508908Y929560D01*
G03X1507434I-737J-1277D01*
G02X1505208I-1113J1928D01*
G03X1503734I-737J-1277D01*
G02X1501508I-1113J1928D01*
G03X1500034I-737J-1277D01*
G02X1497848Y929536I-1114J1928D01*
G01X1497807Y929560D01*
G03X1496333I-737J-1277D01*
G02X1494149Y929536I-1113J1928D01*
G01X1494108Y929560D01*
G03X1492634I-737J-1277D01*
G02X1490466Y929526I-1115J1928D01*
G01X1490408Y929560D01*
G03X1488934I-737J-1277D01*
G02X1486766Y929526I-1115J1928D01*
G01X1486708Y929560D01*
G03X1485234I-737J-1277D01*
G01X1485251Y929571D01*
G03X1484451Y928966I1782J-3188D01*
G01X1484266Y928781D01*
G03X1483983Y928098I683J-683D01*
G02X1483757Y927557I-763J1D01*
G01X1483473Y927276D01*
X1483008Y927006D01*
G02X1482281Y926809I-736J1277D01*
G01X1480704Y926798D01*
X1478457D01*
G02X1474871Y928283I0J5072D01*
G01X1527473Y916619D02*
X1527238Y916854D01*
X1526503D01*
X1525328Y918029D01*
G02X1524870Y918641I1907J1905D01*
G03X1523159Y919653I-1707J-933D01*
G02X1521794Y919983I-4J2973D01*
G03X1520384Y919947I-672J-1313D01*
G02X1518158I-1113J1928D01*
G02X1517046Y921802I1113J1928D01*
G01Y921875D01*
G03X1516343Y923132I-1475J0D01*
G01X1516314Y923149D01*
X1516308Y923152D01*
G03X1514834I-737J-1277D01*
G02X1512666Y923118I-1114J1927D01*
G01X1512608Y923152D01*
G03X1511134I-737J-1277D01*
G02X1508908I-1113J1927D01*
G03X1507434I-737J-1277D01*
G02X1505208I-1113J1927D01*
G03X1503734I-737J-1277D01*
G02X1501508I-1113J1927D01*
G03X1500034I-737J-1277D01*
G02X1497866Y923118I-1114J1927D01*
G01X1497808Y923152D01*
G03X1496334I-737J-1277D01*
G02X1494108I-1113J1927D01*
G03X1492634I-737J-1277D01*
G02X1490466Y923118I-1114J1927D01*
G01X1490408Y923152D01*
G03X1488934I-737J-1277D01*
G02X1486748Y923128I-1114J1927D01*
G01X1486707Y923152D01*
G03X1485233I-737J-1277D01*
G02X1483049Y923128I-1113J1927D01*
G01X1483008Y923152D01*
G03X1481534I-737J-1277D01*
G02X1479366Y923118I-1114J1927D01*
G01X1479308Y923152D01*
G03X1477834I-737J-1277D01*
G02X1475666Y923118I-1114J1927D01*
G01X1475608Y923152D01*
X1475605Y923154D01*
X1475584Y923166D01*
G02X1474510Y924821I1136J1913D01*
G01X1474252Y925079D01*
X1473020D01*
G01X1527473Y917839D02*
X1527237Y917603D01*
X1526814D01*
X1525858Y918559D01*
G02X1525527Y919001I1376J1376D01*
G03X1523158Y920402I-2364J-1293D01*
G02X1522137Y920649I-2J2224D01*
G03X1520008Y920598I-1018J-1978D01*
G02X1518534I-737J1277D01*
G01X1518499Y920618D01*
G02X1517796Y921875I772J1257D01*
G03X1516707Y923788I-2225J0D01*
G01X1516686Y923800D01*
X1516683Y923802D01*
X1516625Y923836D01*
G03X1514457Y923802I-1054J-1961D01*
G02X1512983I-737J1277D01*
G01X1512942Y923826D01*
G03X1510758Y923802I-1071J-1951D01*
G02X1509284I-737J1277D01*
G03X1507058I-1113J-1927D01*
G02X1505584I-737J1277D01*
G03X1503358I-1113J-1927D01*
G02X1501884I-737J1277D01*
G01X1501843Y923826D01*
G03X1499657Y923802I-1072J-1951D01*
G02X1498183I-737J1277D01*
G01X1498142Y923826D01*
G03X1495958Y923802I-1071J-1951D01*
G02X1494484I-737J1277D01*
G01X1494443Y923826D01*
G03X1492257Y923802I-1072J-1951D01*
G02X1490783I-737J1277D01*
G01X1490725Y923836D01*
G03X1488557Y923802I-1054J-1961D01*
G02X1487083I-737J1277D01*
G03X1484857I-1113J-1927D01*
G02X1483383I-737J1277D01*
G01X1483325Y923836D01*
G03X1481157Y923802I-1054J-1961D01*
G02X1479683I-737J1277D01*
G01X1479625Y923836D01*
G03X1477457Y923802I-1054J-1961D01*
G02X1475983I-737J1277D01*
G01X1475977Y923805D01*
X1475948Y923822D01*
G02X1475263Y924854I773J1256D01*
G01X1475488Y925079D01*
X1476720D01*
G01X1529066Y949055D02*
X1528161D01*
X1525996Y951220D01*
X1524612D01*
X1523312Y949920D01*
X1522342D01*
X1521858Y949436D01*
G02X1520384I-737J1277D01*
G03X1518158I-1113J-1927D01*
G02X1516684I-737J1277D01*
G03X1514458I-1113J-1927D01*
G02X1512984I-737J1277D01*
G03X1510758I-1113J-1927D01*
G02X1509284I-737J1277D01*
G01X1509243Y949460D01*
G03X1507057Y949436I-1072J-1951D01*
G02X1505583I-737J1277D01*
G01X1505542Y949460D01*
G03X1503358Y949436I-1071J-1951D01*
G02X1501884I-737J1277D01*
G01X1501843Y949460D01*
G03X1499657Y949436I-1072J-1951D01*
G02X1498183I-737J1277D01*
G03X1495957I-1113J-1927D01*
G02X1494483I-737J1277D01*
G01X1494425Y949470D01*
G03X1492257Y949436I-1054J-1961D01*
G02X1490783I-737J1277D01*
G01X1490725Y949470D01*
G03X1488557Y949436I-1054J-1961D01*
G02X1487083I-737J1277D01*
G01X1487042Y949460D01*
G03X1484858Y949436I-1071J-1951D01*
G02X1483384I-737J1277D01*
G01X1483343Y949460D01*
G03X1481157Y949436I-1072J-1951D01*
G03X1480725Y949110I1115J-1926D01*
G01X1480226Y948975D01*
X1479878Y948998D01*
X1478466D01*
G03X1474871Y947509I0J-5084D01*
G01X1529066Y938571D02*
X1527376D01*
X1525961Y939986D01*
X1524166D01*
G03X1524072Y939974I0J-370D01*
G03X1523708Y939823I380J-1430D01*
G02X1522234I-737J1277D01*
G03X1520008I-1113J-1927D01*
G02X1518534I-737J1277D01*
G03X1516308I-1113J-1927D01*
G02X1514834I-737J1277D01*
G03X1512608I-1113J-1927D01*
G02X1511134I-737J1277D01*
G03X1508908I-1113J-1927D01*
G02X1507434I-737J1277D01*
G03X1505208I-1113J-1927D01*
G02X1503733I-737J1277D01*
G01X1503711Y939836D01*
G03X1501508Y939823I-1090J-1940D01*
G02X1500051Y939812I-738J1277D01*
G01X1500033Y939823D01*
X1500004Y939840D01*
G03X1497808Y939823I-1083J-1944D01*
G02X1496351Y939812I-738J1277D01*
G01X1496333Y939823D01*
X1496304Y939840D01*
G03X1494108Y939823I-1083J-1944D01*
G02X1492651Y939812I-738J1277D01*
G01X1492633Y939823D01*
X1492604Y939840D01*
G03X1490408Y939823I-1083J-1944D01*
G02X1488951Y939812I-738J1277D01*
G01X1488933Y939823D01*
X1488904Y939840D01*
G03X1486708Y939823I-1083J-1944D01*
G02X1485251Y939812I-738J1277D01*
G01X1485233Y939823D01*
X1485219Y939831D01*
G02X1484927Y940054I687J1202D01*
G01X1484666Y940315D01*
X1483685Y941602D01*
G03X1483008Y942377I-1472J-603D01*
G03X1481534I-737J-1277D01*
G01X1481421Y942311D01*
X1480468Y942176D01*
X1480045Y941753D01*
Y941100D01*
G02X1477825Y939828I-1474J0D01*
G01X1477822Y939830D01*
G03X1475869Y939953I-1097J-1854D01*
G01X1475486Y940033D01*
X1474871Y941099D01*
Y941100D01*
G01X1529066Y934546D02*
X1527335D01*
X1525616Y936265D01*
X1524545D01*
G03X1521858Y936619I-1574J-1574D01*
G02X1520384I-737J1277D01*
G03X1518158I-1113J-1928D01*
G02X1516684I-737J1277D01*
G03X1514458I-1113J-1928D01*
G02X1512984I-737J1277D01*
G03X1510758I-1113J-1928D01*
G02X1509284I-737J1277D01*
G03X1507058I-1113J-1928D01*
G02X1505584I-737J1277D01*
G01X1505583Y936618D01*
G03X1503358I-1112J-1927D01*
G01X1503341Y936608D01*
G02X1501883Y936618I-720J1288D01*
G03X1499681Y936632I-1113J-1927D01*
G01X1499658Y936618D01*
X1499635Y936605D01*
G02X1498183Y936618I-715J1291D01*
G03X1495981Y936632I-1113J-1927D01*
G01X1495958Y936618D01*
X1495935Y936605D01*
G02X1494483Y936618I-715J1291D01*
G03X1492281Y936632I-1113J-1927D01*
G01X1492258Y936618D01*
X1492235Y936605D01*
G02X1490783Y936618I-715J1291D01*
G03X1488581Y936632I-1113J-1927D01*
G01X1488558Y936618D01*
X1488535Y936605D01*
G02X1487083Y936618I-715J1291D01*
G03X1484881Y936632I-1113J-1927D01*
G01X1484858Y936618D01*
X1484835Y936605D01*
G02X1483383Y936618I-715J1291D01*
G02X1482646Y937882I738J1277D01*
G01Y937896D01*
G03X1482524Y938623I-2225J0D01*
G01X1481489Y939658D01*
X1480265D01*
G02X1477517Y939139I-1695J1441D01*
G01X1477440Y939184D01*
G03X1476221Y939283I-712J-1208D01*
G01X1476105Y938963D01*
X1476720Y937897D01*
Y937896D01*
G01X1528974Y943885D02*
X1528739Y944120D01*
X1527357D01*
X1525696Y945781D01*
X1524820D01*
G03X1524083Y945581I5J-1476D01*
G01X1524025Y945547D01*
G02X1521857Y945581I-1053J1962D01*
G03X1520383I-737J-1277D01*
G01X1520325Y945547D01*
G02X1518157Y945581I-1053J1962D01*
G03X1516683I-737J-1277D01*
G01X1516625Y945547D01*
G02X1514457Y945581I-1053J1962D01*
G03X1512983I-737J-1277D01*
G01X1512982D01*
G02X1510737Y945594I-1111J1925D01*
G03X1509283Y945582I-716J-1290D01*
G02X1507059I-1112J1927D01*
G01X1507057Y945581D01*
G03X1505583I-737J-1277D01*
G01X1505542Y945557D01*
G02X1503358Y945581I-1071J1952D01*
G03X1501884I-737J-1277D01*
G01X1501843Y945557D01*
G02X1499657Y945581I-1072J1952D01*
G03X1498183I-737J-1277D01*
G02X1495999Y945557I-1113J1928D01*
G01X1495958Y945581D01*
G03X1494484I-737J-1277D01*
G01X1494443Y945557D01*
G02X1492257Y945581I-1072J1952D01*
G03X1490783I-737J-1277D01*
G01X1490725Y945547D01*
G02X1488557Y945581I-1053J1962D01*
G03X1487083I-737J-1277D01*
G01X1487025Y945547D01*
G02X1484857Y945581I-1053J1962D01*
G03X1483383I-737J-1277D01*
G01X1483325Y945547D01*
G02X1481157Y945581I-1053J1962D01*
G03X1478964Y944541I-737J-1277D01*
G02X1478735Y944094I-807J131D01*
G01X1478322Y943681D01*
G02X1477492Y943047I-2781J2781D01*
G01X1477457Y943027D01*
G02X1475983I-737J1277D01*
G01X1475977Y943030D01*
X1475885Y943086D01*
G02X1475274Y944006I689J1120D01*
G01X1475263Y944079D01*
X1475038Y944304D01*
X1473020D01*
G01X1528974Y945105D02*
X1528738Y944869D01*
X1527668D01*
X1526007Y946530D01*
X1524820D01*
G03X1523708Y946232I1J-2226D01*
G02X1522234I-737J1277D01*
G03X1520066Y946266I-1115J-1928D01*
G01X1520008Y946232D01*
G02X1518534I-737J1277D01*
G03X1516366Y946266I-1115J-1928D01*
G01X1516308Y946232D01*
G02X1514834I-737J1277D01*
G03X1512666Y946266I-1115J-1928D01*
G01X1512608Y946232D01*
X1512607Y946231D01*
G02X1511135I-736J1275D01*
G01X1511134Y946232D01*
G03X1508908I-1113J-1928D01*
G02X1507434I-737J1277D01*
G03X1505266Y946266I-1115J-1928D01*
G01X1505208Y946232D01*
G02X1503734I-737J1277D01*
G03X1501508I-1113J-1928D01*
G02X1500034I-737J1277D01*
G03X1497848Y946256I-1114J-1928D01*
G01X1497807Y946232D01*
G02X1496333I-737J1277D01*
G01X1496292Y946256D01*
G03X1494108Y946232I-1071J-1952D01*
G02X1492634I-737J1277D01*
G03X1490466Y946266I-1115J-1928D01*
G01X1490408Y946232D01*
G02X1488934I-737J1277D01*
G03X1486766Y946266I-1115J-1928D01*
G01X1486708Y946232D01*
G02X1485234I-737J1277D01*
G03X1483066Y946266I-1115J-1928D01*
G01X1483008Y946232D01*
G02X1481534I-737J1277D01*
G03X1479366Y946266I-1115J-1928D01*
G01X1479308Y946232D01*
G03X1476720Y944304I7429J-12673D01*
G01X1529060Y952977D02*
X1528474D01*
X1527732Y953719D01*
X1524787D01*
X1523708Y952640D01*
G02X1522234I-737J1277D01*
G03X1520008I-1113J-1927D01*
G02X1518534I-737J1277D01*
G03X1516308I-1113J-1927D01*
G02X1514834I-737J1277D01*
G03X1512608I-1113J-1927D01*
G02X1511134I-737J1277D01*
G03X1508908I-1113J-1927D01*
G02X1507434I-737J1277D01*
G03X1505266Y952674I-1114J-1927D01*
G01X1505208Y952640D01*
G02X1503734I-737J1277D01*
G03X1501508I-1113J-1927D01*
G02X1500034I-737J1277D01*
G03X1497866Y952674I-1114J-1927D01*
G01X1497808Y952640D01*
G02X1496334I-737J1277D01*
G03X1494166Y952674I-1114J-1927D01*
G01X1494108Y952640D01*
G02X1492634I-737J1277D01*
G03X1490466Y952674I-1114J-1927D01*
G01X1490408Y952640D01*
G02X1488934I-737J1277D01*
G03X1486766Y952674I-1114J-1927D01*
G01X1486708Y952640D01*
G02X1485234I-737J1277D01*
G03X1483008I-1113J-1927D01*
G02X1481534I-737J1277D01*
G03X1479366Y952674I-1114J-1927D01*
G01X1479308Y952640D01*
X1479284Y952626D01*
G03X1478210Y950972I1136J-1913D01*
G01X1477951Y950713D01*
X1476720D01*
G01X1518713Y960104D02*
X1517363D01*
X1516308Y959049D01*
G02X1514834I-737J1277D01*
G03X1512608I-1113J-1927D01*
G02X1511134I-737J1277D01*
G03X1508908I-1113J-1927D01*
G02X1507434I-737J1277D01*
G03X1505266Y959083I-1114J-1927D01*
G01X1505208Y959049D01*
G02X1503734I-737J1277D01*
G03X1501508I-1113J-1927D01*
G02X1500034I-737J1277D01*
G03X1497808I-1113J-1927D01*
G02X1496334I-737J1277D01*
G03X1494166Y959083I-1114J-1927D01*
G01X1494108Y959049D01*
G02X1492634I-737J1277D01*
G03X1490466Y959083I-1114J-1927D01*
G01X1490408Y959049D01*
G02X1488934I-737J1277D01*
G03X1486748Y959073I-1114J-1927D01*
G01X1486707Y959049D01*
G02X1485233I-737J1277D01*
G03X1483049Y959073I-1113J-1927D01*
G01X1483008Y959049D01*
G02X1481534I-737J1277D01*
G03X1479366Y959083I-1114J-1927D01*
G01X1479308Y959049D01*
X1479284Y959035D01*
G03X1478210Y957380I1136J-1913D01*
G01X1477952Y957122D01*
X1476720D01*
G01X1516187Y965427D02*
X1515581D01*
X1515196Y965042D01*
Y963530D01*
G02X1514459Y962254I-1473J0D01*
G01X1514458Y962253D01*
G02X1512984I-737J1277D01*
G01X1512950Y962272D01*
X1512942Y962277D01*
G03X1510758Y962253I-1071J-1951D01*
G02X1509284I-737J1277D01*
G01X1509243Y962277D01*
G03X1507057Y962253I-1072J-1951D01*
G02X1505583I-737J1277D01*
G01X1505542Y962277D01*
G03X1503358Y962253I-1071J-1951D01*
G02X1501884I-737J1277D01*
G01X1501843Y962277D01*
G03X1499657Y962253I-1072J-1951D01*
G02X1498183I-737J1277D01*
G01X1498142Y962277D01*
G03X1495958Y962253I-1071J-1951D01*
G02X1494484I-737J1277D01*
G01X1494443Y962277D01*
G03X1492257Y962253I-1072J-1951D01*
G02X1490783I-737J1277D01*
G01X1490725Y962287D01*
G03X1488557Y962253I-1054J-1961D01*
G02X1487083I-737J1277D01*
G03X1484857I-1113J-1927D01*
G02X1483383I-737J1277D01*
G01X1483325Y962287D01*
G03X1481157Y962253I-1054J-1961D01*
G02X1479683I-737J1277D01*
G01X1479642Y962277D01*
G03X1477458Y962253I-1071J-1951D01*
G01X1477150Y962075D01*
G03X1474871Y960326I5508J-9537D01*
G01X1518178Y979665D02*
X1517570D01*
X1516197Y981038D01*
X1513303D01*
X1511466Y982875D01*
X1508528D01*
X1507365Y981712D01*
G02X1507058Y981479I-1038J1049D01*
G02X1505584I-737J1277D01*
G03X1503358I-1113J-1927D01*
G02X1501884I-737J1277D01*
G03X1499658I-1113J-1927D01*
G02X1498184I-737J1277D01*
G03X1495958I-1113J-1927D01*
G02X1494484I-737J1277D01*
G01X1494443Y981503D01*
G03X1492257Y981479I-1072J-1951D01*
G02X1490783I-737J1277D01*
G01X1490725Y981513D01*
G03X1488557Y981479I-1054J-1961D01*
G02X1487083I-737J1277D01*
G03X1484857I-1113J-1927D01*
G02X1483383I-737J1277D01*
G01X1483325Y981513D01*
G03X1481157Y981479I-1054J-1961D01*
G02X1479683I-737J1277D01*
G01X1479625Y981513D01*
G03X1477457Y981479I-1054J-1961D01*
G02X1475983I-737J1277D01*
G01X1475925Y981513D01*
G03X1473757Y981479I-1054J-1961D01*
G02X1472283I-737J1277D01*
G01X1472242Y981503D01*
G03X1470058Y981479I-1071J-1951D01*
G02X1468584I-737J1277D01*
G01X1468543Y981503D01*
G03X1466357Y981479I-1072J-1951D01*
G01X1466245Y981415D01*
X1463771Y979552D01*
G01X1513663Y975373D02*
X1512944D01*
X1512246Y976071D01*
Y976420D01*
G03X1508908Y978275I-2225J-73D01*
G02X1507434I-737J1277D01*
G03X1505208I-1113J-1928D01*
G02X1503734I-737J1277D01*
G03X1501508I-1113J-1928D01*
G02X1500034I-737J1277D01*
G03X1497808I-1113J-1928D01*
G02X1496334I-737J1277D01*
G03X1494166Y978309I-1115J-1928D01*
G01X1494108Y978275D01*
G02X1492634I-737J1277D01*
G03X1490408I-1113J-1928D01*
G02X1488934I-737J1277D01*
G03X1486748Y978299I-1114J-1928D01*
G01X1486707Y978275D01*
G02X1485233I-737J1277D01*
G03X1483049Y978299I-1113J-1928D01*
G01X1483008Y978275D01*
G02X1481534I-737J1277D01*
G03X1479366Y978309I-1115J-1928D01*
G01X1479308Y978275D01*
G02X1477834I-737J1277D01*
G03X1475666Y978309I-1115J-1928D01*
G01X1475608Y978275D01*
G02X1474134I-737J1277D01*
G03X1471908I-1113J-1928D01*
G02X1470434I-737J1277D01*
G03X1468266Y978309I-1115J-1928D01*
G01X1468208Y978275D01*
G02X1466734I-737J1277D01*
G03X1464566Y978309I-1115J-1928D01*
G01X1464508Y978275D01*
X1464394Y978210D01*
X1461920Y976347D01*
G01X1518235Y977366D02*
X1514773D01*
X1512364Y979775D01*
Y980917D01*
X1511176Y982105D01*
X1508818D01*
X1507895Y981182D01*
G02X1507434Y980829I-1572J1575D01*
G02X1505208I-1113J1927D01*
G03X1503734I-737J-1277D01*
G02X1501508I-1113J1927D01*
G03X1500034I-737J-1277D01*
G02X1497808I-1113J1927D01*
G03X1496334I-737J-1277D01*
G02X1494108I-1113J1927D01*
G03X1492634I-737J-1277D01*
G02X1490466Y980795I-1114J1927D01*
G01X1490408Y980829D01*
G03X1488934I-737J-1277D01*
G02X1486748Y980805I-1114J1927D01*
G01X1486707Y980829D01*
G03X1485233I-737J-1277D01*
G02X1483049Y980805I-1113J1927D01*
G01X1483008Y980829D01*
G03X1481534I-737J-1277D01*
G02X1479366Y980795I-1114J1927D01*
G01X1479308Y980829D01*
G03X1477834I-737J-1277D01*
G02X1475666Y980795I-1114J1927D01*
G01X1475608Y980829D01*
G03X1474134I-737J-1277D01*
G02X1471966Y980795I-1114J1927D01*
G01X1471908Y980829D01*
G03X1470434I-737J-1277D01*
G01X1470320Y980762D01*
X1467471Y979552D01*
G01X1514742Y971408D02*
X1513936D01*
X1513329Y972015D01*
Y973815D01*
X1511496Y975648D01*
Y976347D01*
G03X1510793Y977604I-1475J0D01*
G01X1510758Y977624D01*
G03X1509284I-737J-1277D01*
G02X1507058I-1113J1928D01*
G03X1505584I-737J-1277D01*
G02X1503358I-1113J1928D01*
G03X1501884I-737J-1277D01*
G02X1499658I-1113J1928D01*
G03X1498184I-737J-1277D01*
G01X1498143Y977600D01*
G02X1495957Y977624I-1072J1952D01*
G03X1494483I-737J-1277D01*
G01X1494442Y977600D01*
G02X1492258Y977624I-1071J1952D01*
G03X1490784I-737J-1277D01*
G01X1490743Y977600D01*
G02X1488557Y977624I-1072J1952D01*
G03X1487083I-737J-1277D01*
G02X1484857I-1113J1928D01*
G03X1483383I-737J-1277D01*
G01X1483325Y977590D01*
G02X1481157Y977624I-1053J1962D01*
G03X1479683I-737J-1277D01*
G01X1479625Y977590D01*
G02X1477457Y977624I-1053J1962D01*
G03X1475983I-737J-1277D01*
G01X1475942Y977600D01*
G02X1473758Y977624I-1071J1952D01*
G03X1472284I-737J-1277D01*
G01X1472172Y977558D01*
X1469320Y976347D01*
G01X1522039Y986314D02*
X1520729D01*
X1520538Y986505D01*
X1482349D01*
X1475304Y993550D01*
Y999684D01*
G01X1529668Y1038079D02*
X1528471D01*
X1526686Y1039864D01*
X1525253D01*
G02X1524516Y1040063I3J1475D01*
G01X1524458Y1040097D01*
G03X1522290Y1040063I-1054J-1961D01*
G02X1520816I-737J1277D01*
G01X1520758Y1040097D01*
G03X1518590Y1040063I-1054J-1961D01*
G02X1517116I-737J1277D01*
G03X1514890I-1113J-1927D01*
G02X1513416I-737J1277D01*
G03X1511190I-1113J-1927D01*
G02X1509716I-737J1277D01*
G03X1507490I-1113J-1927D01*
G02X1506016I-737J1277D01*
G01X1505958Y1040097D01*
G03X1503790Y1040063I-1054J-1961D01*
G02X1502316I-737J1277D01*
G01Y1040062D01*
G03X1500114Y1040076I-1113J-1927D01*
G01X1500091Y1040062D01*
X1500068Y1040049D01*
G02X1498616Y1040062I-715J1291D01*
G03X1496414Y1040076I-1113J-1927D01*
G01X1496391Y1040062D01*
X1496368Y1040049D01*
G02X1494916Y1040062I-715J1291D01*
G03X1492714Y1040076I-1113J-1927D01*
G01X1492691Y1040062D01*
X1492668Y1040049D01*
G02X1491216Y1040062I-715J1291D01*
G03X1489014Y1040076I-1113J-1927D01*
G01X1488991Y1040062D01*
X1488968Y1040049D01*
G02X1487516Y1040062I-715J1291D01*
G03X1485314Y1040076I-1113J-1927D01*
G01X1485291Y1040062D01*
X1485268Y1040049D01*
G02X1483816Y1040062I-715J1291D01*
G03X1481614Y1040076I-1113J-1927D01*
G02X1480168Y1039698I-1446J2578D01*
G01X1478283D01*
G03X1475304Y1038136I0J-3622D01*
G01X1529168Y1027656D02*
X1527215D01*
X1526603Y1027044D01*
X1525256D01*
G02X1524516Y1027246I5J1476D01*
G01X1524481Y1027266D01*
G02X1523778Y1028523I772J1257D01*
G01Y1028562D01*
G03X1522666Y1030450I-2225J-39D01*
G03X1520440I-1113J-1927D01*
G02X1518966I-737J1277D01*
G03X1516740I-1113J-1927D01*
G02X1515266I-737J1277D01*
G03X1513040I-1113J-1927D01*
G02X1511566I-737J1277D01*
G03X1509340I-1113J-1927D01*
G02X1507866I-737J1277D01*
G03X1505682Y1030474I-1113J-1927D01*
G01X1505641Y1030450D01*
G02X1504167I-737J1277D01*
G03X1501999Y1030484I-1114J-1927D01*
G01X1501941Y1030450D01*
G02X1500467I-737J1277D01*
G03X1498281Y1030474I-1114J-1927D01*
G01X1498240Y1030450D01*
G02X1496766I-737J1277D01*
G03X1494582Y1030474I-1113J-1927D01*
G01X1494541Y1030450D01*
G02X1493067I-737J1277D01*
G03X1490899Y1030484I-1114J-1927D01*
G01X1490841Y1030450D01*
G02X1489367I-737J1277D01*
G03X1487199Y1030484I-1114J-1927D01*
G01X1487141Y1030450D01*
G02X1485667I-737J1277D01*
G02X1485112Y1031014I741J1285D01*
G01X1484742Y1031683D01*
X1484030Y1032650D01*
X1483441Y1033004D01*
G03X1481967I-737J-1277D01*
G02X1479799Y1032970I-1114J1927D01*
G01X1479741Y1033004D01*
G03X1478267I-737J-1277D01*
G01X1478154Y1032938D01*
X1475304Y1031727D01*
G01X1529668Y1032844D02*
X1529576D01*
X1529341Y1033079D01*
X1528495D01*
X1527688Y1033885D01*
X1527183Y1035103D01*
X1526384Y1035903D01*
X1526383D01*
G03X1526060Y1036166I-1409J-1401D01*
G01X1526059D01*
G03X1525991Y1036208I-809J-1233D01*
G03X1524517I-737J-1277D01*
G02X1522349Y1036174I-1115J1928D01*
G01X1522291Y1036208D01*
G03X1520817I-737J-1277D01*
G02X1518631Y1036184I-1114J1928D01*
G01X1518590Y1036208D01*
G03X1517116I-737J-1277D01*
G02X1514890I-1113J1928D01*
G03X1513416I-737J-1277D01*
G02X1511190I-1113J1928D01*
G03X1509716I-737J-1277D01*
G02X1507490I-1113J1928D01*
G03X1506016I-737J-1277D01*
G01X1505958Y1036174D01*
G02X1503790Y1036208I-1053J1962D01*
G03X1502316I-737J-1277D01*
G01X1502258Y1036174D01*
G02X1500090Y1036208I-1053J1962D01*
G03X1498616I-737J-1277D01*
G01X1498575Y1036184D01*
G02X1496391Y1036208I-1071J1952D01*
G03X1494917I-737J-1277D01*
G01X1494876Y1036184D01*
G02X1492690Y1036208I-1072J1952D01*
G03X1491216I-737J-1277D01*
G01X1491158Y1036174D01*
G02X1488990Y1036208I-1053J1962D01*
G03X1487516I-737J-1277D01*
G02X1485290I-1113J1928D01*
G03X1483816I-737J-1277D01*
G01X1483758Y1036174D01*
G02X1481590Y1036208I-1053J1962D01*
G03X1480116I-737J-1277D01*
G01X1480058Y1036174D01*
G02X1477890Y1036208I-1053J1962D01*
G03X1475696Y1035157I-737J-1277D01*
G01X1475922Y1034931D01*
X1477153D01*
G01X1529668Y1034064D02*
X1529576D01*
X1529340Y1033828D01*
X1528806D01*
X1528324Y1034310D01*
X1527819Y1035528D01*
X1526914Y1036433D01*
G03X1526469Y1036794I-1937J-1933D01*
G03X1526367Y1036857I-1219J-1860D01*
G03X1524143I-1112J-1926D01*
G01X1524142D01*
X1524140Y1036859D01*
G02X1522666I-737J1277D01*
G01X1522608Y1036893D01*
G03X1520440Y1036859I-1053J-1962D01*
G02X1518966I-737J1277D01*
G03X1516740I-1113J-1928D01*
G02X1515266I-737J1277D01*
G03X1513040I-1113J-1928D01*
G02X1511566I-737J1277D01*
G01X1511564Y1036857D01*
G03X1509342I-1111J-1926D01*
G01X1509340Y1036859D01*
G02X1507866I-737J1277D01*
G03X1505682Y1036883I-1113J-1928D01*
G01X1505641Y1036859D01*
G02X1504167I-737J1277D01*
G03X1501999Y1036893I-1115J-1928D01*
G01X1501941Y1036859D01*
G02X1500467I-737J1277D01*
G03X1498299Y1036893I-1115J-1928D01*
G01X1498241Y1036859D01*
G02X1496767I-737J1277D01*
G03X1494541I-1113J-1928D01*
G02X1493067I-737J1277D01*
G03X1490899Y1036893I-1115J-1928D01*
G01X1490841Y1036859D01*
G02X1489367I-737J1277D01*
G03X1487181Y1036883I-1114J-1928D01*
G01X1487140Y1036859D01*
G02X1485666I-737J1277D01*
G03X1483482Y1036883I-1113J-1928D01*
G01X1483441Y1036859D01*
G02X1481967I-737J1277D01*
G03X1479799Y1036893I-1115J-1928D01*
G01X1479741Y1036859D01*
G02X1478267I-737J1277D01*
G03X1474953Y1035272I-1114J-1928D01*
G03X1474942Y1035189I2201J-334D01*
G01X1474684Y1034931D01*
X1473453D01*
G01X1529668Y1061485D02*
X1528750D01*
X1528242Y1060977D01*
X1527274Y1060576D01*
X1525986Y1059288D01*
G02X1524512I-737J1277D01*
G01X1524471Y1059312D01*
G03X1522287Y1059288I-1071J-1951D01*
G02X1520813I-737J1277D01*
G01X1520772Y1059312D01*
G03X1518588Y1059288I-1071J-1951D01*
G02X1517114I-737J1277D01*
G03X1514890I-1112J-1927D01*
G02X1513416I-737J1277D01*
G03X1511190I-1113J-1927D01*
G02X1509716I-737J1277D01*
G01X1509658Y1059322D01*
G03X1507490Y1059288I-1054J-1961D01*
G02X1506016I-737J1277D01*
G01X1505958Y1059322D01*
G03X1503790Y1059288I-1054J-1961D01*
G02X1502316I-737J1277D01*
G01X1502275Y1059312D01*
G03X1500091Y1059288I-1071J-1951D01*
G01X1500068Y1059275D01*
G02X1498616Y1059288I-715J1290D01*
G03X1496414Y1059302I-1113J-1927D01*
G01X1496391Y1059288D01*
X1496368Y1059275D01*
G02X1494916Y1059288I-715J1290D01*
G03X1492714Y1059302I-1113J-1927D01*
G01X1492691Y1059288D01*
X1492668Y1059275D01*
G02X1491216Y1059288I-715J1290D01*
G03X1489014Y1059302I-1113J-1927D01*
G01X1488991Y1059288D01*
X1488968Y1059275D01*
G02X1487516Y1059288I-715J1290D01*
G03X1485314Y1059302I-1113J-1927D01*
G01X1485291Y1059288D01*
X1485268Y1059275D01*
G02X1483816Y1059288I-715J1290D01*
G03X1481637Y1059300I-1100J-1904D01*
G01X1481621Y1059291D01*
G02X1481105Y1059017I-5834J10363D01*
G02X1480589Y1058898I-515J1057D01*
G01X1479014D01*
G03X1475304Y1057361I0J-5246D01*
G01X1529668Y1051070D02*
X1528740D01*
X1527324Y1049654D01*
G02X1527004Y1049514I-337J335D01*
G02X1526362Y1049676I-37J1205D01*
G01X1526321Y1049700D01*
G03X1524137Y1049676I-1071J-1951D01*
G02X1522663I-737J1276D01*
G01X1522622Y1049700D01*
G03X1520438Y1049676I-1071J-1951D01*
G02X1518964I-737J1276D01*
G01X1518923Y1049700D01*
G03X1516739Y1049676I-1071J-1951D01*
G02X1515265I-737J1276D01*
G01X1515224Y1049700D01*
G03X1513040Y1049676I-1071J-1951D01*
G02X1511566I-737J1276D01*
G03X1509382Y1049700I-1113J-1927D01*
G01X1509341Y1049676D01*
G02X1507867I-737J1276D01*
G01X1507843Y1049689D01*
G03X1505641Y1049675I-1089J-1940D01*
G02X1504189Y1049662I-737J1277D01*
G01X1504166Y1049675D01*
X1504143Y1049689D01*
G03X1501941Y1049675I-1089J-1940D01*
G02X1500489Y1049662I-737J1277D01*
G01X1500466Y1049675D01*
X1500443Y1049689D01*
G03X1498241Y1049675I-1089J-1940D01*
G02X1496789Y1049662I-737J1277D01*
G01X1496766Y1049675D01*
X1496743Y1049689D01*
G03X1494541Y1049675I-1089J-1940D01*
G02X1493089Y1049662I-737J1277D01*
G01X1493066Y1049675D01*
X1493043Y1049689D01*
G03X1490841Y1049675I-1089J-1940D01*
G02X1489389Y1049662I-737J1277D01*
G01X1489366Y1049675D01*
X1489343Y1049689D01*
G03X1487141Y1049675I-1089J-1940D01*
G02X1485638Y1049691I-738J1277D01*
G02X1485018Y1050447I766J1260D01*
G03X1484733Y1050996I-2239J-814D01*
G03X1484321Y1051640I-1101J-251D01*
G03X1483441Y1052229I-4869J-6322D01*
G03X1481967I-737J-1277D01*
G02X1479799Y1052195I-1115J1928D01*
G01X1479741Y1052229D01*
G03X1478267I-737J-1277D01*
G01X1478158Y1052165D01*
X1475304Y1050952D01*
G01X1529668Y1057463D02*
X1529576D01*
X1529340Y1057227D01*
X1528051D01*
X1527023Y1056199D01*
X1526321Y1056108D01*
G03X1524137Y1056084I-1071J-1951D01*
G02X1522697Y1056065I-737J1277D01*
G01X1522593Y1056125D01*
G03X1520439Y1056084I-1040J-1968D01*
G02X1519012Y1056057I-738J1277D01*
G01X1518965Y1056084D01*
X1518907Y1056118D01*
G03X1516739Y1056084I-1054J-1961D01*
G02X1515265I-737J1277D01*
G01X1515224Y1056108D01*
G03X1513040Y1056084I-1071J-1951D01*
G02X1511566I-737J1277D01*
G03X1509382Y1056108I-1113J-1927D01*
G01X1509341Y1056084D01*
G02X1507867I-737J1277D01*
G03X1505699Y1056118I-1114J-1927D01*
G01X1505641Y1056084D01*
G02X1504167I-737J1277D01*
G03X1501999Y1056118I-1114J-1927D01*
G01X1501941Y1056084D01*
G02X1500467I-737J1277D01*
G03X1498299Y1056118I-1114J-1927D01*
G01X1498241Y1056084D01*
G02X1496767I-737J1277D01*
G03X1494541I-1113J-1927D01*
G02X1493067I-737J1277D01*
G03X1490899Y1056118I-1114J-1927D01*
G01X1490841Y1056084D01*
G02X1489367I-737J1277D01*
G03X1487199Y1056118I-1114J-1927D01*
G01X1487141Y1056084D01*
G02X1485667I-737J1277D01*
G03X1483499Y1056118I-1114J-1927D01*
G01X1483441Y1056084D01*
G02X1482096Y1056018I-737J1277D01*
G02X1481967Y1056084I606J1344D01*
G01X1481966D01*
G03X1479572Y1055975I-1112J-1925D01*
G01X1478846Y1055463D01*
X1478813Y1055454D01*
X1478731Y1055396D01*
X1478018Y1055361D01*
X1477890Y1055434D01*
G03X1476416I-737J-1277D01*
G01X1476410Y1055431D01*
X1476381Y1055414D01*
G03X1475696Y1054382I773J-1256D01*
G01X1475471Y1054157D01*
X1473453D01*
G01X1529668Y1074942D02*
X1528947D01*
X1524879Y1070874D01*
Y1070178D01*
G02X1524176Y1068921I-1475J0D01*
G01X1524141Y1068901D01*
G02X1522667I-737J1277D01*
G03X1520499Y1068935I-1114J-1927D01*
G01X1520441Y1068901D01*
G02X1518967I-737J1277D01*
G03X1516799Y1068935I-1114J-1927D01*
G01X1516741Y1068901D01*
G02X1515267I-737J1277D01*
G03X1513099Y1068935I-1114J-1927D01*
G01X1513041Y1068901D01*
G02X1511567I-737J1277D01*
G01X1511566D01*
G03X1509341I-1112J-1927D01*
G02X1507883Y1068891I-738J1277D01*
G01X1507866Y1068901D01*
X1507843Y1068915D01*
G03X1505641Y1068901I-1089J-1940D01*
G02X1504189Y1068888I-737J1277D01*
G01X1504166Y1068901D01*
X1504143Y1068915D01*
G03X1501941Y1068901I-1089J-1940D01*
G02X1500489Y1068888I-737J1277D01*
G01X1500466Y1068901D01*
X1500443Y1068915D01*
G03X1498241Y1068901I-1089J-1940D01*
G02X1496789Y1068888I-737J1277D01*
G01X1496766Y1068901D01*
X1496743Y1068915D01*
G03X1494541Y1068901I-1089J-1940D01*
G02X1493089Y1068888I-737J1277D01*
G01X1493066Y1068901D01*
X1493043Y1068915D01*
G03X1490841Y1068901I-1089J-1940D01*
G02X1489389Y1068888I-737J1277D01*
G01X1489366Y1068901D01*
X1489343Y1068915D01*
G03X1487141Y1068901I-1089J-1940D01*
G02X1485638Y1068917I-738J1277D01*
G02X1485018Y1069673I766J1260D01*
G03X1484733Y1070222I-2239J-814D01*
G03X1484321Y1070866I-1101J-251D01*
G03X1483441Y1071455I-4869J-6322D01*
G03X1481967I-737J-1277D01*
G02X1479799Y1071421I-1115J1928D01*
G01X1479741Y1071455D01*
G03X1478267I-737J-1277D01*
G01X1478158Y1071391D01*
X1475304Y1070178D01*
G01X1527339Y1084578D02*
X1526909Y1084148D01*
Y1081966D01*
X1523258Y1078315D01*
X1521553D01*
G02X1520816Y1078514I3J1476D01*
G03X1518590I-1113J-1927D01*
G02X1517116I-737J1277D01*
G03X1514890I-1113J-1927D01*
G02X1513416I-737J1277D01*
G03X1511190I-1113J-1927D01*
G02X1509716I-737J1277D01*
G01X1509658Y1078548D01*
G03X1507490Y1078514I-1054J-1961D01*
G02X1506016I-737J1277D01*
G01X1505958Y1078548D01*
G03X1503790Y1078514I-1054J-1961D01*
G02X1502316I-737J1277D01*
G01X1502275Y1078538D01*
G03X1500091Y1078514I-1071J-1951D01*
G02X1498617I-737J1277D01*
G01X1498576Y1078538D01*
G03X1496390Y1078514I-1072J-1951D01*
G02X1494916I-737J1277D01*
G01X1494858Y1078548D01*
G03X1492690Y1078514I-1054J-1961D01*
G02X1491216I-737J1277D01*
G03X1489014Y1078528I-1113J-1927D01*
G01X1488991Y1078514D01*
X1488968Y1078501D01*
G02X1487516Y1078514I-715J1290D01*
G03X1485314Y1078528I-1113J-1927D01*
G01X1485291Y1078514D01*
X1485268Y1078501D01*
G02X1483816Y1078514I-715J1290D01*
G01X1483640Y1078616D01*
G03X1481855Y1078381I-739J-1280D01*
G01X1481837Y1078363D01*
G02X1481197Y1078098I-640J640D01*
G01X1478951D01*
G03X1475304Y1076587I0J-5157D01*
G01X1529668Y1080218D02*
X1529576D01*
X1529341Y1080453D01*
X1528827D01*
X1523233Y1074859D01*
X1521551D01*
G03X1520812Y1074661I0J-1477D01*
G01X1520813D01*
X1520814Y1074660D01*
G02X1518630Y1074636I-1113J1927D01*
G01X1518556Y1074679D01*
G03X1517116Y1074660I-703J-1296D01*
G02X1514890I-1113J1927D01*
G03X1513416I-737J-1277D01*
G02X1511190I-1113J1927D01*
G03X1509716I-737J-1277D01*
G01X1509658Y1074626D01*
G02X1507490Y1074660I-1054J1961D01*
G03X1506016I-737J-1277D01*
G01X1505958Y1074626D01*
G02X1503790Y1074660I-1054J1961D01*
G03X1502316I-737J-1277D01*
G01X1502258Y1074626D01*
G02X1500090Y1074660I-1054J1961D01*
G03X1498616I-737J-1277D01*
G01X1498575Y1074636D01*
G02X1496391Y1074660I-1071J1951D01*
G03X1494917I-737J-1277D01*
G01X1494876Y1074636D01*
G02X1492690Y1074660I-1072J1951D01*
G03X1491216I-737J-1277D01*
G01X1491158Y1074626D01*
G02X1488990Y1074660I-1054J1961D01*
G03X1487516I-737J-1277D01*
G01X1487458Y1074626D01*
G02X1485290Y1074660I-1054J1961D01*
G03X1483816I-737J-1277D01*
G01X1483758Y1074626D01*
G02X1481590Y1074660I-1054J1961D01*
G03X1480116I-737J-1277D01*
G01X1480110Y1074657D01*
X1480096Y1074649D01*
Y1074648D01*
G03X1480088Y1074643I775J-1250D01*
G03X1479445Y1073826I763J-1262D01*
G02X1479353Y1073598I-1408J435D01*
G01X1479127Y1073154D01*
G02X1479070Y1073075I-277J140D01*
G01X1478755Y1072760D01*
G02X1477925Y1072126I-2781J2781D01*
G01X1477890Y1072106D01*
G02X1476416I-737J1277D01*
G01X1476410Y1072109D01*
X1476381Y1072126D01*
G02X1475696Y1073158I773J1256D01*
G01X1475471Y1073383D01*
X1473453D01*
G01X1529359Y1099508D02*
X1528672D01*
X1525048Y1095884D01*
Y1095370D01*
X1524447Y1094769D01*
G02X1524140Y1094536I-1038J1049D01*
G03X1523028Y1092681I1113J-1928D01*
G01Y1092608D01*
G02X1522325Y1091351I-1475J0D01*
G01X1522290Y1091331D01*
G03X1521178Y1089443I1113J-1927D01*
G01Y1089404D01*
G02X1520475Y1088147I-1475J0D01*
G01X1520440Y1088127D01*
G02X1518966I-737J1277D01*
G03X1516740I-1113J-1927D01*
G02X1515266I-737J1277D01*
G03X1513040I-1113J-1927D01*
G02X1511566I-737J1277D01*
G03X1509382Y1088151I-1113J-1927D01*
G01X1509341Y1088127D01*
G02X1507867I-737J1277D01*
G03X1505699Y1088161I-1114J-1927D01*
G01X1505641Y1088127D01*
G02X1504167I-737J1277D01*
G03X1501999Y1088161I-1114J-1927D01*
G01X1501941Y1088127D01*
G02X1500467I-737J1277D01*
G03X1498281Y1088151I-1114J-1927D01*
G01X1498240Y1088127D01*
G02X1496766I-737J1277D01*
G03X1494582Y1088151I-1113J-1927D01*
G01X1494541Y1088127D01*
G02X1493067I-737J1277D01*
G03X1490899Y1088161I-1114J-1927D01*
G01X1490841Y1088127D01*
G02X1489367I-737J1277D01*
G03X1487199Y1088161I-1114J-1927D01*
G01X1487141Y1088127D01*
G02X1485001Y1088951I-737J1277D01*
G03X1483499Y1090647I-3347J-1451D01*
G01X1483441Y1090681D01*
G03X1481967I-737J-1277D01*
G02X1479799Y1090647I-1114J1927D01*
G01X1479741Y1090681D01*
G03X1478267I-737J-1276D01*
G01X1477557Y1090271D01*
G02X1477241Y1090123I-1040J1808D01*
G01X1475304Y1089404D01*
G01X1528769Y1105547D02*
X1528677D01*
X1528442Y1105782D01*
X1528195D01*
X1527853Y1105439D01*
X1526704Y1103296D01*
X1526359Y1102463D01*
X1525481Y1101150D01*
X1524967Y1100638D01*
G02X1524737Y1100441I-1557J1586D01*
G02X1522292Y1100295I-1333J1780D01*
G01X1522291D01*
X1522290Y1100294D01*
G03X1520078Y1099017I-737J-1277D01*
G01Y1098978D01*
G02X1518966Y1097090I-2225J39D01*
G01X1518931Y1097070D01*
G03X1518228Y1095813I772J-1257D01*
G01Y1095740D01*
G02X1514890Y1093885I-2225J73D01*
G03X1513416I-737J-1277D01*
G01X1513375Y1093861D01*
G02X1511189Y1093885I-1072J1952D01*
G03X1509715I-737J-1277D01*
G01X1509674Y1093861D01*
G02X1507490Y1093885I-1071J1952D01*
G03X1506016I-737J-1277D01*
G02X1503790I-1113J1928D01*
G03X1502316I-737J-1277D01*
G01X1502258Y1093851D01*
G02X1500090Y1093885I-1053J1962D01*
G03X1498616I-737J-1277D01*
G01X1498558Y1093851D01*
G02X1496390Y1093885I-1053J1962D01*
G03X1494916I-737J-1277D01*
G01X1494875Y1093861D01*
G02X1492691Y1093885I-1071J1952D01*
G03X1491217I-737J-1277D01*
G02X1489049Y1093851I-1115J1928D01*
G01X1488991Y1093885D01*
G03X1487517I-737J-1277D01*
G01X1487476Y1093861D01*
G02X1485290Y1093885I-1072J1952D01*
G03X1483816I-737J-1277D01*
G01X1483758Y1093851D01*
G02X1481590Y1093885I-1053J1962D01*
G03X1479397Y1092845I-737J-1277D01*
G02X1479168Y1092398I-807J131D01*
G01X1478755Y1091985D01*
G02X1477925Y1091351I-2781J2781D01*
G01X1477890Y1091331D01*
G02X1475696Y1092383I-737J1277D01*
G01X1475471Y1092608D01*
X1473453D01*
G01X1522683Y888967D02*
X1521141Y890509D01*
Y892295D01*
X1520209Y893690D01*
X1516615Y897284D01*
G03X1516308Y897517I-1038J-1049D01*
G03X1514834I-737J-1277D01*
G02X1512608I-1113J1928D01*
G03X1511134I-737J-1277D01*
G02X1508908I-1113J1928D01*
G03X1507434I-737J-1277D01*
G02X1505266Y897483I-1115J1928D01*
G01X1505208Y897517D01*
G03X1503734I-737J-1277D01*
G02X1501508I-1113J1928D01*
G03X1500034I-737J-1277D01*
G02X1497808I-1113J1928D01*
G03X1496334I-737J-1277D01*
G02X1494166Y897483I-1115J1928D01*
G01X1494108Y897517D01*
G03X1492634I-737J-1277D01*
G02X1490466Y897483I-1115J1928D01*
G01X1490408Y897517D01*
G03X1488934I-737J-1277D01*
G02X1486766Y897483I-1115J1928D01*
G01X1486708Y897517D01*
G02X1485595Y899389I1112J1928D01*
G01Y899445D01*
G03X1484892Y900702I-1475J0D01*
G01X1484857Y900722D01*
G02X1483994Y901626I1113J1927D01*
G01X1482271Y902649D01*
G01X1522649Y881426D02*
X1520900Y883175D01*
Y884039D01*
X1518909Y886030D01*
Y889936D01*
X1514765Y894080D01*
G03X1514458Y894313I-1038J-1049D01*
G03X1512984I-737J-1277D01*
G02X1510758I-1113J1927D01*
G03X1509284I-737J-1277D01*
G01X1509243Y894289D01*
G02X1507057Y894313I-1072J1951D01*
G03X1505583I-737J-1277D01*
G01X1505542Y894289D01*
G02X1503358Y894313I-1071J1951D01*
G03X1501884I-737J-1277D01*
G01X1501843Y894289D01*
G02X1499657Y894313I-1072J1951D01*
G03X1498183I-737J-1277D01*
G01X1498125Y894279D01*
G02X1495957Y894313I-1054J1961D01*
G03X1494483I-737J-1277D01*
G01X1494442Y894289D01*
G02X1492258Y894313I-1071J1951D01*
G03X1490784I-737J-1277D01*
G01X1490743Y894289D01*
G02X1488557Y894313I-1072J1951D01*
G03X1487083I-737J-1277D01*
G01X1487025Y894279D01*
G02X1484857Y894313I-1054J1961D01*
G01X1484840Y894323D01*
X1484833Y894327D01*
G02X1483745Y896240I1138J1913D01*
G03X1483042Y897497I-1475J0D01*
G01X1483007Y897517D01*
G02X1482718Y897716I1114J1927D01*
G01X1480420Y899445D01*
G01X1524373Y892336D02*
X1524138Y892571D01*
X1523323D01*
X1522742Y893152D01*
X1522275Y894279D01*
X1518190Y898364D01*
Y899835D01*
X1517395Y900630D01*
G03X1516684Y900724I-417J-417D01*
G01X1516683Y900723D01*
G02X1514459I-1112J1926D01*
G03X1512982I-739J-1278D01*
G01X1512983Y900721D01*
G02X1510758Y900722I-1112J1928D01*
G03X1509284I-737J-1277D01*
G01X1509243Y900698D01*
G02X1507057Y900722I-1072J1951D01*
G03X1505583I-737J-1277D01*
G01X1505542Y900698D01*
G02X1503358Y900722I-1071J1951D01*
G03X1501884I-737J-1277D01*
G02X1499658I-1113J1927D01*
G03X1498184I-737J-1277D01*
G01X1498143Y900698D01*
G02X1495957Y900722I-1072J1951D01*
G03X1494483I-737J-1277D01*
G01X1494425Y900688D01*
G02X1492257Y900722I-1054J1961D01*
G03X1490783I-737J-1277D01*
G01X1490725Y900688D01*
G02X1488557Y900722I-1054J1961D01*
G01X1488533Y900736D01*
G02X1488505Y900752I1090J1941D01*
G01X1488506Y900754D01*
G02X1487447Y902649I1166J1895D01*
G03X1486748Y903904I-1476J0D01*
G01X1486742Y903907D01*
X1486645Y903962D01*
X1486136Y904188D01*
X1484738D01*
X1484132Y904309D01*
X1483936Y904390D01*
G02X1483383Y904576I184J1463D01*
G01X1483377Y904579D01*
X1483348Y904596D01*
G02X1482663Y905628I773J1256D01*
G01X1482438Y905853D01*
X1480420D01*
G01X1524950Y903949D02*
X1524514Y904385D01*
X1523483D01*
X1522696Y905172D01*
Y907720D01*
X1520315Y910101D01*
G03X1520008Y910334I-1038J-1049D01*
G03X1518534I-737J-1277D01*
G02X1516308I-1113J1928D01*
G03X1514834I-737J-1277D01*
G02X1512608I-1113J1928D01*
G03X1511134I-737J-1277D01*
G02X1508908I-1113J1928D01*
G03X1507434I-737J-1277D01*
G02X1505208I-1113J1928D01*
G03X1503734I-737J-1277D01*
G02X1501508I-1113J1928D01*
G03X1500034I-737J-1277D01*
G02X1497848Y910310I-1114J1928D01*
G01X1497807Y910334D01*
G03X1496333I-737J-1277D01*
G02X1494149Y910310I-1113J1928D01*
G01X1494108Y910334D01*
G02X1492995Y912206I1112J1928D01*
G01Y912262D01*
G03X1492292Y913519I-1475J0D01*
G01X1492257Y913539D01*
G03X1490783I-737J-1277D01*
G01X1490725Y913505D01*
G02X1488557Y913539I-1054J1961D01*
G03X1487083I-737J-1277D01*
G01X1487042Y913515D01*
G02X1484858Y913539I-1071J1951D01*
G03X1483384I-737J-1277D01*
G01X1483268Y913471D01*
X1480420Y912262D01*
G01X1524465Y898765D02*
X1523240D01*
X1522520Y899485D01*
Y902800D01*
X1518293Y907027D01*
G03X1518158Y907130I-451J-451D01*
G03X1516684I-737J-1277D01*
G02X1514458I-1113J1927D01*
G03X1512984I-737J-1277D01*
G02X1510758I-1113J1927D01*
G03X1509284I-737J-1277D01*
G02X1507058I-1113J1927D01*
G03X1505584I-737J-1277D01*
G02X1503358I-1113J1927D01*
G03X1501884I-737J-1277D01*
G01X1501843Y907106D01*
G02X1499657Y907130I-1072J1951D01*
G03X1498183I-737J-1277D01*
G02X1495999Y907106I-1113J1927D01*
G01X1495958Y907130D01*
G03X1494484I-737J-1277D01*
G01X1494443Y907106D01*
G02X1492257Y907130I-1072J1951D01*
G02X1491146Y908996I1114J1927D01*
G01Y909057D01*
G03X1490443Y910314I-1475J0D01*
G01X1490408Y910334D01*
G03X1488934I-737J-1277D01*
G02X1486766Y910300I-1115J1928D01*
G01X1486708Y910334D01*
G03X1485234I-737J-1277D01*
G01X1485124Y910270D01*
X1482271Y909057D01*
G01X1524373Y893556D02*
X1524137Y893320D01*
X1523634D01*
X1523378Y893577D01*
X1522911Y894704D01*
X1518939Y898675D01*
Y900146D01*
X1517925Y901160D01*
G03X1516310Y901373I-946J-947D01*
G01X1516308Y901372D01*
G02X1514834I-737J1277D01*
G03X1512608I-1113J-1927D01*
G02X1511134I-737J1277D01*
G03X1508908I-1113J-1927D01*
G02X1507434I-737J1277D01*
G03X1505266Y901406I-1114J-1927D01*
G01X1505208Y901372D01*
G02X1503734I-737J1277D01*
G03X1501508I-1113J-1927D01*
G02X1500034I-737J1277D01*
G03X1497808I-1113J-1927D01*
G02X1496334I-737J1277D01*
G03X1494166Y901406I-1114J-1927D01*
G01X1494108Y901372D01*
G02X1492634I-737J1277D01*
G03X1490466Y901406I-1114J-1927D01*
G01X1490408Y901372D01*
G02X1488934I-737J1277D01*
G01X1488899Y901392D01*
G02X1488196Y902649I772J1257D01*
G03X1487131Y904548I-2226J0D01*
G01X1487116Y904557D01*
X1486985Y904632D01*
X1486295Y904937D01*
X1484813D01*
X1484358Y905028D01*
X1484120Y905266D01*
Y905853D01*
G01X1528199Y924958D02*
X1527444D01*
X1527046Y925356D01*
Y926107D01*
X1525849Y927304D01*
X1524820D01*
G03X1523708Y927006I0J-2224D01*
G02X1522234I-737J1277D01*
G01X1522199Y927026D01*
G02X1521496Y928283I772J1257D01*
G01Y928339D01*
G03X1520383Y930211I-2225J-56D01*
G01X1520325Y930245D01*
G03X1518157Y930211I-1053J-1962D01*
G02X1516683I-737J1277D01*
G01X1516625Y930245D01*
G03X1514457Y930211I-1053J-1962D01*
G02X1512983I-737J1277D01*
G01X1512925Y930245D01*
G03X1510757Y930211I-1053J-1962D01*
G02X1509283I-737J1277D01*
G01X1509242Y930235D01*
G03X1507058Y930211I-1071J-1952D01*
G02X1505584I-737J1277D01*
G03X1503358I-1113J-1928D01*
G02X1501884I-737J1277D01*
G01X1501843Y930235D01*
G03X1499657Y930211I-1072J-1952D01*
G02X1498183I-737J1277D01*
G03X1495957I-1113J-1928D01*
G02X1494483I-737J1277D01*
G01X1494425Y930245D01*
G03X1492257Y930211I-1053J-1962D01*
G02X1490783I-737J1277D01*
G01X1490725Y930245D01*
G03X1488557Y930211I-1053J-1962D01*
G02X1487083I-737J1277D01*
G01X1487042Y930235D01*
G03X1484858Y930211I-1071J-1952D01*
G01X1484887Y930227D01*
X1484469Y929982D01*
G03X1482272Y928284I5523J-9416D01*
G01X1482271Y928283D01*
G01X1528009Y914535D02*
X1527108D01*
X1524717Y916926D01*
G03X1523914Y917482I-1935J-1936D01*
G02X1523900Y917489I1217J2452D01*
G03X1521858Y917393I-928J-2023D01*
G02X1520384I-737J1277D01*
G03X1518158I-1113J-1927D01*
G02X1516684I-737J1277D01*
G01X1516649Y917413D01*
G02X1515946Y918670I772J1257D01*
G01Y918743D01*
G03X1514834Y920598I-2225J-73D01*
G03X1512608I-1113J-1928D01*
G02X1511134I-737J1277D01*
G03X1508908I-1113J-1928D01*
G02X1507434I-737J1277D01*
G03X1505208I-1113J-1928D01*
G02X1503734I-737J1277D01*
G03X1501508I-1113J-1928D01*
G02X1500034I-737J1277D01*
G03X1497808I-1113J-1928D01*
G02X1496334I-737J1277D01*
G01X1496304Y920614D01*
G03X1494108Y920597I-1083J-1944D01*
G02X1492651Y920587I-737J1278D01*
G01X1492604Y920614D01*
G03X1490408Y920597I-1083J-1944D01*
G02X1488951Y920587I-737J1278D01*
G01X1488933Y920597D01*
X1488904Y920614D01*
G03X1486708Y920597I-1083J-1944D01*
G02X1485251Y920587I-737J1278D01*
G01X1483672Y921499D01*
G03X1482271Y921875I-1402J-2424D01*
G01X1528009Y910558D02*
X1527409D01*
X1526301Y911666D01*
Y912896D01*
X1525204Y913993D01*
X1523026D01*
G02X1522234Y914189I-56J1473D01*
G03X1520008I-1113J-1927D01*
G02X1518534I-737J1277D01*
G03X1516308I-1113J-1927D01*
G02X1514834I-737J1277D01*
G01X1514799Y914209D01*
G02X1514096Y915466I772J1257D01*
G01Y915505D01*
G03X1512984Y917393I-2225J-39D01*
G03X1510758I-1113J-1927D01*
G02X1509284I-737J1277D01*
G03X1507058I-1113J-1927D01*
G02X1505584I-737J1277D01*
G03X1503358I-1113J-1927D01*
G02X1501884I-737J1277D01*
G03X1499716Y917427I-1114J-1927D01*
G01X1499658Y917393D01*
G02X1498184I-737J1277D01*
G01X1498143Y917417D01*
G03X1495957Y917393I-1072J-1951D01*
G02X1494483I-737J1277D01*
G01X1494425Y917427D01*
G03X1492257Y917393I-1054J-1961D01*
G02X1490783I-737J1277D01*
G01X1490725Y917427D01*
G03X1488557Y917393I-1054J-1961D01*
G02X1487083I-737J1277D01*
G01X1487025Y917427D01*
G03X1484857Y917393I-1054J-1961D01*
G02X1483383I-737J1277D01*
G01X1483325Y917427D01*
G03X1481157Y917393I-1054J-1961D01*
G02X1479683I-737J1277D01*
G01X1479648Y917413D01*
G02X1478963Y918444I773J1256D01*
G01X1479189Y918670D01*
X1480420D01*
G01X1528199Y928908D02*
X1526961D01*
X1525858Y930011D01*
X1524820D01*
G02X1524083Y930211I5J1476D01*
G01X1524048Y930231D01*
G02X1523345Y931488I772J1257D01*
G01Y931549D01*
G03X1522234Y933415I-2225J-61D01*
G03X1520066Y933449I-1114J-1927D01*
G01X1520008Y933415D01*
G02X1518534I-737J1276D01*
G03X1516366Y933449I-1114J-1927D01*
G01X1516308Y933415D01*
G02X1514834I-737J1276D01*
G03X1512666Y933449I-1114J-1927D01*
G01X1512608Y933415D01*
G02X1511134I-737J1276D01*
G03X1508966Y933449I-1114J-1927D01*
G01X1508908Y933415D01*
G02X1507434I-737J1276D01*
G03X1505208I-1113J-1927D01*
G02X1503734I-737J1276D01*
G01X1503693Y933439D01*
G03X1501507Y933415I-1072J-1951D01*
G02X1500033I-737J1276D01*
G03X1497849Y933439I-1113J-1927D01*
G01X1497808Y933415D01*
G02X1496334I-737J1276D01*
G03X1494166Y933449I-1114J-1927D01*
G01X1494108Y933415D01*
G02X1492634I-737J1276D01*
G03X1490466Y933449I-1114J-1927D01*
G01X1490408Y933415D01*
G02X1488934I-737J1276D01*
G03X1486766Y933449I-1114J-1927D01*
G01X1486708Y933415D01*
G02X1485234I-737J1276D01*
G03X1483008I-1113J-1927D01*
G01X1482702Y933238D01*
G03X1480420Y931488I5495J-9528D01*
G01X1527566Y921023D02*
X1527361D01*
X1527125Y920787D01*
X1526602D01*
X1525836Y921552D01*
G03X1525485Y921852I-2159J-2170D01*
G01X1523770Y923113D01*
G03X1521414Y923631I-1762J-2397D01*
G02X1520383Y923802I-290J1447D01*
G01X1520377Y923805D01*
X1520348Y923822D01*
G02X1519645Y925079I772J1257D01*
G01Y925140D01*
G03X1518534Y927006I-2225J-61D01*
G03X1516366Y927040I-1114J-1927D01*
G01X1516308Y927006D01*
G02X1514834I-737J1277D01*
G03X1512666Y927040I-1114J-1927D01*
G01X1512608Y927006D01*
G02X1511134I-737J1277D01*
G03X1508908I-1113J-1927D01*
G02X1507434I-737J1277D01*
G03X1505208I-1113J-1927D01*
G02X1503734I-737J1277D01*
G03X1501508I-1113J-1927D01*
G02X1500034I-737J1277D01*
G03X1497848Y927030I-1114J-1927D01*
G01X1497807Y927006D01*
X1497808D01*
G02X1496356Y926993I-737J1277D01*
G01X1496310Y927019D01*
G03X1494108Y927006I-1090J-1940D01*
G02X1492656Y926993I-737J1277D01*
G01X1492610Y927019D01*
G03X1490408Y927006I-1090J-1940D01*
G02X1488956Y926993I-737J1277D01*
G02X1488949Y926996I575J1350D01*
G01X1488946Y926998D01*
X1488936Y927004D01*
X1488897Y927025D01*
G03X1486602Y926941I-1078J-1948D01*
G01X1485663Y926328D01*
X1484967Y926294D01*
X1484857Y926356D01*
G03X1482663Y925304I-737J-1277D01*
G01X1482438Y925079D01*
X1480420D01*
G01X1527566Y919803D02*
X1527360D01*
X1527125Y920038D01*
X1526291D01*
X1525307Y921021D01*
G03X1525042Y921248I-1632J-1637D01*
G01X1523326Y922509D01*
G03X1521564Y922897I-1318J-1793D01*
G02X1520066Y923118I-443J2181D01*
G01X1520008Y923152D01*
X1519999Y923157D01*
X1519991Y923162D01*
X1519984Y923166D01*
G02X1518895Y925079I1136J1913D01*
G03X1518192Y926336I-1475J0D01*
G01X1518157Y926356D01*
G03X1516683I-737J-1277D01*
G01X1516625Y926322D01*
G02X1514457Y926356I-1054J1961D01*
G03X1512983I-737J-1277D01*
G01X1512942Y926332D01*
G02X1510758Y926356I-1071J1951D01*
G03X1509284I-737J-1277D01*
G02X1507058I-1113J1927D01*
G03X1505584I-737J-1277D01*
G02X1503358I-1113J1927D01*
G03X1501884I-737J-1277D01*
G01X1501843Y926332D01*
G02X1499657Y926356I-1072J1951D01*
G03X1498183I-737J-1277D01*
G02X1495981Y926343I-1112J1927D01*
G01X1495935Y926369D01*
G03X1494483Y926356I-715J-1290D01*
G02X1492281Y926343I-1112J1927D01*
G01X1492235Y926369D01*
G03X1490783Y926356I-715J-1290D01*
G02X1488581Y926343I-1112J1927D01*
G01X1488577Y926345D01*
X1488574Y926347D01*
X1488535Y926369D01*
G03X1487012Y926314I-716J-1293D01*
G01X1485903Y925590D01*
X1484564Y925523D01*
X1484120Y925079D01*
G01X1529066Y947078D02*
X1527973D01*
X1526956Y948095D01*
X1524491D01*
X1523708Y948786D01*
G03X1522234I-737J-1277D01*
G02X1520008I-1113J1927D01*
G03X1518534I-737J-1277D01*
G02X1516308I-1113J1927D01*
G03X1514834I-737J-1277D01*
G02X1512608I-1113J1927D01*
G03X1511134I-737J-1277D01*
G02X1508908I-1113J1927D01*
G03X1507434I-737J-1277D01*
G02X1505266Y948752I-1114J1927D01*
G01X1505208Y948786D01*
G03X1503734I-737J-1277D01*
G02X1501508I-1113J1927D01*
G03X1500034I-737J-1277D01*
G02X1497848Y948762I-1114J1927D01*
G01X1497807Y948786D01*
G03X1496333I-737J-1277D01*
G02X1494149Y948762I-1113J1927D01*
G01X1494108Y948786D01*
G03X1492634I-737J-1277D01*
G02X1490466Y948752I-1114J1927D01*
G01X1490408Y948786D01*
G03X1488934I-737J-1277D01*
G02X1486766Y948752I-1114J1927D01*
G01X1486708Y948786D01*
G03X1485234I-737J-1277D01*
G02X1483008I-1113J1927D01*
G03X1481534I-737J-1277D01*
G01X1481499Y948766D01*
G03X1480814Y947735I773J-1256D01*
G01X1481040Y947509D01*
X1482271D01*
G01X1529066Y936581D02*
X1527787D01*
X1525131Y939237D01*
X1524321D01*
G03X1524084Y939173I0J-472D01*
G02X1521858I-1113J1927D01*
G03X1520384I-737J-1277D01*
G02X1518158I-1113J1927D01*
G03X1516684I-737J-1277D01*
G02X1514458I-1113J1927D01*
G03X1512984I-737J-1277D01*
G02X1510758I-1113J1927D01*
G03X1509284I-737J-1277D01*
G02X1507058I-1113J1927D01*
G03X1505584I-737J-1277D01*
G01X1505583D01*
G02X1503358I-1112J1927D01*
G01X1503348Y939179D01*
G03X1501883Y939173I-727J-1283D01*
G02X1499687Y939156I-1113J1927D01*
G01X1499658Y939173D01*
X1499640Y939184D01*
G03X1498183Y939173I-719J-1288D01*
G02X1495987Y939156I-1113J1927D01*
G01X1495958Y939173D01*
X1495940Y939184D01*
G03X1494483Y939173I-719J-1288D01*
G02X1492287Y939156I-1113J1927D01*
G01X1492258Y939173D01*
X1492240Y939184D01*
G03X1490783Y939173I-719J-1288D01*
G02X1488587Y939156I-1113J1927D01*
G01X1488558Y939173D01*
X1488540Y939184D01*
G03X1487083Y939173I-719J-1288D01*
G02X1484887Y939156I-1113J1927D01*
G01X1484449Y939414D01*
G02X1482272Y941099I5539J9405D01*
G01X1482271Y941100D01*
G01X1528199Y932069D02*
X1527681D01*
X1524015Y935735D01*
G03X1523708Y935968I-1038J-1049D01*
G03X1522234I-737J-1277D01*
G02X1520008I-1113J1928D01*
G03X1518534I-737J-1277D01*
G02X1516308I-1113J1928D01*
G03X1514834I-737J-1277D01*
G02X1512608I-1113J1928D01*
G03X1511134I-737J-1277D01*
G02X1508908I-1113J1928D01*
G03X1507434I-737J-1277D01*
G02X1505208I-1113J1928D01*
G01Y935969D01*
G03X1503733I-737J-1277D01*
G01X1503719Y935960D01*
G02X1501508Y935969I-1098J1936D01*
G03X1500056Y935982I-737J-1277D01*
G01X1500033Y935969D01*
X1500010Y935955D01*
G02X1497808Y935969I-1089J1941D01*
G03X1496356Y935982I-737J-1277D01*
G01X1496333Y935969D01*
X1496310Y935955D01*
G02X1494108Y935969I-1089J1941D01*
G03X1492656Y935982I-737J-1277D01*
G01X1492633Y935969D01*
X1492610Y935955D01*
G02X1490408Y935969I-1089J1941D01*
G03X1488956Y935982I-737J-1277D01*
G01X1488933Y935969D01*
X1488910Y935955D01*
G02X1486708Y935969I-1089J1941D01*
G03X1485256Y935982I-737J-1277D01*
G01X1485233Y935969D01*
X1485210Y935955D01*
G02X1483008Y935969I-1089J1941D01*
G01X1482693Y936151D01*
G02X1480420Y937896I5502J9519D01*
G01X1528974Y941915D02*
X1528738Y941679D01*
X1527785D01*
X1526636Y942828D01*
X1524820D01*
G02X1524025Y943061I1J1476D01*
G03X1521857Y943027I-1054J-1961D01*
G02X1520383I-737J1277D01*
G01X1520325Y943061D01*
G03X1518157Y943027I-1054J-1961D01*
G02X1516683I-737J1277D01*
G01X1516625Y943061D01*
G03X1514457Y943027I-1054J-1961D01*
G02X1512983I-737J1277D01*
G01X1512982D01*
G03X1510760Y943026I-1110J-1927D01*
G01X1510758Y943027D01*
G02X1509284I-737J1277D01*
G01X1509243Y943051D01*
G03X1507057Y943027I-1072J-1951D01*
G02X1505583I-737J1277D01*
G01X1505542Y943051D01*
G03X1503358Y943027I-1071J-1951D01*
G02X1501884I-737J1277D01*
G01X1501843Y943051D01*
G03X1499657Y943027I-1072J-1951D01*
G02X1498183I-737J1277D01*
G01X1498142Y943051D01*
G03X1495958Y943027I-1071J-1951D01*
G02X1494484I-737J1277D01*
G01X1494443Y943051D01*
G03X1492257Y943027I-1072J-1951D01*
G02X1490783I-737J1277D01*
G01X1490725Y943061D01*
G03X1488557Y943027I-1054J-1961D01*
G02X1487083I-737J1277D01*
G01X1486604Y943304D01*
X1486290Y943388D01*
X1484813D01*
X1484358Y943479D01*
X1484120Y943717D01*
Y944304D01*
G01X1528974Y940695D02*
X1528739Y940930D01*
X1527474D01*
X1526325Y942079D01*
X1525070D01*
X1525069Y942078D01*
X1525068Y942079D01*
X1524819D01*
G02X1523708Y942377I1J2225D01*
G03X1522234I-737J-1277D01*
G02X1520066Y942343I-1114J1927D01*
G01X1520008Y942377D01*
G03X1518534I-737J-1277D01*
G02X1516366Y942343I-1114J1927D01*
G01X1516308Y942377D01*
G03X1514834I-737J-1277D01*
G02X1512666Y942343I-1114J1927D01*
G01X1512608Y942377D01*
G03X1511134I-737J-1277D01*
G02X1508908I-1113J1927D01*
G03X1507434I-737J-1277D01*
G02X1505266Y942343I-1114J1927D01*
G01X1505208Y942377D01*
G03X1503734I-737J-1277D01*
G02X1501508I-1113J1927D01*
G03X1500034I-737J-1277D01*
G02X1497866Y942343I-1114J1927D01*
G01X1497808Y942377D01*
G03X1496334I-737J-1277D01*
G02X1494108I-1113J1927D01*
G03X1492634I-737J-1277D01*
G02X1490466Y942343I-1114J1927D01*
G01X1490408Y942377D01*
G03X1488934I-737J-1277D01*
G01X1488932Y942378D01*
G02X1486708I-1112J1926D01*
G01X1486314Y942606D01*
X1486191Y942639D01*
X1484739D01*
X1484132Y942760D01*
X1483936Y942841D01*
G02X1483383Y943027I184J1463D01*
G01X1483377Y943030D01*
X1483348Y943047D01*
G02X1482663Y944079I773J1256D01*
G01X1482438Y944304D01*
X1480420D01*
G01X1529066Y951015D02*
X1528077D01*
X1526572Y952520D01*
X1524709D01*
X1524269Y952080D01*
G03X1524084Y951990I551J-1368D01*
G02X1521858I-1113J1927D01*
G03X1520384I-737J-1277D01*
G02X1518158I-1113J1927D01*
G03X1516684I-737J-1277D01*
G02X1514458I-1113J1927D01*
G03X1512984I-737J-1277D01*
G02X1510758I-1113J1927D01*
G03X1509284I-737J-1277D01*
G01X1509243Y951966D01*
G02X1507057Y951990I-1072J1951D01*
G03X1505583I-737J-1277D01*
G01X1505542Y951966D01*
G02X1503358Y951990I-1071J1951D01*
G03X1501884I-737J-1277D01*
G01X1501843Y951966D01*
G02X1499657Y951990I-1072J1951D01*
G03X1498183I-737J-1277D01*
G01X1498125Y951956D01*
G02X1495957Y951990I-1054J1961D01*
G03X1494483I-737J-1277D01*
G01X1494425Y951956D01*
G02X1492257Y951990I-1054J1961D01*
G03X1490783I-737J-1277D01*
G01X1490725Y951956D01*
G02X1488557Y951990I-1054J1961D01*
G03X1487083I-737J-1277D01*
G01X1487042Y951966D01*
G02X1484858Y951990I-1071J1951D01*
G03X1483384I-737J-1277D01*
G01X1483343Y951966D01*
G02X1481157Y951990I-1072J1951D01*
G03X1479683I-737J-1277D01*
G01X1479648Y951970D01*
G03X1478963Y950939I773J-1256D01*
G01X1479189Y950713D01*
X1480420D01*
G01X1518319Y956697D02*
X1517509D01*
X1516105Y958101D01*
X1515571D01*
G02X1514458Y958399I-1J2225D01*
G03X1512984I-737J-1277D01*
G02X1510758I-1113J1927D01*
G03X1509284I-737J-1277D01*
G01X1509243Y958375D01*
G02X1507057Y958399I-1072J1951D01*
G03X1505583I-737J-1277D01*
G01X1505542Y958375D01*
G02X1503358Y958399I-1071J1951D01*
G03X1501884I-737J-1277D01*
G02X1499658I-1113J1927D01*
G03X1498184I-737J-1277D01*
G01X1498143Y958375D01*
G02X1495957Y958399I-1072J1951D01*
G03X1494483I-737J-1277D01*
G01X1494425Y958365D01*
G02X1492257Y958399I-1054J1961D01*
G03X1490783I-737J-1277D01*
G01X1490725Y958365D01*
G02X1488557Y958399I-1054J1961D01*
G03X1487083I-737J-1277D01*
G02X1484857I-1113J1927D01*
G03X1483383I-737J-1277D01*
G01X1483325Y958365D01*
G02X1481157Y958399I-1054J1961D01*
G03X1479683I-737J-1277D01*
G01X1479648Y958379D01*
G03X1478963Y957347I773J-1256D01*
G01X1479188Y957122D01*
X1480420D01*
G01X1516735Y962793D02*
X1515961Y962019D01*
X1515357D01*
X1515294Y961956D01*
G02X1512666Y961569I-1574J1574D01*
G01X1512608Y961603D01*
G03X1511134I-737J-1277D01*
G02X1508908I-1113J1927D01*
G03X1507434I-737J-1277D01*
G02X1505266Y961569I-1114J1927D01*
G01X1505208Y961603D01*
G03X1503734I-737J-1277D01*
G02X1501508I-1113J1927D01*
G03X1500034I-737J-1277D01*
G02X1497866Y961569I-1114J1927D01*
G01X1497808Y961603D01*
G03X1496334I-737J-1277D01*
G02X1494108I-1113J1927D01*
G03X1492634I-737J-1277D01*
G02X1490466Y961569I-1114J1927D01*
G01X1490408Y961603D01*
G03X1488934I-737J-1277D01*
G02X1486748Y961579I-1114J1927D01*
G01X1486707Y961603D01*
G03X1485233I-737J-1277D01*
G02X1484333Y961315I-1113J1927D01*
G03X1482303Y960358I318J-3306D01*
G01X1482271Y960326D01*
G01X1486248Y996900D02*
Y997684D01*
X1484929Y999003D01*
Y999684D01*
G03X1483840Y1001597I-2225J0D01*
G01X1482295Y1002498D01*
G03X1480853Y1002888I-1442J-2472D01*
G01X1484178Y996900D02*
Y999718D01*
G03X1483441Y1000961I-1474J-34D01*
G03X1482741Y1001267I-1712J-2962D01*
G03X1482394Y1001319I-345J-1122D01*
G01X1480941D01*
G02X1477153Y1002888I0J5356D01*
G01X1512613Y996825D02*
X1496555D01*
X1495278Y998102D01*
Y999780D01*
G03X1494585Y1001019I-1454J0D01*
G03X1493832Y1001219I-753J-1318D01*
G01X1491161D01*
X1488253Y1002888D01*
G01X1526167Y1023653D02*
X1523695D01*
X1523547Y1023801D01*
G02X1522631Y1024061I0J1744D01*
G02X1521928Y1025318I772J1257D01*
G01Y1025391D01*
G03X1520816Y1027246I-2225J-73D01*
G03X1518590I-1113J-1928D01*
G02X1517116I-737J1277D01*
G03X1514890I-1113J-1928D01*
G02X1513416I-737J1277D01*
G03X1511190I-1113J-1928D01*
G02X1509716I-737J1277D01*
G03X1507490I-1113J-1928D01*
G02X1506016I-737J1277D01*
G01X1505958Y1027280D01*
G03X1503790Y1027246I-1053J-1962D01*
G02X1502316I-737J1277D01*
G03X1500090I-1113J-1928D01*
G02X1498616I-737J1277D01*
G01X1498558Y1027280D01*
G03X1496390Y1027246I-1053J-1962D01*
G02X1494916I-737J1277D01*
G01X1494858Y1027280D01*
G03X1492690Y1027246I-1053J-1962D01*
G02X1491216I-737J1277D01*
G01X1491158Y1027280D01*
G03X1488990Y1027246I-1053J-1962D01*
G02X1487516I-737J1277D01*
G01X1487458Y1027280D01*
G03X1485290Y1027246I-1053J-1962D01*
G02X1483816I-737J1277D01*
G01X1483781Y1027266D01*
G02X1483078Y1028523I772J1257D01*
G01Y1028584D01*
G03X1481967Y1030450I-2225J-61D01*
G03X1479799Y1030484I-1114J-1927D01*
G01X1479741Y1030450D01*
X1479717Y1030436D01*
G03X1478643Y1028782I1136J-1913D01*
G01X1478384Y1028523D01*
X1477153D01*
G01X1529167Y1025674D02*
X1527228D01*
X1526607Y1026295D01*
X1525256D01*
G02X1524140Y1026595I0J2226D01*
G02X1523028Y1028450I1113J1928D01*
G01Y1028523D01*
G03X1522325Y1029780I-1475J0D01*
G01X1522290Y1029800D01*
G03X1520816I-737J-1277D01*
G02X1518590I-1113J1927D01*
G03X1517116I-737J-1277D01*
G02X1514890I-1113J1927D01*
G03X1513416I-737J-1277D01*
G02X1511190I-1113J1927D01*
G03X1509716I-737J-1277D01*
G02X1507490I-1113J1927D01*
G03X1506016I-737J-1277D01*
G01X1505958Y1029766D01*
G02X1503790Y1029800I-1054J1961D01*
G03X1502316I-737J-1277D01*
G01X1502258Y1029766D01*
G02X1500090Y1029800I-1054J1961D01*
G03X1498616I-737J-1277D01*
G02X1496390I-1113J1927D01*
G03X1494916I-737J-1277D01*
G01X1494858Y1029766D01*
G02X1492690Y1029800I-1054J1961D01*
G03X1491216I-737J-1277D01*
G01X1491158Y1029766D01*
G02X1488990Y1029800I-1054J1961D01*
G03X1487516I-737J-1277D01*
G01X1487458Y1029766D01*
G02X1485290Y1029800I-1054J1961D01*
G02X1482704Y1031727I6959J12037D01*
G01X1526167Y1021693D02*
X1524389D01*
X1523004Y1023078D01*
G02X1521178Y1025257I462J2242D01*
G01Y1025318D01*
G03X1520475Y1026575I-1475J0D01*
G01X1520440Y1026595D01*
G03X1518966I-737J-1277D01*
G02X1516740I-1113J1928D01*
G03X1515266I-737J-1277D01*
G02X1513040I-1113J1928D01*
G03X1511566I-737J-1277D01*
G02X1509340I-1113J1928D01*
G03X1507866I-737J-1277D01*
G02X1505682Y1026571I-1113J1928D01*
G01X1505641Y1026595D01*
G03X1504167I-737J-1277D01*
G02X1501981Y1026571I-1114J1928D01*
G01X1501940Y1026595D01*
G03X1500466I-737J-1277D01*
G02X1498282Y1026571I-1113J1928D01*
G01X1498241Y1026595D01*
G03X1496767I-737J-1277D01*
G02X1494599Y1026561I-1115J1928D01*
G01X1494541Y1026595D01*
G03X1493067I-737J-1277D01*
G02X1490899Y1026561I-1115J1928D01*
G01X1490841Y1026595D01*
G03X1489367I-737J-1277D01*
G02X1487199Y1026561I-1115J1928D01*
G01X1487141Y1026595D01*
G03X1485667I-737J-1277D01*
G02X1483499Y1026561I-1115J1928D01*
G01X1483441Y1026595D01*
G02X1482328Y1028467I1112J1928D01*
G01Y1028523D01*
G03X1481625Y1029780I-1475J0D01*
G01X1481590Y1029800D01*
G03X1480116I-737J-1277D01*
G01X1480081Y1029780D01*
G03X1479396Y1028749I773J-1256D01*
G01X1479622Y1028523D01*
X1480853D01*
G01X1529668Y1042014D02*
X1527727D01*
X1526827Y1042914D01*
G03X1524199Y1043301I-1574J-1574D01*
G01X1524141Y1043267D01*
G02X1522667I-737J1277D01*
G03X1520499Y1043301I-1114J-1927D01*
G01X1520441Y1043267D01*
G02X1518967I-737J1277D01*
G03X1516799Y1043301I-1114J-1927D01*
G01X1516741Y1043267D01*
G02X1515267I-737J1277D01*
G03X1513099Y1043301I-1114J-1927D01*
G01X1513041Y1043267D01*
G02X1511567I-737J1277D01*
G03X1509399Y1043301I-1114J-1927D01*
G01X1509341Y1043267D01*
G02X1507867I-737J1277D01*
G03X1505699Y1043301I-1114J-1927D01*
G01X1505641Y1043267D01*
G02X1504184Y1043256I-738J1277D01*
G01X1504166Y1043267D01*
X1504137Y1043284D01*
G03X1501941Y1043267I-1083J-1944D01*
G02X1500484Y1043256I-738J1277D01*
G01X1500466Y1043267D01*
X1500437Y1043284D01*
G03X1498241Y1043267I-1083J-1944D01*
G02X1496784Y1043256I-738J1277D01*
G01X1496766Y1043267D01*
X1496737Y1043284D01*
G03X1494541Y1043267I-1083J-1944D01*
G02X1493084Y1043256I-738J1277D01*
G01X1493066Y1043267D01*
X1493037Y1043284D01*
G03X1490841Y1043267I-1083J-1944D01*
G02X1489384Y1043256I-738J1277D01*
G01X1489366Y1043267D01*
X1489337Y1043284D01*
G03X1487141Y1043267I-1083J-1944D01*
G02X1485684Y1043256I-738J1277D01*
G01X1485666Y1043267D01*
X1485637Y1043284D01*
G03X1483441Y1043267I-1083J-1944D01*
G02X1481984Y1043256I-738J1277D01*
G01X1481966Y1043267D01*
X1481937Y1043284D01*
G03X1479741Y1043267I-1083J-1944D01*
G03X1479250Y1042882I1114J-1926D01*
G02X1477153Y1041340I-5495J5276D01*
G01X1529668Y1040046D02*
X1528635D01*
X1526297Y1042384D01*
G03X1525990Y1042617I-1038J-1049D01*
G03X1524516I-737J-1277D01*
G01X1524458Y1042583D01*
G02X1522290Y1042617I-1054J1961D01*
G03X1520816I-737J-1277D01*
G01X1520758Y1042583D01*
G02X1518590Y1042617I-1054J1961D01*
G03X1517116I-737J-1277D01*
G01X1517058Y1042583D01*
G02X1514890Y1042617I-1054J1961D01*
G03X1513416I-737J-1277D01*
G01X1513358Y1042583D01*
G02X1511190Y1042617I-1054J1961D01*
G03X1509716I-737J-1277D01*
G01X1509658Y1042583D01*
G02X1507490Y1042617I-1054J1961D01*
G03X1506016I-737J-1277D01*
G02X1503820Y1042600I-1113J1927D01*
G01X1503791Y1042617D01*
X1503773Y1042628D01*
G03X1502316Y1042617I-719J-1288D01*
G02X1500120Y1042600I-1113J1927D01*
G01X1500091Y1042617D01*
X1500073Y1042628D01*
G03X1498616Y1042617I-719J-1288D01*
G02X1496420Y1042600I-1113J1927D01*
G01X1496391Y1042617D01*
X1496373Y1042628D01*
G03X1494916Y1042617I-719J-1288D01*
G02X1492720Y1042600I-1113J1927D01*
G01X1492691Y1042617D01*
X1492673Y1042628D01*
G03X1491216Y1042617I-719J-1288D01*
G02X1489020Y1042600I-1113J1927D01*
G01X1488991Y1042617D01*
X1488973Y1042628D01*
G03X1487516Y1042617I-719J-1288D01*
G02X1485320Y1042600I-1113J1927D01*
G01X1485291Y1042617D01*
X1485273Y1042628D01*
G03X1483816Y1042617I-719J-1288D01*
G02X1482711Y1042319I-1112J1927D01*
G03X1480853Y1041340I0J-2253D01*
G01X1529668Y1036088D02*
X1528902D01*
X1525875Y1039115D01*
X1525252D01*
G02X1525109Y1039119I-9J2225D01*
G02X1524141Y1039413I146J2220D01*
G03X1522667I-737J-1277D01*
G02X1520499Y1039379I-1114J1927D01*
G01X1520441Y1039413D01*
G03X1518967I-737J-1277D01*
G02X1516781Y1039389I-1114J1927D01*
G01X1516740Y1039413D01*
G03X1515266I-737J-1277D01*
G02X1513040I-1113J1927D01*
G03X1511566I-737J-1277D01*
G02X1509340I-1113J1927D01*
G03X1507866I-737J-1277D01*
G02X1505682Y1039389I-1113J1927D01*
G01X1505641Y1039413D01*
G03X1504167I-737J-1277D01*
G02X1501999Y1039379I-1114J1927D01*
G01X1501941Y1039413D01*
G03X1500489Y1039426I-737J-1277D01*
G01X1500466Y1039413D01*
X1500443Y1039399D01*
G02X1498241Y1039413I-1089J1941D01*
G03X1496789Y1039426I-737J-1277D01*
G01X1496766Y1039413D01*
X1496743Y1039399D01*
G02X1494541Y1039413I-1089J1941D01*
G03X1493089Y1039426I-737J-1277D01*
G01X1493066Y1039413D01*
X1493043Y1039399D01*
G02X1490841Y1039413I-1089J1941D01*
G03X1489389Y1039426I-737J-1277D01*
G01X1489366Y1039413D01*
X1489343Y1039399D01*
G02X1487141Y1039413I-1089J1941D01*
G03X1485689Y1039426I-737J-1277D01*
G01X1485666Y1039413D01*
X1484100Y1038510D01*
G02X1482704Y1038136I-1397J2423D01*
G01X1529668Y1047114D02*
X1528569D01*
X1528278Y1046823D01*
X1527298D01*
G03X1525990Y1046472I0J-2614D01*
G02X1524516I-737J1277D01*
G01X1524458Y1046506D01*
G03X1522290Y1046472I-1053J-1962D01*
G02X1520816I-737J1277D01*
G01X1520758Y1046506D01*
G03X1518590Y1046472I-1053J-1962D01*
G02X1517116I-737J1277D01*
G01X1517058Y1046506D01*
G03X1514890Y1046472I-1053J-1962D01*
G02X1513416I-737J1277D01*
G01X1513358Y1046506D01*
G03X1511190Y1046472I-1053J-1962D01*
G02X1509716I-737J1277D01*
G01X1509658Y1046506D01*
G03X1507490Y1046472I-1053J-1962D01*
G01X1507491Y1046471D01*
X1507468Y1046458D01*
G02X1506016Y1046471I-715J1290D01*
G03X1503814Y1046485I-1113J-1927D01*
G01X1503791Y1046471D01*
X1503768Y1046458D01*
G02X1502316Y1046471I-715J1290D01*
G03X1500114Y1046485I-1113J-1927D01*
G01X1500091Y1046471D01*
X1500068Y1046458D01*
G02X1498616Y1046471I-715J1290D01*
G03X1496414Y1046485I-1113J-1927D01*
G01X1496391Y1046471D01*
X1496368Y1046458D01*
G02X1494916Y1046471I-715J1290D01*
G03X1492714Y1046485I-1113J-1927D01*
G01X1492691Y1046471D01*
X1492668Y1046458D01*
G02X1491216Y1046471I-715J1290D01*
G03X1489014Y1046485I-1113J-1927D01*
G01X1488991Y1046471D01*
X1488968Y1046458D01*
G02X1487516Y1046471I-715J1290D01*
G01X1487475Y1046495D01*
G03X1485291Y1046471I-1071J-1951D01*
G02X1483079Y1047748I-737J1277D01*
G03X1481991Y1049661I-2226J0D01*
G01X1481967Y1049675D01*
G03X1479799Y1049709I-1114J-1927D01*
G01X1479741Y1049675D01*
X1479622Y1049607D01*
X1477153Y1047749D01*
G01X1529668Y1045140D02*
X1528522D01*
X1527841Y1045821D01*
G03X1526367I-737J-1277D01*
G02X1524199Y1045787I-1115J1928D01*
G01X1524141Y1045821D01*
G03X1522667I-737J-1277D01*
G02X1520499Y1045787I-1115J1928D01*
G01X1520441Y1045821D01*
G03X1518967I-737J-1277D01*
G02X1516799Y1045787I-1115J1928D01*
G01X1516741Y1045821D01*
G03X1515267I-737J-1277D01*
G02X1513099Y1045787I-1115J1928D01*
G01X1513041Y1045821D01*
G03X1511567I-737J-1277D01*
G02X1509399Y1045787I-1115J1928D01*
G01X1509341Y1045821D01*
G03X1507867I-737J-1277D01*
G01X1507843Y1045808D01*
G02X1505641Y1045822I-1089J1941D01*
G03X1504189Y1045835I-737J-1278D01*
G01X1504166Y1045822D01*
X1504143Y1045808D01*
G02X1501941Y1045822I-1089J1941D01*
G03X1500489Y1045835I-737J-1278D01*
G01X1500466Y1045822D01*
X1500443Y1045808D01*
G02X1498241Y1045822I-1089J1941D01*
G03X1496789Y1045835I-737J-1278D01*
G01X1496766Y1045822D01*
X1496743Y1045808D01*
G02X1494541Y1045822I-1089J1941D01*
G03X1493089Y1045835I-737J-1278D01*
G01X1493066Y1045822D01*
X1493043Y1045808D01*
G02X1490841Y1045822I-1089J1941D01*
G03X1489389Y1045835I-737J-1278D01*
G01X1489366Y1045822D01*
X1489343Y1045808D01*
G02X1487141Y1045822I-1089J1941D01*
G03X1485689Y1045835I-737J-1278D01*
G01X1485666Y1045822D01*
X1485643Y1045808D01*
G02X1483441Y1045822I-1089J1941D01*
G01X1483134Y1045999D01*
G02X1480855Y1047747I5460J9478D01*
G01X1480853Y1047749D01*
G01X1530868Y1030859D02*
X1530776D01*
X1530540Y1030623D01*
X1528871D01*
X1528498Y1030250D01*
X1527103D01*
G02X1526366Y1030450I5J1475D01*
G01X1526310Y1030482D01*
G02X1525628Y1031726I794J1244D01*
G01Y1031788D01*
G03X1524517Y1033654I-2225J-61D01*
G03X1522349Y1033688I-1114J-1927D01*
G01X1522291Y1033654D01*
G02X1520817I-737J1277D01*
G03X1518631Y1033678I-1114J-1927D01*
G01X1518590Y1033654D01*
G02X1517116I-737J1277D01*
G03X1514890I-1113J-1927D01*
G02X1513416I-737J1277D01*
G03X1511190I-1113J-1927D01*
G02X1509716I-737J1277D01*
G03X1507490I-1113J-1927D01*
G02X1506016I-737J1277D01*
G01X1505958Y1033688D01*
G03X1503790Y1033654I-1054J-1961D01*
G02X1502316I-737J1277D01*
G01X1502258Y1033688D01*
G03X1500090Y1033654I-1054J-1961D01*
G02X1498616I-737J1277D01*
G03X1496432Y1033678I-1113J-1927D01*
G01X1496391Y1033654D01*
G02X1494917I-737J1277D01*
G01X1494876Y1033678D01*
G03X1492690Y1033654I-1072J-1951D01*
G02X1491216I-737J1277D01*
G01X1491158Y1033688D01*
G03X1488991Y1033655I-1054J-1961D01*
G01X1488990Y1033654D01*
G02X1487516I-737J1277D01*
G01X1487512Y1033656D01*
X1487060Y1033920D01*
X1486200Y1034121D01*
X1484776D01*
X1484553Y1034344D01*
Y1034931D01*
G01X1530868Y1029639D02*
X1530776D01*
X1530541Y1029874D01*
X1529182D01*
X1528809Y1029501D01*
X1527103D01*
G02X1525990Y1029799I-1J2225D01*
G02X1525907Y1029849I1107J1931D01*
G02X1524877Y1031688I1195J1877D01*
G01X1524878Y1031727D01*
G03X1524175Y1032984I-1475J0D01*
G01X1524140Y1033004D01*
G03X1522666I-737J-1277D01*
G01X1522608Y1032970D01*
G02X1520440Y1033004I-1054J1961D01*
G03X1518966I-737J-1277D01*
G02X1516740I-1113J1927D01*
G03X1515266I-737J-1277D01*
G01X1515265Y1033003D01*
G02X1513040Y1033004I-1112J1928D01*
G01X1513041Y1033005D01*
G03X1511564I-738J-1278D01*
G01X1511565Y1033003D01*
G02X1509340Y1033004I-1112J1928D01*
G03X1507866I-737J-1277D01*
G02X1505682Y1032980I-1113J1927D01*
G01X1505641Y1033004D01*
G03X1504167I-737J-1277D01*
G02X1501999Y1032970I-1114J1927D01*
G01X1501941Y1033004D01*
G03X1500467I-737J-1277D01*
G02X1498281Y1032980I-1114J1927D01*
G01X1498240Y1033004D01*
G03X1496766I-737J-1277D01*
G01X1496725Y1032980D01*
G02X1494541Y1033004I-1071J1951D01*
G03X1493067I-737J-1277D01*
G02X1490899Y1032970I-1114J1927D01*
G01X1490841Y1033004D01*
G03X1489395Y1033019I-736J-1277D01*
G01X1489367Y1033004D01*
G02X1487199Y1032970I-1114J1927D01*
G01X1486779Y1033216D01*
X1486113Y1033372D01*
X1484643D01*
X1484565Y1033387D01*
X1484369Y1033468D01*
G02X1483816Y1033654I184J1463D01*
G01X1483810Y1033657D01*
X1483781Y1033674D01*
G02X1483096Y1034706I773J1256D01*
G01X1482871Y1034931D01*
X1480853D01*
G01X1529668Y1065454D02*
X1528881D01*
X1527571Y1064579D01*
X1526982Y1063157D01*
X1526616Y1062791D01*
X1525253D01*
G03X1524141Y1062493I1J-2227D01*
G02X1522667I-737J1277D01*
G03X1520499Y1062527I-1115J-1928D01*
G01X1520441Y1062493D01*
G02X1518967I-737J1277D01*
G03X1516799Y1062527I-1115J-1928D01*
G01X1516741Y1062493D01*
G02X1515267I-737J1277D01*
G03X1513099Y1062527I-1115J-1928D01*
G01X1513041Y1062493D01*
G02X1511567I-737J1277D01*
G03X1509399Y1062527I-1115J-1928D01*
G01X1509341Y1062493D01*
G02X1507867I-737J1277D01*
G03X1505699Y1062527I-1115J-1928D01*
G01X1505641Y1062493D01*
G02X1504167I-737J1277D01*
G03X1501981Y1062517I-1114J-1928D01*
G01X1501940Y1062493D01*
G02X1500466I-737J1277D01*
G01X1500425Y1062517D01*
G03X1498241Y1062493I-1071J-1952D01*
G02X1496767I-737J1277D01*
G03X1494599Y1062527I-1115J-1928D01*
G01X1494541Y1062493D01*
G02X1493067I-737J1277D01*
G03X1490899Y1062527I-1115J-1928D01*
G01X1490841Y1062493D01*
G02X1489367I-737J1277D01*
G03X1487199Y1062527I-1115J-1928D01*
G01X1487141Y1062493D01*
G02X1485667I-737J1277D01*
G03X1483499Y1062527I-1115J-1928D01*
G01X1483441Y1062493D01*
G02X1481967I-737J1277D01*
G03X1479799Y1062527I-1115J-1928D01*
G01X1479741Y1062493D01*
X1479627Y1062428D01*
X1477153Y1060565D01*
G01X1529668Y1063478D02*
X1528625D01*
X1527189Y1062042D01*
X1525254D01*
G03X1524516Y1061842I4J-1477D01*
G01X1524458Y1061808D01*
G02X1522290Y1061842I-1053J1962D01*
G03X1520816I-737J-1277D01*
G01X1520758Y1061808D01*
G02X1518590Y1061842I-1053J1962D01*
G03X1517116I-737J-1277D01*
G01X1517058Y1061808D01*
G02X1514890Y1061842I-1053J1962D01*
G03X1513416I-737J-1277D01*
G01X1513358Y1061808D01*
G02X1511190Y1061842I-1053J1962D01*
G03X1509716I-737J-1277D01*
G01X1509658Y1061808D01*
G02X1507490Y1061842I-1053J1962D01*
G03X1506016I-737J-1277D01*
G01X1505958Y1061808D01*
G02X1503790Y1061842I-1053J1962D01*
G03X1502316I-737J-1277D01*
G02X1500132Y1061818I-1113J1928D01*
G01X1500091Y1061842D01*
G03X1498617I-737J-1277D01*
G01X1498576Y1061818D01*
G02X1496390Y1061842I-1072J1952D01*
G03X1494916I-737J-1277D01*
G01X1494858Y1061808D01*
G02X1492690Y1061842I-1053J1962D01*
G03X1491216I-737J-1277D01*
G01X1491158Y1061808D01*
G02X1488990Y1061842I-1053J1962D01*
G03X1487516I-737J-1277D01*
G01X1487458Y1061808D01*
G02X1485290Y1061842I-1053J1962D01*
G03X1483816I-737J-1277D01*
G01X1483701Y1061775D01*
X1480853Y1060565D01*
G01X1529668Y1059434D02*
X1528056D01*
X1527393Y1058974D01*
G03X1527046Y1058927I-2J-1288D01*
G03X1526362Y1058638I786J-2815D01*
G02X1524178Y1058614I-1113J1927D01*
G01X1524137Y1058638D01*
G03X1522663I-737J-1277D01*
G02X1520479Y1058614I-1113J1927D01*
G01X1520438Y1058638D01*
G03X1518964I-737J-1277D01*
G02X1516780Y1058614I-1113J1927D01*
G01X1516739Y1058638D01*
G03X1515265I-737J-1277D01*
G01X1515224Y1058614D01*
G02X1513040Y1058638I-1071J1951D01*
G03X1511566I-737J-1277D01*
G02X1509382Y1058614I-1113J1927D01*
G01X1509341Y1058638D01*
G03X1507867I-737J-1277D01*
G02X1505699Y1058604I-1114J1927D01*
G01X1505641Y1058638D01*
G03X1504167I-737J-1277D01*
G02X1501999Y1058604I-1114J1927D01*
G01X1501941Y1058638D01*
G03X1500467I-737J-1277D01*
G02X1498241I-1113J1927D01*
G03X1496767I-737J-1277D01*
G02X1494599Y1058604I-1114J1927D01*
G01X1494541Y1058638D01*
G03X1493067I-737J-1277D01*
G02X1490899Y1058604I-1114J1927D01*
G01X1490841Y1058638D01*
G03X1489367I-737J-1277D01*
G02X1487199Y1058604I-1114J1927D01*
G01X1487141Y1058638D01*
G03X1485667I-737J-1277D01*
G01X1485554Y1058572D01*
X1482704Y1057361D01*
G01X1529668Y1049098D02*
X1528692D01*
G03X1528478Y1049066I-1J-722D01*
G01X1528218Y1048985D01*
G03X1527888Y1048870I1689J-5377D01*
G02X1526173Y1048927I-789J2081D01*
G03X1524325I-924J-2023D01*
G02X1522329Y1049001I-924J2025D01*
G01X1522288Y1049025D01*
G03X1520814I-737J-1276D01*
G02X1518630Y1049001I-1113J1927D01*
G01X1518589Y1049025D01*
G03X1517115I-737J-1276D01*
G02X1514931Y1049001I-1113J1927D01*
G01X1514890Y1049025D01*
G03X1513416I-737J-1276D01*
G02X1511190I-1113J1927D01*
G03X1509716I-737J-1276D01*
G01X1509658Y1048991D01*
G02X1507490Y1049025I-1054J1961D01*
G01X1507468Y1049039D01*
G03X1506016Y1049026I-715J-1290D01*
G02X1503814Y1049012I-1113J1926D01*
G01X1503791Y1049026D01*
X1503768Y1049039D01*
G03X1502316Y1049026I-715J-1290D01*
G02X1500114Y1049012I-1113J1926D01*
G01X1500091Y1049026D01*
X1500068Y1049039D01*
G03X1498616Y1049026I-715J-1290D01*
G02X1496414Y1049012I-1113J1926D01*
G01X1496391Y1049026D01*
X1496368Y1049039D01*
G03X1494916Y1049026I-715J-1290D01*
G02X1492714Y1049012I-1113J1926D01*
G01X1492691Y1049026D01*
X1492668Y1049039D01*
G03X1491216Y1049026I-715J-1290D01*
G02X1489014Y1049012I-1113J1926D01*
G01X1488991Y1049026D01*
X1488968Y1049039D01*
G03X1487516Y1049026I-715J-1290D01*
G02X1485314Y1049012I-1113J1926D01*
G01X1485121Y1049121D01*
G02X1482704Y1050952I5572J9866D01*
G01X1529668Y1056243D02*
X1529576D01*
X1529341Y1056478D01*
X1528362D01*
X1527373Y1055488D01*
X1526175Y1055333D01*
X1525961Y1055451D01*
G03X1524511Y1055435I-711J-1294D01*
G02X1522347Y1055400I-1113J1926D01*
G01X1522242Y1055461D01*
G03X1520815Y1055434I-689J-1304D01*
G02X1518647Y1055400I-1114J1927D01*
G01X1518589Y1055434D01*
X1518556Y1055453D01*
G03X1517116Y1055434I-703J-1296D01*
G02X1514948Y1055400I-1114J1927D01*
G01X1514890Y1055434D01*
G03X1513416I-737J-1277D01*
G02X1511190I-1113J1927D01*
G03X1509716I-737J-1277D01*
G01X1509658Y1055400D01*
G02X1507490Y1055434I-1054J1961D01*
G03X1506016I-737J-1277D01*
G01X1505958Y1055400D01*
G02X1503790Y1055434I-1054J1961D01*
G03X1502316I-737J-1277D01*
G01X1502258Y1055400D01*
G02X1500090Y1055434I-1054J1961D01*
G03X1498616I-737J-1277D01*
G01X1498575Y1055410D01*
G02X1496391Y1055434I-1071J1951D01*
G03X1494917I-737J-1277D01*
G01X1494876Y1055410D01*
G02X1492690Y1055434I-1072J1951D01*
G03X1491216I-737J-1277D01*
G01X1491158Y1055400D01*
G02X1488990Y1055434I-1054J1961D01*
G03X1487516I-737J-1277D01*
G01X1487458Y1055400D01*
G02X1485290Y1055434I-1054J1961D01*
G03X1483816I-737J-1277D01*
G01X1483787Y1055417D01*
Y1055418D01*
G02X1481787Y1055335I-1082J1943D01*
G01X1481765D01*
X1481592Y1055434D01*
Y1055435D01*
G03X1480004Y1055363I-738J-1276D01*
G01X1479171Y1054774D01*
X1479138Y1054766D01*
X1478278Y1054157D01*
X1477153D01*
G01X1529668Y1054257D02*
X1529576D01*
X1529340Y1054021D01*
X1528265D01*
X1527422Y1053178D01*
X1527098D01*
G03X1525986Y1052880I0J-2224D01*
G02X1524512I-737J1277D01*
G03X1522330Y1052904I-1112J-1928D01*
G01X1522242Y1052853D01*
G02X1520815Y1052880I-689J1304D01*
G03X1518647Y1052914I-1115J-1928D01*
G01X1518589Y1052880D01*
X1518556Y1052861D01*
G02X1517116Y1052880I-703J1296D01*
G03X1514948Y1052914I-1115J-1928D01*
G01X1514890Y1052880D01*
G02X1513416I-737J1277D01*
G03X1511190I-1113J-1928D01*
G02X1509716I-737J1277D01*
G01X1509658Y1052914D01*
G03X1507490Y1052880I-1053J-1962D01*
G02X1506016I-737J1277D01*
G01X1505958Y1052914D01*
G03X1503790Y1052880I-1054J-1961D01*
G02X1502316I-737J1277D01*
G01X1502258Y1052914D01*
G03X1500090Y1052880I-1054J-1961D01*
G02X1498616I-737J1277D01*
G03X1496432Y1052904I-1113J-1927D01*
G01X1496391Y1052880D01*
G02X1494917I-737J1277D01*
G01X1494876Y1052904D01*
G03X1492690Y1052880I-1072J-1951D01*
G02X1491216I-737J1277D01*
G01X1491158Y1052914D01*
G03X1488990Y1052880I-1054J-1961D01*
G02X1487516I-737J1277D01*
G01X1487379Y1052954D01*
X1487338Y1052981D01*
X1487143Y1053111D01*
X1485960Y1053347D01*
X1484776D01*
X1484553Y1053570D01*
Y1054157D01*
G01X1529668Y1053037D02*
X1529576D01*
X1529341Y1053272D01*
X1528576D01*
X1527733Y1052429D01*
X1527098D01*
G03X1526360Y1052231I0J-1474D01*
G02X1524138I-1111J1926D01*
G03X1522699Y1052251I-737J-1279D01*
G01X1522665Y1052232D01*
X1522605Y1052197D01*
G02X1520440Y1052231I-1052J1960D01*
G03X1519013Y1052259I-739J-1279D01*
G01X1518965Y1052232D01*
X1518923Y1052207D01*
G02X1516741Y1052231I-1070J1950D01*
G03X1515314Y1052259I-739J-1279D01*
G01X1515267Y1052232D01*
G02X1513042Y1052231I-1113J1925D01*
G03X1511564I-739J-1279D01*
G02X1509339Y1052232I-1112J1926D01*
G01X1509292Y1052259D01*
G03X1507865Y1052231I-688J-1307D01*
G02X1505642I-1112J1926D01*
G01X1505638Y1052233D01*
X1505594Y1052258D01*
G03X1504165Y1052231I-690J-1305D01*
G02X1501939Y1052232I-1112J1926D01*
G01X1501892Y1052260D01*
G03X1500465Y1052231I-687J-1307D01*
G02X1498241I-1112J1926D01*
G03X1496801Y1052251I-738J-1278D01*
G01X1496768Y1052232D01*
G02X1494540I-1114J1925D01*
G01X1494507Y1052252D01*
G03X1493065Y1052231I-702J-1299D01*
G02X1490839Y1052232I-1112J1926D01*
G01X1490792Y1052260D01*
G03X1489365Y1052231I-687J-1307D01*
G02X1487152Y1052225I-1112J1926D01*
G01X1486994Y1052310D01*
X1486851Y1052405D01*
X1485886Y1052598D01*
X1484643D01*
X1484565Y1052613D01*
X1484369Y1052694D01*
G02X1483816Y1052880I184J1463D01*
G01X1483810Y1052883D01*
X1483781Y1052900D01*
G02X1483096Y1053932I773J1256D01*
G01X1482871Y1054157D01*
X1480853D01*
G01X1529668Y1083410D02*
X1528965D01*
X1528109Y1082554D01*
Y1081966D01*
X1523709Y1077566D01*
X1521553D01*
G02X1520440Y1077864I0J2226D01*
G03X1518966I-737J-1277D01*
G02X1516740I-1113J1927D01*
G03X1515266I-737J-1277D01*
G02X1513040I-1113J1927D01*
G03X1511566I-737J-1277D01*
G02X1509382Y1077840I-1113J1927D01*
G01X1509341Y1077864D01*
G03X1507867I-737J-1277D01*
G02X1505699Y1077830I-1114J1927D01*
G01X1505641Y1077864D01*
G03X1504167I-737J-1277D01*
G02X1501999Y1077830I-1114J1927D01*
G01X1501941Y1077864D01*
G03X1500467I-737J-1277D01*
G02X1498241I-1113J1927D01*
G03X1496767I-737J-1277D01*
G02X1494599Y1077830I-1114J1927D01*
G01X1494541Y1077864D01*
G03X1493067I-737J-1277D01*
G02X1490899Y1077830I-1114J1927D01*
G01X1490841Y1077864D01*
G03X1489389Y1077878I-738J-1277D01*
G01X1489366Y1077864D01*
X1489343Y1077851D01*
G02X1487141Y1077864I-1090J1940D01*
G03X1485689Y1077878I-738J-1277D01*
G01X1485666Y1077864D01*
X1484100Y1076961D01*
G02X1482704Y1076587I-1397J2423D01*
G01X1529668Y1070981D02*
X1529043D01*
X1525282Y1067220D01*
X1524526D01*
X1522804Y1065498D01*
X1521553D01*
G02X1520758Y1065731I1J1476D01*
G03X1518590Y1065697I-1054J-1961D01*
G02X1517116I-737J1277D01*
G01X1517058Y1065731D01*
G03X1514890Y1065697I-1054J-1961D01*
G02X1513416I-737J1277D01*
G01X1513358Y1065731D01*
G03X1511190Y1065697I-1054J-1961D01*
G02X1509716I-737J1277D01*
G01X1509658Y1065731D01*
G03X1507490Y1065697I-1054J-1961D01*
G02X1506016I-737J1277D01*
G01X1505958Y1065731D01*
G03X1503790Y1065697I-1054J-1961D01*
G02X1502316I-737J1277D01*
G03X1500090I-1113J-1927D01*
G02X1498616I-737J1277D01*
G01X1498558Y1065731D01*
G03X1496390Y1065697I-1054J-1961D01*
G02X1494916I-737J1277D01*
G01X1494858Y1065731D01*
G03X1492690Y1065697I-1054J-1961D01*
G02X1491216I-737J1277D01*
G01X1491158Y1065731D01*
G03X1488990Y1065697I-1054J-1961D01*
G02X1487516I-737J1277D01*
G01X1487458Y1065731D01*
G03X1485290Y1065697I-1054J-1961D01*
G02X1483816I-737J1277D01*
G01X1483781Y1065717D01*
G02X1483078Y1066974I772J1257D01*
G01Y1067035D01*
G03X1481967Y1068901I-2225J-61D01*
G03X1479799Y1068935I-1114J-1927D01*
G01X1479741Y1068901D01*
X1479717Y1068887D01*
G03X1478643Y1067233I1136J-1913D01*
G01X1478384Y1066974D01*
X1477153D01*
G01X1529668Y1072966D02*
X1528417D01*
X1525629Y1070178D01*
G02X1522290Y1068251I-2225J0D01*
G03X1520816I-737J-1277D01*
G01X1520758Y1068217D01*
G02X1518590Y1068251I-1054J1961D01*
G03X1517116I-737J-1277D01*
G01X1517058Y1068217D01*
G02X1514890Y1068251I-1054J1961D01*
G03X1513416I-737J-1277D01*
G01X1513358Y1068217D01*
G02X1511190Y1068251I-1054J1961D01*
G01X1511191Y1068252D01*
G03X1509716I-737J-1277D01*
G02X1507506Y1068243I-1113J1926D01*
G01X1507491Y1068252D01*
X1507468Y1068265D01*
G03X1506016Y1068252I-715J-1290D01*
G02X1503814Y1068238I-1113J1926D01*
G01X1503791Y1068252D01*
X1503768Y1068265D01*
G03X1502316Y1068252I-715J-1290D01*
G02X1500114Y1068238I-1113J1926D01*
G01X1500091Y1068252D01*
X1500068Y1068265D01*
G03X1498616Y1068252I-715J-1290D01*
G02X1496414Y1068238I-1113J1926D01*
G01X1496391Y1068252D01*
X1496368Y1068265D01*
G03X1494916Y1068252I-715J-1290D01*
G02X1492714Y1068238I-1113J1926D01*
G01X1492691Y1068252D01*
X1492668Y1068265D01*
G03X1491216Y1068252I-715J-1290D01*
G02X1489014Y1068238I-1113J1926D01*
G01X1488991Y1068252D01*
X1488968Y1068265D01*
G03X1487516Y1068252I-715J-1290D01*
G02X1485314Y1068238I-1113J1926D01*
G01X1485121Y1068347D01*
G02X1482704Y1070178I5572J9866D01*
G01X1529668Y1069020D02*
X1529227D01*
X1526678Y1066471D01*
X1524837D01*
X1523115Y1064749D01*
X1521553D01*
G02X1520441Y1065047I0J2224D01*
G03X1518967I-737J-1277D01*
G02X1516799Y1065013I-1114J1927D01*
G01X1516741Y1065047D01*
G03X1515267I-737J-1277D01*
G02X1513099Y1065013I-1114J1927D01*
G01X1513041Y1065047D01*
G03X1511567I-737J-1277D01*
G02X1509399Y1065013I-1114J1927D01*
G01X1509341Y1065047D01*
G03X1507867I-737J-1277D01*
G02X1505699Y1065013I-1114J1927D01*
G01X1505641Y1065047D01*
G03X1504167I-737J-1277D01*
G02X1501981Y1065023I-1114J1927D01*
G01X1501940Y1065047D01*
G03X1500466I-737J-1277D01*
G02X1498282Y1065023I-1113J1927D01*
G01X1498241Y1065047D01*
G03X1496767I-737J-1277D01*
G02X1494599Y1065013I-1114J1927D01*
G01X1494541Y1065047D01*
G03X1493067I-737J-1277D01*
G02X1490899Y1065013I-1114J1927D01*
G01X1490841Y1065047D01*
G03X1489367I-737J-1277D01*
G02X1487199Y1065013I-1114J1927D01*
G01X1487141Y1065047D01*
G03X1485667I-737J-1277D01*
G02X1483499Y1065013I-1114J1927D01*
G01X1483441Y1065047D01*
X1483417Y1065061D01*
G02X1482328Y1066974I1136J1913D01*
G03X1481625Y1068231I-1475J0D01*
G01X1481590Y1068251D01*
G03X1480116I-737J-1277D01*
G01X1480081Y1068231D01*
G03X1479396Y1067200I773J-1256D01*
G01X1479622Y1066974D01*
X1480853D01*
G01X1529668Y1078139D02*
X1529576D01*
X1529340Y1077903D01*
X1528005D01*
X1522413Y1072311D01*
G02X1520869Y1072074I-933J934D01*
G01X1520823Y1072100D01*
X1520819Y1072102D01*
G02X1520816Y1072106I1083J815D01*
G01X1520758Y1072140D01*
G03X1518590Y1072106I-1053J-1962D01*
G02X1517116I-737J1277D01*
G01X1517058Y1072140D01*
G03X1514890Y1072106I-1053J-1962D01*
G02X1513416I-737J1277D01*
G01X1513358Y1072140D01*
G03X1511190Y1072106I-1053J-1962D01*
G02X1509716I-737J1277D01*
G01X1509658Y1072140D01*
G03X1507490Y1072106I-1053J-1962D01*
G02X1506016I-737J1277D01*
G01X1505958Y1072140D01*
G03X1503790Y1072106I-1053J-1962D01*
G02X1502316I-737J1277D01*
G01X1502258Y1072140D01*
G03X1500090Y1072106I-1053J-1962D01*
G02X1498616I-737J1277D01*
G03X1496432Y1072130I-1113J-1928D01*
G01X1496391Y1072106D01*
G02X1494917I-737J1277D01*
G01X1494876Y1072130D01*
G03X1492690Y1072106I-1072J-1952D01*
G02X1491216I-737J1277D01*
G01X1491158Y1072140D01*
G03X1488991Y1072107I-1054J-1962D01*
G01X1488990Y1072106D01*
G02X1487516I-737J1277D01*
G01X1486867Y1072480D01*
X1486507Y1072467D01*
X1486506Y1072469D01*
X1485186Y1072481D01*
X1485184D01*
X1484790Y1072560D01*
Y1072559D01*
X1484553Y1072796D01*
Y1073383D01*
G01X1529668Y1081438D02*
X1529576D01*
X1529340Y1081202D01*
X1528516D01*
X1522922Y1075608D01*
X1521550D01*
G03X1520438Y1075310I1J-2226D01*
G02X1518998Y1075291I-737J1277D01*
G01X1518924Y1075334D01*
G03X1516740Y1075310I-1071J-1951D01*
G02X1515266I-737J1277D01*
G03X1513040I-1113J-1927D01*
G02X1511566I-737J1277D01*
G03X1509382Y1075334I-1113J-1927D01*
G01X1509341Y1075310D01*
G02X1507867I-737J1277D01*
G03X1505699Y1075344I-1114J-1927D01*
G01X1505641Y1075310D01*
G02X1504167I-737J1277D01*
G03X1501999Y1075344I-1114J-1927D01*
G01X1501941Y1075310D01*
G02X1500467I-737J1277D01*
G03X1498299Y1075344I-1114J-1927D01*
G01X1498241Y1075310D01*
G02X1496767I-737J1277D01*
G03X1494541I-1113J-1927D01*
G02X1493067I-737J1277D01*
G03X1490899Y1075344I-1114J-1927D01*
G01X1490841Y1075310D01*
G02X1489367I-737J1277D01*
G03X1487199Y1075344I-1114J-1927D01*
G01X1487141Y1075310D01*
G02X1485667I-737J1277D01*
G03X1483499Y1075344I-1114J-1927D01*
G01X1483441Y1075310D01*
G02X1481967I-737J1277D01*
G03X1479799Y1075344I-1114J-1927D01*
G01X1479741Y1075310D01*
X1479738Y1075308D01*
X1479717Y1075296D01*
G03X1479690Y1075279I1172J-1891D01*
G03X1478967Y1074564I1160J-1896D01*
G01X1478829Y1074332D01*
G03X1478714Y1074031I817J-485D01*
G01X1478469Y1073574D01*
X1478278Y1073383D01*
X1477153D01*
G01X1529668Y1076919D02*
X1529576D01*
X1529341Y1077154D01*
X1528316D01*
X1522943Y1071781D01*
G02X1520508Y1071417I-1463J1463D01*
G01X1520452Y1071449D01*
X1520441Y1071455D01*
G03X1518967I-737J-1277D01*
G02X1516799Y1071421I-1115J1928D01*
G01X1516741Y1071455D01*
G03X1515267I-737J-1277D01*
G02X1513099Y1071421I-1115J1928D01*
G01X1513041Y1071455D01*
G03X1511567I-737J-1277D01*
G02X1509399Y1071421I-1115J1928D01*
G01X1509341Y1071455D01*
G03X1507867I-737J-1277D01*
G02X1505699Y1071421I-1115J1928D01*
G01X1505641Y1071455D01*
G03X1504167I-737J-1277D01*
G02X1501999Y1071421I-1115J1928D01*
G01X1501941Y1071455D01*
G03X1500467I-737J-1277D01*
G02X1498281Y1071431I-1114J1928D01*
G01X1498240Y1071455D01*
G03X1496766I-737J-1277D01*
G01X1496725Y1071431D01*
G02X1494541Y1071455I-1071J1952D01*
G03X1493067I-737J-1277D01*
G02X1490899Y1071421I-1115J1928D01*
G01X1490841Y1071455D01*
G03X1489367I-737J-1277D01*
G02X1489364Y1071457I545J821D01*
G02X1487142I-1111J1926D01*
G01X1486679Y1071723D01*
X1486530Y1071718D01*
X1486499D01*
X1485179Y1071731D01*
X1485177D01*
X1485103Y1071732D01*
X1485100Y1071733D01*
X1484643Y1071823D01*
X1484565Y1071839D01*
X1484369Y1071920D01*
G02X1483816Y1072106I184J1463D01*
G01X1483810Y1072109D01*
X1483781Y1072126D01*
G02X1483096Y1073158I773J1256D01*
G01X1482871Y1073383D01*
X1480853D01*
G01X1525949Y1085968D02*
X1525579Y1085598D01*
Y1084341D01*
X1525809Y1083785D01*
Y1082066D01*
X1524512Y1080769D01*
X1519704D01*
G02X1518590Y1081068I1J2228D01*
G03X1517116I-737J-1277D01*
G01X1517058Y1081034D01*
G02X1514890Y1081068I-1053J1962D01*
G03X1513416I-737J-1277D01*
G01X1513358Y1081034D01*
G02X1511190Y1081068I-1053J1962D01*
G03X1509716I-737J-1277D01*
G01X1509658Y1081034D01*
G02X1507490Y1081068I-1053J1962D01*
G03X1506016I-737J-1277D01*
G01X1505958Y1081034D01*
G02X1503790Y1081068I-1054J1961D01*
G03X1502316I-737J-1277D01*
G02X1500132Y1081044I-1113J1927D01*
G01X1500091Y1081068D01*
G03X1498617I-737J-1277D01*
G01X1498576Y1081044D01*
G02X1496390Y1081068I-1072J1951D01*
G03X1494916I-737J-1277D01*
G01X1494858Y1081034D01*
G02X1492690Y1081068I-1054J1961D01*
G03X1491216I-737J-1277D01*
G01X1491158Y1081034D01*
G02X1488990Y1081068I-1054J1961D01*
G03X1487516I-737J-1277D01*
G01X1487458Y1081034D01*
G02X1485290Y1081068I-1054J1961D01*
G03X1483816I-737J-1277D01*
G01X1483758Y1081034D01*
G02X1481590Y1081068I-1054J1961D01*
G03X1480116I-737J-1277D01*
G01X1480081Y1081048D01*
G03X1479396Y1080017I773J-1256D01*
G01X1479622Y1079791D01*
X1480853D01*
G01X1528769Y1089823D02*
X1526840D01*
X1526489Y1089472D01*
Y1088211D01*
X1524719Y1086441D01*
Y1084199D01*
X1525011Y1083494D01*
Y1082503D01*
X1524026Y1081518D01*
X1519705D01*
G02X1518967Y1081719I6J1477D01*
G03X1516799Y1081753I-1115J-1928D01*
G01X1516741Y1081719D01*
G02X1515267I-737J1277D01*
G03X1513099Y1081753I-1115J-1928D01*
G01X1513041Y1081719D01*
G02X1511567I-737J1277D01*
G03X1509399Y1081753I-1115J-1928D01*
G01X1509341Y1081719D01*
G02X1507867I-737J1277D01*
G03X1505720Y1081764I-1114J-1928D01*
G01X1505641Y1081718D01*
G02X1504167I-737J1277D01*
G03X1501981Y1081742I-1114J-1927D01*
G01X1501940Y1081718D01*
G02X1500466I-737J1277D01*
G01X1500425Y1081742D01*
G03X1498241Y1081718I-1071J-1951D01*
G02X1496767I-737J1277D01*
G03X1494599Y1081752I-1114J-1927D01*
G01X1494541Y1081718D01*
G02X1493067I-737J1277D01*
G03X1490899Y1081752I-1114J-1927D01*
G01X1490841Y1081718D01*
G02X1489367I-737J1277D01*
G03X1487199Y1081752I-1114J-1927D01*
G01X1487141Y1081718D01*
G02X1485667I-737J1277D01*
G03X1483499Y1081752I-1114J-1927D01*
G01X1483441Y1081718D01*
G02X1481967I-737J1277D01*
G03X1479799Y1081752I-1114J-1927D01*
G01X1479741Y1081718D01*
X1479717Y1081704D01*
G03X1478643Y1080050I1136J-1913D01*
G01X1478384Y1079791D01*
X1477153D01*
G01X1528769Y1108790D02*
X1527575D01*
X1527102Y1108317D01*
X1525688Y1104904D01*
X1524663Y1103879D01*
X1524078D01*
G03X1522668Y1103498I0J-2798D01*
G02X1520482Y1103474I-1114J1928D01*
G01X1520441Y1103498D01*
G03X1518967I-737J-1277D01*
G01X1518931Y1103478D01*
G03X1518228Y1102221I772J-1257D01*
G01Y1102182D01*
G02X1517116Y1100294I-2225J39D01*
G01X1517081Y1100274D01*
G03X1516378Y1099017I772J-1257D01*
G01Y1098978D01*
G02X1515266Y1097090I-2225J39D01*
G02X1513040I-1113J1927D01*
G03X1511566I-737J-1277D01*
G02X1509340I-1113J1927D01*
G03X1507866I-737J-1277D01*
G02X1505640I-1113J1927D01*
G03X1504166I-737J-1277D01*
G02X1501982Y1097066I-1113J1927D01*
G01X1501941Y1097090D01*
G03X1500467I-737J-1277D01*
G02X1498241I-1113J1927D01*
G03X1496767I-737J-1277D01*
G02X1494541I-1113J1927D01*
G03X1493067I-737J-1277D01*
G02X1490881Y1097066I-1114J1927D01*
G01X1490840Y1097090D01*
G03X1489366I-737J-1277D01*
G01X1489006Y1096879D01*
X1487864Y1096209D01*
G02X1486404Y1095813I-1459J2490D01*
G01X1528658Y1110760D02*
X1527628D01*
X1527009Y1110141D01*
Y1110119D01*
X1525071Y1105436D01*
X1524283Y1104648D01*
X1524151D01*
G03X1522291Y1104149I0J-3717D01*
G02X1520817I-737J1277D01*
G01X1520776Y1104173D01*
G03X1518590Y1104149I-1072J-1952D01*
G03X1517478Y1102294I1113J-1928D01*
G01Y1102221D01*
G02X1516775Y1100964I-1475J0D01*
G01X1516740Y1100944D01*
G03X1515628Y1099056I1113J-1927D01*
G01Y1099017D01*
G02X1514925Y1097760I-1475J0D01*
G01X1514890Y1097740D01*
G02X1513416I-737J1277D01*
G03X1511190I-1113J-1927D01*
G02X1509716I-737J1277D01*
G03X1507490I-1113J-1927D01*
G02X1506016I-737J1277D01*
G03X1503790I-1113J-1927D01*
G02X1502316I-737J1277D01*
G01X1502275Y1097764D01*
G03X1500091Y1097740I-1071J-1951D01*
G02X1498617I-737J1277D01*
G03X1496391I-1113J-1927D01*
G02X1494917I-737J1277D01*
G01X1494876Y1097764D01*
G03X1492690Y1097740I-1072J-1951D01*
G02X1491216I-737J1277D01*
G03X1489032Y1097764I-1113J-1927D01*
G01X1488701Y1097571D01*
X1488342Y1097432D01*
X1487943Y1097519D01*
G02X1487823Y1097563I63J358D01*
G01X1487517Y1097740D01*
G03X1485349Y1097774I-1114J-1927D01*
G01X1484927Y1097528D01*
G03X1482703Y1095813I5460J-9380D01*
G01X1528769Y1095541D02*
X1528050D01*
X1524878Y1092369D01*
Y1089404D01*
G02X1524175Y1088147I-1475J0D01*
G01X1524140Y1088127D01*
G03X1523028Y1086239I1113J-1927D01*
G01Y1086200D01*
G02X1522325Y1084943I-1475J0D01*
G01X1522290Y1084923D01*
G02X1520816I-737J1277D01*
G01X1520758Y1084957D01*
G03X1518590Y1084923I-1054J-1961D01*
G02X1517116I-737J1277D01*
G01X1517058Y1084957D01*
G03X1514890Y1084923I-1054J-1961D01*
G02X1513416I-737J1277D01*
G01X1513358Y1084957D01*
G03X1511190Y1084923I-1054J-1961D01*
G02X1509716I-737J1277D01*
G01X1509658Y1084957D01*
G03X1507490Y1084923I-1054J-1961D01*
G02X1506016I-737J1277D01*
G01X1505958Y1084957D01*
G03X1503790Y1084923I-1053J-1962D01*
G02X1502316I-737J1277D01*
G03X1500090I-1113J-1928D01*
G02X1498616I-737J1277D01*
G01X1498558Y1084957D01*
G03X1496390Y1084923I-1053J-1962D01*
G02X1494916I-737J1277D01*
G01X1494858Y1084957D01*
G03X1492690Y1084923I-1053J-1962D01*
G02X1491216I-737J1277D01*
G01X1491158Y1084957D01*
G03X1488990Y1084923I-1053J-1962D01*
G02X1487516I-737J1277D01*
G01X1487475Y1084947D01*
G03X1485291Y1084923I-1071J-1952D01*
G02X1483817I-737J1277D01*
G01X1483782Y1084943D01*
G02X1483079Y1086200I772J1257D01*
G03X1481991Y1088113I-2226J0D01*
G01X1481967Y1088127D01*
G03X1479799Y1088161I-1114J-1927D01*
G01X1479741Y1088127D01*
X1479717Y1088113D01*
G03X1478643Y1086459I1136J-1913D01*
G01X1478384Y1086200D01*
X1477153D01*
G01X1529359Y1097526D02*
X1528648D01*
X1525742Y1094620D01*
X1525358D01*
X1524977Y1094239D01*
G02X1524481Y1093865I-1575J1573D01*
G03X1523778Y1092608I772J-1257D01*
G01Y1092569D01*
G02X1522666Y1090681I-2225J39D01*
G01X1522631Y1090661D01*
G03X1521928Y1089404I772J-1257D01*
G01Y1089365D01*
G02X1520816Y1087477I-2225J39D01*
G02X1518590I-1113J1927D01*
G03X1517116I-737J-1277D01*
G02X1514890I-1113J1927D01*
G03X1513416I-737J-1277D01*
G02X1511190I-1113J1927D01*
G03X1509716I-737J-1277D01*
G01X1509658Y1087443D01*
G02X1507490Y1087477I-1054J1961D01*
G03X1506016I-737J-1277D01*
G01X1505958Y1087443D01*
G02X1503790Y1087477I-1054J1961D01*
G03X1502316I-737J-1277D01*
G01X1502258Y1087443D01*
G02X1500090Y1087477I-1054J1961D01*
G03X1498616I-737J-1277D01*
G02X1496390I-1113J1927D01*
G03X1494916I-737J-1277D01*
G01X1494858Y1087443D01*
G02X1492690Y1087477I-1054J1961D01*
G03X1491216I-737J-1277D01*
G01X1491158Y1087443D01*
G02X1488990Y1087477I-1054J1961D01*
G03X1487516I-737J-1277D01*
G01X1487475Y1087453D01*
G02X1485291Y1087477I-1071J1951D01*
G02X1484990Y1087685I1110J1929D01*
G01X1482704Y1089404D01*
G01X1528769Y1093545D02*
X1528085D01*
X1525628Y1091088D01*
Y1089365D01*
G02X1524516Y1087477I-2225J39D01*
G01X1524481Y1087457D01*
G03X1523778Y1086200I772J-1257D01*
G01Y1086139D01*
G02X1522667Y1084273I-2225J61D01*
G02X1520499Y1084239I-1114J1927D01*
G01X1520441Y1084273D01*
G03X1518967I-737J-1277D01*
G02X1516799Y1084239I-1114J1927D01*
G01X1516741Y1084273D01*
G03X1515267I-737J-1277D01*
G02X1513099Y1084239I-1114J1927D01*
G01X1513041Y1084273D01*
G03X1511567I-737J-1277D01*
G02X1509399Y1084239I-1114J1927D01*
G01X1509341Y1084273D01*
G03X1507867I-737J-1277D01*
G02X1505663Y1084259I-1114J1927D01*
G01X1505641Y1084272D01*
G03X1504167I-737J-1277D01*
G02X1501981Y1084248I-1114J1928D01*
G01X1501940Y1084272D01*
G03X1500466I-737J-1277D01*
G02X1498282Y1084248I-1113J1928D01*
G01X1498241Y1084272D01*
G03X1496767I-737J-1277D01*
G02X1494599Y1084238I-1115J1928D01*
G01X1494541Y1084272D01*
G03X1493067I-737J-1277D01*
G02X1490899Y1084238I-1115J1928D01*
G01X1490841Y1084272D01*
G03X1489367I-737J-1277D01*
G02X1487199Y1084238I-1115J1928D01*
G01X1487141Y1084272D01*
G03X1485667I-737J-1277D01*
G02X1483441I-1113J1928D01*
G02X1482328Y1086170I1113J1928D01*
G01Y1086200D01*
G03X1481625Y1087457I-1475J0D01*
G01X1481590Y1087477D01*
G03X1480116I-737J-1277D01*
G01X1480081Y1087457D01*
G03X1479396Y1086426I773J-1256D01*
G01X1479622Y1086200D01*
X1480853D01*
G01X1528769Y1102700D02*
X1528677D01*
X1528441Y1102464D01*
X1527739D01*
X1527084Y1101809D01*
X1526708Y1100906D01*
X1523841Y1098039D01*
X1523402D01*
G03X1521178Y1095886I1J-2226D01*
G01Y1095813D01*
G02X1520475Y1094556I-1475J0D01*
G01X1520440Y1094536D01*
G03X1519328Y1092681I1113J-1928D01*
G01Y1092608D01*
G02X1518625Y1091351I-1475J0D01*
G01X1518590Y1091331D01*
G02X1517116I-737J1277D01*
G03X1514890I-1113J-1927D01*
G02X1513416I-737J1277D01*
G01X1513375Y1091355D01*
G03X1511189Y1091331I-1072J-1951D01*
G02X1509749Y1091312I-737J1277D01*
G01X1509716Y1091331D01*
X1509658Y1091365D01*
G03X1507490Y1091331I-1054J-1961D01*
G02X1506016I-737J1277D01*
G01X1505958Y1091365D01*
G03X1503790Y1091331I-1054J-1961D01*
G02X1502316I-737J1277D01*
G01X1502258Y1091365D01*
G03X1500090Y1091331I-1054J-1961D01*
G02X1498616I-737J1277D01*
G03X1496390I-1113J-1927D01*
G02X1494916I-737J1277D01*
G01X1494875Y1091355D01*
G03X1492691Y1091331I-1071J-1951D01*
G02X1491217I-737J1277D01*
G03X1488992Y1091332I-1113J-1927D01*
G01X1488993Y1091330D01*
X1488992D01*
G02X1488979Y1091323I-706J1295D01*
G01X1488912Y1091287D01*
X1488682Y1091183D01*
G02X1487854Y1091174I-424J937D01*
G01X1487674Y1091251D01*
G02X1487519Y1091328I578J1358D01*
G01X1487518Y1091330D01*
X1487350Y1091420D01*
X1487347Y1091422D01*
X1487310Y1091442D01*
X1487309D01*
X1486705Y1091692D01*
X1485247D01*
X1484790Y1091784D01*
X1484553Y1092021D01*
Y1092608D01*
G01X1528769Y1106767D02*
X1528677D01*
X1528441Y1106531D01*
X1527884D01*
X1527244Y1105891D01*
X1526026Y1103617D01*
X1525695Y1102818D01*
X1524899Y1101629D01*
X1524440Y1101171D01*
G02X1524290Y1101042I-1033J1050D01*
G01X1524288D01*
G02X1522666Y1100944I-885J1179D01*
G03X1519328Y1099056I-1113J-1927D01*
G01Y1099017D01*
G02X1518625Y1097760I-1475J0D01*
G01X1518590Y1097740D01*
G03X1517478Y1095852I1113J-1927D01*
G01Y1095813D01*
G02X1515266Y1094536I-1475J0D01*
G03X1513040I-1113J-1928D01*
G02X1511566I-737J1277D01*
G03X1509398Y1094570I-1115J-1928D01*
G01X1509340Y1094536D01*
G02X1507866I-737J1277D01*
G03X1505640I-1113J-1928D01*
G02X1504166I-737J1277D01*
G03X1501982Y1094560I-1113J-1928D01*
G01X1501941Y1094536D01*
G02X1500467I-737J1277D01*
G03X1498299Y1094570I-1115J-1928D01*
G01X1498241Y1094536D01*
G02X1496767I-737J1277D01*
G03X1494599Y1094570I-1115J-1928D01*
G01X1494541Y1094536D01*
G02X1493067I-737J1277D01*
G01X1493026Y1094560D01*
G03X1490840Y1094536I-1072J-1952D01*
G02X1489366I-737J1277D01*
G01X1489325Y1094560D01*
G03X1487141Y1094536I-1071J-1952D01*
G02X1485667I-737J1277D01*
G03X1483499Y1094570I-1115J-1928D01*
G01X1483441Y1094536D01*
G02X1481967I-737J1277D01*
G03X1479799Y1094570I-1115J-1928D01*
G01X1479741Y1094536D01*
G03X1477153Y1092608I7429J-12673D01*
G01X1528769Y1101480D02*
X1528677D01*
X1528442Y1101715D01*
X1528050D01*
X1527719Y1101384D01*
X1527343Y1100481D01*
X1524152Y1097290D01*
X1523402D01*
G03X1522664Y1097092I1J-1477D01*
G03X1522631Y1097070I802J-1238D01*
G03X1521928Y1095813I772J-1257D01*
G01Y1095740D01*
G02X1520816Y1093885I-2225J73D01*
G01X1520781Y1093865D01*
G03X1520078Y1092608I772J-1257D01*
G01Y1092569D01*
G02X1518966Y1090681I-2225J39D01*
G02X1516740I-1113J1927D01*
G03X1515266I-737J-1277D01*
G02X1513040I-1113J1927D01*
G03X1511566I-737J-1277D01*
G02X1509398Y1090647I-1114J1927D01*
G01X1509340Y1090681D01*
X1509307Y1090700D01*
G03X1507867Y1090681I-703J-1296D01*
G02X1505699Y1090647I-1114J1927D01*
G01X1505641Y1090681D01*
G03X1504167I-737J-1277D01*
G02X1501999Y1090647I-1114J1927D01*
G01X1501941Y1090681D01*
G03X1500467I-737J-1277D01*
G02X1498281Y1090657I-1114J1927D01*
G01X1498240Y1090681D01*
G03X1496766I-737J-1277D01*
G02X1494582Y1090657I-1113J1927D01*
G01X1494541Y1090681D01*
G03X1493067I-737J-1277D01*
G02X1490841I-1113J1927D01*
G03X1489367I-737J-1277D01*
G02X1489172Y1090581I-1112J1928D01*
G01X1489170D01*
X1488991Y1090500D01*
G02X1487560Y1090485I-733J1620D01*
G01X1487379Y1090562D01*
G02X1487145Y1090679I876J2045D01*
G01X1487122Y1090692D01*
X1486994Y1090760D01*
X1486991Y1090762D01*
X1486556Y1090943D01*
X1485172D01*
X1484643Y1091049D01*
Y1091048D01*
X1484565Y1091064D01*
X1484369Y1091145D01*
G02X1483816Y1091331I184J1463D01*
G01X1483810Y1091334D01*
X1483781Y1091351D01*
G02X1483096Y1092383I773J1256D01*
G01X1482871Y1092608D01*
X1480853D01*
G01X1527011Y1112407D02*
X1525989Y1111385D01*
Y1109812D01*
X1524831Y1107016D01*
X1524518Y1106703D01*
G02X1522332Y1106679I-1114J1927D01*
G01X1522291Y1106703D01*
G03X1520817I-737J-1277D01*
G02X1518631Y1106679I-1114J1927D01*
G01X1518590Y1106703D01*
G03X1517116I-737J-1277D01*
G01X1517081Y1106683D01*
G03X1516378Y1105426I772J-1257D01*
G01Y1105353D01*
G02X1515266Y1103498I-2225J73D01*
G01X1515231Y1103478D01*
G03X1514528Y1102221I772J-1257D01*
G01Y1102182D01*
G02X1513416Y1100294I-2225J39D01*
G02X1511190I-1113J1927D01*
G03X1509716I-737J-1277D01*
G02X1507548Y1100260I-1114J1927D01*
G01X1507490Y1100294D01*
G03X1506016I-737J-1277D01*
G01X1505958Y1100260D01*
G02X1503790Y1100294I-1054J1961D01*
G03X1502316I-737J-1277D01*
G01X1502275Y1100270D01*
G02X1500091Y1100294I-1071J1951D01*
G03X1498617I-737J-1277D01*
G02X1496449Y1100260I-1114J1927D01*
G01X1496391Y1100294D01*
G03X1494917I-737J-1277D01*
G01X1494876Y1100270D01*
G02X1492920Y1100178I-1072J1951D01*
G01X1492569Y1100084D01*
X1491953Y1099017D01*
G01X1536845Y858190D02*
X1535717Y859318D01*
Y861461D01*
X1534454Y862724D01*
X1534067Y862722D01*
G02X1533333Y862920I4J1475D01*
G01X1533275Y862954D01*
G03X1531107Y862920I-1054J-1961D01*
G02X1529633I-737J1277D01*
G01X1529575Y862954D01*
G03X1527407Y862920I-1054J-1961D01*
G02X1525933I-737J1277D01*
G02X1525195Y864198I738J1278D01*
G01Y864199D01*
G03X1521861Y866124I-2223J0D01*
G01X1521858Y866123D01*
G03X1520745Y864197I1111J-1927D01*
G02X1520008Y862921I-1473J0D01*
G01X1520007Y862920D01*
G02X1518533I-737J1277D01*
G01X1518475Y862954D01*
G03X1516307Y862920I-1054J-1961D01*
G02X1514833I-737J1277D01*
G01X1514792Y862944D01*
G03X1512608Y862920I-1071J-1951D01*
G02X1511134I-737J1276D01*
G01X1511024Y862984D01*
X1508171Y864197D01*
G01X1518204Y998315D02*
X1517059D01*
X1516829Y998085D01*
X1511119D01*
X1510689Y997655D01*
X1501069D01*
X1499354Y999370D01*
Y1000414D01*
X1498294Y1001474D01*
X1497069D01*
X1495655Y1002888D01*
G01X1527067Y1006600D02*
X1525698D01*
X1524219Y1008079D01*
X1523484D01*
X1523127Y1007722D01*
G02X1520499Y1007335I-1574J1575D01*
G01X1520394Y1007396D01*
G03X1518967Y1007369I-689J-1304D01*
G02X1516799Y1007335I-1115J1928D01*
G01X1516741Y1007369D01*
G03X1515267I-737J-1277D01*
G02X1513108Y1007330I-1115J1928D01*
G01X1513040Y1007370D01*
G03X1511566I-737J-1277D01*
G02X1509340I-1113J1927D01*
G03X1507866I-737J-1277D01*
G03X1507129Y1006127I737J-1277D01*
G01Y1006037D01*
G02X1506016Y1004165I-2225J56D01*
G01X1505981Y1004145D01*
G03X1505296Y1003113I773J-1256D01*
G01X1505521Y1002888D01*
X1506753D01*
G01X1527067Y1002274D02*
X1526050D01*
X1524458Y1003866D01*
X1523404D01*
G02X1522290Y1004165I0J2225D01*
G03X1520816I-737J-1277D01*
G01X1520758Y1004131D01*
G02X1518590Y1004165I-1054J1961D01*
G03X1517116I-737J-1277D01*
G01X1517058Y1004131D01*
G02X1514890Y1004165I-1054J1961D01*
G03X1513416I-737J-1277D01*
G02X1511190I-1113J1928D01*
G03X1509716I-737J-1277D01*
G01X1509681Y1004145D01*
G03X1508978Y1002888I772J-1257D01*
G01Y1001304D01*
X1508603Y1000929D01*
Y999684D01*
G01X1527067Y1008828D02*
X1523173D01*
X1522597Y1008252D01*
G02X1522291Y1008020I-1038J1051D01*
G02X1520864Y1007993I-738J1277D01*
G01X1520817Y1008020D01*
X1520759Y1008054D01*
G03X1518591Y1008020I-1053J-1962D01*
G02X1517149Y1008001I-738J1277D01*
G01X1517116Y1008020D01*
X1517058Y1008054D01*
G03X1514890Y1008020I-1053J-1962D01*
G02X1513416I-737J1277D01*
G03X1511190I-1113J-1927D01*
G02X1509716I-737J1277D01*
G03X1507490I-1113J-1927D01*
G03X1506378Y1006132I1113J-1927D01*
G01Y1006059D01*
G02X1505641Y1004816I-1474J34D01*
G03X1504542Y1003145I1112J-1928D01*
G01X1504285Y1002888D01*
X1503053D01*
G01X1527067Y1004615D02*
X1523404D01*
G02X1522667Y1004815I5J1476D01*
G03X1520499Y1004849I-1114J-1927D01*
G01X1520441Y1004815D01*
G02X1518967I-737J1277D01*
G03X1516799Y1004849I-1114J-1927D01*
G01X1516741Y1004815D01*
G02X1515267I-737J1277D01*
G01X1515232Y1004836D01*
G03X1513040Y1004816I-1078J-1948D01*
G02X1511566I-737J1277D01*
G03X1509340I-1113J-1928D01*
G03X1508228Y1002961I1113J-1928D01*
G01Y1002888D01*
G02X1507525Y1001631I-1475J0D01*
G01X1506938Y1001296D01*
X1503995D01*
X1501204Y999684D01*
G01X1525037Y1114380D02*
X1524170Y1113513D01*
Y1109861D01*
G02X1521750Y1107644I-2226J0D01*
G03X1520440Y1107353I-195J-2218D01*
G02X1518966I-737J1277D01*
G03X1516740I-1113J-1927D01*
G03X1515628Y1105465I1113J-1927D01*
G01Y1105426D01*
G02X1514925Y1104169I-1475J0D01*
G01X1514890Y1104149D01*
G03X1513778Y1102294I1113J-1928D01*
G01Y1102221D01*
G02X1513075Y1100964I-1475J0D01*
G01X1513040Y1100944D01*
G02X1511566I-737J1277D01*
G01X1511525Y1100968D01*
G03X1509339Y1100944I-1072J-1951D01*
G02X1507865I-737J1277D01*
G03X1505641I-1112J-1927D01*
G02X1504167I-737J1277D01*
G03X1501999Y1100978I-1114J-1927D01*
G01X1501941Y1100944D01*
G02X1500467I-737J1277D01*
G01X1500426Y1100968D01*
G03X1498240Y1100944I-1072J-1951D01*
G02X1496766I-737J1277D01*
G01X1496725Y1100968D01*
G03X1494541Y1100944I-1071J-1951D01*
G02X1493271Y1100847I-736J1277D01*
G01X1493188Y1101154D01*
X1493804Y1102221D01*
G01X1529337Y844821D02*
X1528729Y845429D01*
Y848232D01*
X1527059Y849902D01*
X1526673D01*
G02X1525936Y850102I4J1474D01*
G03X1523750Y850126I-1114J-1926D01*
G01X1523709Y850102D01*
X1523676Y850083D01*
G02X1522236Y850102I-703J1294D01*
G03X1520025I-1105J-1912D01*
G01X1520008Y850092D01*
G02X1518537I-735J1273D01*
G01X1518532Y850094D01*
G02X1517797Y851367I735J1273D01*
G01Y851377D01*
G03X1517726Y851547I-241J-1D01*
G01X1517439Y851835D01*
G03X1516548Y852518I-3037J-3039D01*
G01X1516308Y852657D01*
G03X1514834I-737J-1277D01*
G02X1512608I-1113J1927D01*
G02X1511496Y854545I1113J1927D01*
G01Y854584D01*
G03X1510945Y855733I-1475J-1D01*
G01X1510637Y855651D01*
X1510021Y854584D01*
G01X1530776Y846260D02*
X1530099Y846937D01*
Y850778D01*
X1528520Y852357D01*
G02X1527409Y852654I0J2227D01*
G01X1527362Y852682D01*
G03X1525935Y852655I-689J-1305D01*
G02X1523767Y852621I-1115J1929D01*
G01X1523709Y852655D01*
X1523662Y852682D01*
G03X1522235Y852655I-689J-1305D01*
G01X1522125Y852590D01*
X1519286Y851395D01*
X1519271Y851380D01*
G01X1527888Y843372D02*
X1527439Y843821D01*
Y848386D01*
X1526673Y849152D01*
G02X1525559Y849451I0J2225D01*
G03X1524119Y849470I-737J-1275D01*
G01X1524086Y849451D01*
X1524045Y849427D01*
G02X1521859Y849451I-1072J1950D01*
G03X1520402I-728J-1261D01*
G01X1520385Y849441D01*
G02X1518159I-1113J1926D01*
G01X1518158D01*
X1518041Y849508D01*
X1515574Y851375D01*
X1515571Y851378D01*
Y851380D01*
G01X1536765Y863871D02*
Y863877D01*
X1533777Y866865D01*
X1532205D01*
X1530095Y868975D01*
G03X1527408Y869329I-1574J-1574D01*
G02X1525934I-737J1277D01*
G03X1523708I-1113J-1928D01*
G02X1522234I-737J1277D01*
G03X1520008I-1113J-1928D01*
G02X1518534I-737J1277D01*
G03X1516308I-1113J-1928D01*
G03X1515196Y867403I1112J-1926D01*
G01Y867401D01*
G02X1514493Y866144I-1475J0D01*
G01X1514458Y866124D01*
X1514345Y866060D01*
X1511871Y864197D01*
G01X1537251Y860596D02*
X1536579Y861268D01*
Y861966D01*
X1533588Y864957D01*
X1533053D01*
X1529565Y868445D01*
G03X1529258Y868678I-1038J-1049D01*
G03X1527784I-737J-1277D01*
G02X1525558I-1113J1928D01*
G03X1524084I-737J-1277D01*
G02X1521858I-1113J1928D01*
G03X1520384I-737J-1277D01*
G01X1520349Y868658D01*
G03X1519646Y867401I772J-1257D01*
G01Y867269D01*
X1519270Y864197D01*
G01X1536893Y855278D02*
X1534941Y857230D01*
Y861100D01*
X1534069Y861972D01*
G02X1533926Y861976I-9J2225D01*
G02X1532958Y862270I146J2220D01*
G03X1531484I-737J-1277D01*
G02X1529316Y862236I-1114J1927D01*
G01X1529258Y862270D01*
G03X1527784I-737J-1277D01*
G02X1525616Y862236I-1114J1927D01*
G01X1525439Y862338D01*
X1522970Y864197D01*
G01X1532277Y847762D02*
X1531409Y848630D01*
Y850641D01*
X1528943Y853107D01*
X1528521D01*
G02X1527727Y853340I2J1476D01*
G03X1525559Y853306I-1053J-1963D01*
G02X1524132Y853279I-738J1278D01*
G01X1524085Y853306D01*
X1524027Y853340D01*
G03X1521859Y853306I-1053J-1963D01*
G02X1520417Y853287I-738J1278D01*
G01X1520384Y853306D01*
G03X1518158I-1113J-1929D01*
G02X1517673Y853105I-485J485D01*
G01X1517438D01*
G02X1516684Y853307I0J1507D01*
G03X1514458I-1113J-1927D01*
G02X1512984I-737J1277D01*
G01X1512949Y853327D01*
G02X1512246Y854584I772J1257D01*
G01Y854657D01*
G03X1511350Y856371I-2225J-72D01*
G01X1511255Y856722D01*
X1511871Y857789D01*
G01X1536034Y851518D02*
X1535969Y851583D01*
Y851915D01*
X1535320Y852564D01*
Y854264D01*
X1533207Y856377D01*
Y858418D01*
X1532858Y858767D01*
X1532217D01*
G02X1531085Y859078I0J2217D01*
G03X1529633Y859066I-715J-1289D01*
G01X1529575Y859032D01*
G02X1527407Y859066I-1054J1961D01*
G03X1525933I-737J-1277D01*
G01X1525875Y859032D01*
G02X1523707Y859066I-1054J1961D01*
G03X1522233I-737J-1277D01*
G02X1520009I-1112J1927D01*
G03X1518739Y859163I-736J-1277D01*
G01X1518656Y858856D01*
X1519271Y857789D01*
G01X1534629Y850112D02*
X1534564Y850177D01*
X1534230D01*
X1533610Y850797D01*
Y854119D01*
X1531417Y856312D01*
X1530370D01*
G02X1529633Y856512I5J1476D01*
G01X1529575Y856546D01*
G03X1527407Y856512I-1053J-1962D01*
G02X1525933I-737J1277D01*
G01X1525875Y856546D01*
G03X1523707Y856512I-1053J-1962D01*
G02X1522233I-737J1277D01*
G03X1520009I-1112J-1928D01*
G02X1518535I-737J1277D01*
G03X1516616Y856661I-1115J-1927D01*
G03X1516537Y856629I796J-2079D01*
G01X1516187Y856722D01*
X1515571Y857789D01*
G01X1536897Y852381D02*
X1536832Y852446D01*
X1536498D01*
X1536069Y852875D01*
Y854575D01*
X1533956Y856688D01*
Y858729D01*
X1533169Y859516D01*
X1532218D01*
X1532217Y859517D01*
G02X1531483Y859714I0J1467D01*
G01X1531484Y859716D01*
G03X1529316Y859750I-1114J-1927D01*
G01X1529258Y859716D01*
G02X1527784I-737J1277D01*
G03X1525616Y859750I-1114J-1927D01*
G01X1525558Y859716D01*
G02X1524084I-737J1277D01*
G03X1521916Y859750I-1114J-1927D01*
G01X1521858Y859716D01*
G02X1520384I-737J1277D01*
G01X1520326Y859750D01*
G03X1518467Y859864I-1053J-1961D01*
G03X1518388Y859832I796J-2079D01*
G01X1518037Y859926D01*
X1517421Y860993D01*
G01X1533766Y849249D02*
X1533701Y849314D01*
Y849646D01*
X1532861Y850486D01*
Y853808D01*
X1531106Y855563D01*
X1530370D01*
G02X1529258Y855861I1J2226D01*
G03X1527784I-737J-1277D01*
G02X1525616Y855827I-1115J1928D01*
G01X1525558Y855861D01*
G03X1524084I-737J-1277D01*
G02X1521916Y855827I-1115J1928D01*
G01X1521858Y855861D01*
G03X1520384I-737J-1277D01*
G01X1520326Y855827D01*
G02X1518158Y855861I-1053J1962D01*
G03X1516888Y855958I-736J-1277D01*
G01X1516805Y855651D01*
X1517421Y854584D01*
G54D24*
G01X1879155Y478898D02*
X1883405D01*
X1883805Y479298D01*
Y485527D01*
X1884858Y486268D01*
X1903181Y483037D01*
X1903965Y483587D01*
X1904843Y488568D01*
X1904295Y489354D01*
X1863531Y496540D01*
X1862874Y497478D01*
X1863949Y503575D01*
X1864886Y504233D01*
X1903412Y497441D01*
X1903874Y497766D01*
X1904849Y503297D01*
X1904526Y503758D01*
X1863524Y510987D01*
X1862867Y511923D01*
X1863942Y518021D01*
X1864880Y518680D01*
X1903212Y511921D01*
X1903674Y512246D01*
X1904650Y517778D01*
X1904326Y518239D01*
X1863394Y525455D01*
X1862736Y526392D01*
X1863811Y532490D01*
X1864748Y533148D01*
X1903310Y526350D01*
X1903773Y526675D01*
X1904749Y532206D01*
X1904425Y532666D01*
X1863499Y539882D01*
X1862841Y540819D01*
X1863916Y546917D01*
X1864853Y547575D01*
X1903307Y540796D01*
X1903769Y541121D01*
X1904744Y546652D01*
X1904421Y547113D01*
X1863378Y554349D01*
X1862720Y555286D01*
X1863795Y561384D01*
X1864732Y562042D01*
X1903193Y555261D01*
X1903654Y555585D01*
X1904629Y561117D01*
X1904306Y561578D01*
X1863514Y568770D01*
X1862856Y569707D01*
X1863931Y575806D01*
X1864170Y575974D01*
X1864171Y575973D01*
X1864888Y576477D01*
X1883336Y573224D01*
X1883784Y573671D01*
Y582469D01*
X1883405Y582848D01*
X1879155D01*
G01X1889155Y478898D02*
X1885005D01*
X1884505Y479398D01*
Y485163D01*
X1885023Y485528D01*
X1903346Y482296D01*
X1904605Y483180D01*
X1905583Y488731D01*
X1904703Y489993D01*
X1863939Y497180D01*
X1863614Y497642D01*
X1864102Y500406D01*
X1864103D01*
X1864589Y503168D01*
X1865051Y503493D01*
X1903576Y496701D01*
X1904514Y497358D01*
X1905590Y503462D01*
X1904933Y504398D01*
X1863931Y511627D01*
X1863607Y512088D01*
X1864582Y517614D01*
X1865045Y517939D01*
X1903376Y511181D01*
X1904314Y511838D01*
X1905390Y517942D01*
X1904733Y518879D01*
X1863801Y526095D01*
X1863476Y526557D01*
X1864451Y532083D01*
X1864913Y532408D01*
X1903474Y525610D01*
X1904413Y526267D01*
X1905489Y532371D01*
X1904832Y533306D01*
X1863906Y540522D01*
X1863581Y540984D01*
X1864556Y546510D01*
X1865018Y546835D01*
X1903471Y540056D01*
X1904409Y540713D01*
X1905485Y546817D01*
X1904828Y547753D01*
X1863785Y554989D01*
X1863460Y555451D01*
X1864435Y560977D01*
X1864897Y561302D01*
X1903357Y554521D01*
X1904294Y555178D01*
X1905370Y561282D01*
X1904713Y562218D01*
X1863921Y569410D01*
X1863596Y569872D01*
X1864571Y575398D01*
X1864574Y575400D01*
X1865053Y575737D01*
X1883573Y572471D01*
X1884484Y573380D01*
Y582427D01*
X1884905Y582848D01*
X1889155D01*
G54D15*
X526478Y1439952D03*
X718638Y1429579D03*
X1178470Y1466363D03*
X1502956Y1439530D03*
X1679944Y1463655D03*
G54D25*
G01X1186280Y298972D02*
X1183970Y301282D01*
Y306592D01*
X1155915Y334647D01*
X968635D01*
X947920Y355362D01*
X834092D01*
X809728Y330998D01*
X759656D01*
X757601Y328943D01*
X690701D01*
X645220Y283462D01*
X603888D01*
X591133Y270707D01*
X571629D01*
X568044Y267122D01*
X535790D01*
X531550Y271362D01*
X269592D01*
X225845Y227615D01*
X108635D01*
X82956Y253294D01*
X27130D01*
X14220Y240384D01*
Y199209D01*
X17061Y196368D01*
G01X1181450Y306052D02*
X1181020D01*
X1154125Y332947D01*
X1143362D01*
X1142862Y332447D01*
Y330142D01*
X1142362Y329642D01*
X1140362D01*
X1139862Y330142D01*
Y332447D01*
X1139362Y332947D01*
X1137362D01*
X1136862Y332447D01*
Y330142D01*
X1136362Y329642D01*
X1134362D01*
X1133862Y330142D01*
Y332447D01*
X1133362Y332947D01*
X967930D01*
X947215Y353662D01*
X834797D01*
X810433Y329298D01*
X760361D01*
X758306Y327243D01*
X691406D01*
X645925Y281762D01*
X604593D01*
X591838Y269007D01*
X572334D01*
X568749Y265422D01*
X534870D01*
X530630Y269662D01*
X270297D01*
X226550Y225915D01*
X107930D01*
X82251Y251594D01*
X27835D01*
X16320Y240079D01*
Y203971D01*
X16925Y203366D01*
G01X24720Y216362D02*
X27874Y219516D01*
X35576D01*
X39388Y215704D01*
X65087D01*
X89622Y191169D01*
X177089D01*
X212896Y155362D01*
X245820D01*
X250620Y160162D01*
X256600D01*
X259500Y157262D01*
X270020D01*
X273720Y160962D01*
X309520D01*
X315470Y155012D01*
X354550D01*
X369270Y140292D01*
X390956D01*
X400220Y131028D01*
Y119334D01*
X413692Y105862D01*
X438220D01*
X466886Y134528D01*
X492054D01*
X495660Y130922D01*
X520459D01*
X542459Y108922D01*
X615655D01*
X627740Y96837D01*
Y72812D01*
X630850Y69702D01*
Y56772D01*
X630350Y56272D01*
X628910D01*
X628410Y55772D01*
Y54272D01*
X628910Y53772D01*
X630350D01*
X630850Y53272D01*
Y52092D01*
X631899Y51043D01*
X678570D01*
X679551Y50062D01*
X689629D01*
X694400Y54833D01*
Y58157D01*
G01X33500Y200862D02*
Y204032D01*
X21220Y216312D01*
Y225738D01*
X23032Y227550D01*
X28262D01*
X31720Y231008D01*
Y242238D01*
X33374Y243892D01*
X39940D01*
X57000Y226832D01*
X76870D01*
X104670Y199032D01*
X179292D01*
X208962Y169362D01*
X266920D01*
X267320Y169762D01*
X285740D01*
X287540Y171562D01*
X312520D01*
X323940Y182982D01*
Y187992D01*
X346710Y210762D01*
X361190D01*
G01X357303Y213159D02*
X346702D01*
X322240Y188697D01*
X302105D01*
X284970Y171562D01*
X266520D01*
X266120Y171162D01*
X210400D01*
X180740Y200822D01*
X105412D01*
X77612Y228622D01*
X57830D01*
X40750Y245702D01*
X32778D01*
X29720Y242644D01*
Y232862D01*
X26611Y229753D01*
X22829D01*
X19520Y226444D01*
Y215606D01*
X31220Y203906D01*
Y198312D01*
X33670Y195862D01*
Y192862D01*
G01X1124985Y302578D02*
X1117004D01*
X1090035Y329547D01*
X966520D01*
X945805Y350262D01*
X836207D01*
X811843Y325898D01*
X761771D01*
X759716Y323843D01*
X692816D01*
X647335Y278362D01*
X606003D01*
X593203Y265562D01*
X587434D01*
X583454Y261582D01*
X532740D01*
X528060Y266262D01*
X271707D01*
X227960Y222515D01*
X106520D01*
X80841Y248194D01*
X31052D01*
X27720Y244862D01*
Y235362D01*
X24720Y232362D01*
G01X697720Y58162D02*
X695875Y60007D01*
X693632D01*
X692550Y58925D01*
Y55388D01*
X689124Y51962D01*
X680241D01*
X679460Y52743D01*
X634989D01*
X632670Y55062D01*
Y71072D01*
X629440Y74302D01*
Y97542D01*
X615320Y111662D01*
X548240D01*
X544660Y115242D01*
X538544D01*
X520774Y133012D01*
X496300D01*
X493084Y136228D01*
X466181D01*
X437515Y107562D01*
X414397D01*
X401920Y120039D01*
Y131733D01*
X391661Y141992D01*
X370050D01*
X355330Y156712D01*
X319270D01*
X313220Y162762D01*
X289910D01*
X288710Y163962D01*
X273300D01*
X271600Y162262D01*
X244800D01*
X239800Y157262D01*
X213401D01*
X177794Y192869D01*
X91673D01*
X67138Y217404D01*
X40093D01*
X36281Y221216D01*
X27866D01*
X24720Y224362D01*
G01X1122059Y305673D02*
X1116314D01*
X1104125Y317862D01*
Y318568D01*
X1105365Y319809D01*
Y320515D01*
X1103666Y322214D01*
X1102960D01*
X1101720Y320973D01*
X1101014D01*
X1099315Y322672D01*
Y323378D01*
X1100555Y324619D01*
Y325325D01*
X1098856Y327024D01*
X1098150D01*
X1096910Y325783D01*
X1096204D01*
X1090740Y331247D01*
X967225D01*
X946510Y351962D01*
X835502D01*
X811138Y327598D01*
X761066D01*
X759011Y325543D01*
X692111D01*
X646630Y280062D01*
X605298D01*
X592498Y267262D01*
X586728D01*
X582748Y263282D01*
X534170D01*
X529490Y267962D01*
X271002D01*
X227255Y224215D01*
X107225D01*
X81546Y249894D01*
X28752D01*
X24720Y245862D01*
Y240362D01*
G01X189600Y1566300D02*
X191322D01*
X202500Y1555122D01*
Y1534362D01*
X115000Y1446862D01*
Y1302862D01*
X109000Y1296862D01*
X58000D01*
X42500Y1281362D01*
X31500D01*
X23000Y1272862D01*
Y1011862D01*
X13155Y1002017D01*
Y686207D01*
X26500Y672862D01*
G01X454661Y1609235D02*
X445910Y1600484D01*
Y1581622D01*
X453310Y1574222D01*
Y1570842D01*
X455520Y1568632D01*
Y1564062D01*
X440320Y1548862D01*
X426647D01*
X425547Y1547762D01*
X403439D01*
X398639Y1552562D01*
X228635D01*
X120320Y1444247D01*
Y1333788D01*
X127220Y1326888D01*
Y1306836D01*
X104046Y1283662D01*
X52280D01*
X32820Y1264202D01*
Y1014542D01*
X17891Y999613D01*
Y697421D01*
X29316Y685996D01*
X30936D01*
X33810Y683122D01*
X38470D01*
G01X424820Y1552605D02*
X424197Y1551982D01*
X414680D01*
X412930Y1550232D01*
X403368D01*
X399438Y1554162D01*
X227972D01*
X118720Y1444910D01*
Y1333125D01*
X125620Y1326225D01*
Y1307075D01*
X111507Y1292962D01*
X59320D01*
X31520Y1265162D01*
Y1015081D01*
X16591Y1000152D01*
Y696882D01*
X28777Y684696D01*
X29736D01*
X33810Y680622D01*
X38470D01*
G01Y685622D02*
X33810D01*
X32036Y687396D01*
X29896D01*
X20454Y696838D01*
Y754863D01*
X23054Y757463D01*
Y763784D01*
X23049Y763789D01*
Y764060D01*
X20454Y766655D01*
Y1000196D01*
X34120Y1013862D01*
Y1263662D01*
X52720Y1282262D01*
X104626D01*
X128620Y1306256D01*
Y1327468D01*
X121720Y1334368D01*
Y1443667D01*
X229215Y1551162D01*
X392839D01*
X397639Y1546362D01*
X426884D01*
X427449Y1546927D01*
X440449D01*
X455184Y1561662D01*
X456900D01*
X457400Y1562162D01*
Y1575912D01*
X453900Y1579412D01*
Y1582300D01*
X449200Y1587000D01*
Y1600200D01*
X457500Y1608500D01*
Y1610062D01*
X448700Y1618862D01*
X430170D01*
X421320Y1627712D01*
Y1671699D01*
G01X187400Y1568132D02*
X187668Y1568400D01*
X197262D01*
X204500Y1561162D01*
Y1533863D01*
X117000Y1446363D01*
Y1301863D01*
X109999Y1294862D01*
X58499D01*
X42699Y1279062D01*
X33039D01*
X24800Y1270823D01*
Y1010823D01*
X14873Y1000896D01*
Y687489D01*
X26500Y675862D01*
G01X38470Y688122D02*
X33810D01*
X33236Y688696D01*
X30435D01*
X21754Y697377D01*
Y754170D01*
X29304Y761720D01*
Y765523D01*
X28084Y766743D01*
X26570D01*
X21754Y771559D01*
Y999147D01*
X34735Y1012128D01*
X43735D01*
X46354Y1014747D01*
Y1267654D01*
X49740Y1271040D01*
X49741D01*
X59028Y1280327D01*
X105428D01*
X130555Y1305454D01*
Y1328270D01*
X123020Y1335805D01*
Y1443127D01*
X229720Y1549827D01*
X391586D01*
X396386Y1545027D01*
X427954D01*
X428154Y1545227D01*
X441154D01*
X453254Y1557327D01*
X457728D01*
X459400Y1558999D01*
Y1577500D01*
X458000Y1578900D01*
Y1581300D01*
X459500Y1582800D01*
Y1584700D01*
X456100Y1588100D01*
Y1594000D01*
X463200Y1601100D01*
Y1617590D01*
X453120Y1627670D01*
Y1638032D01*
X449940Y1641212D01*
Y1647412D01*
G01X374800Y1546400D02*
X374038Y1547162D01*
X230966D01*
X125620Y1441816D01*
Y1337116D01*
X133320Y1329416D01*
Y1304308D01*
X106574Y1277562D01*
X60174D01*
X49120Y1266508D01*
Y1013601D01*
X44881Y1009362D01*
X35881D01*
X24520Y998001D01*
Y775241D01*
X27230Y772531D01*
X28845D01*
X32240Y769136D01*
Y759784D01*
X24520Y752064D01*
Y698523D01*
X29921Y693122D01*
X38470D01*
G01Y690622D02*
X30441D01*
X23120Y697943D01*
Y753360D01*
X30766Y761006D01*
Y766642D01*
X29149Y768259D01*
X26947D01*
X23120Y772086D01*
Y998581D01*
X35301Y1010762D01*
X44301D01*
X47720Y1014181D01*
Y1267088D01*
X59594Y1278962D01*
X105994D01*
X131920Y1304888D01*
Y1328836D01*
X124320Y1336436D01*
Y1442496D01*
X230286Y1548462D01*
X391020D01*
X395820Y1543662D01*
X428520D01*
X428720Y1543862D01*
X442420D01*
X454520Y1555962D01*
X458662D01*
X461400Y1558700D01*
Y1568500D01*
X464300Y1571400D01*
Y1575600D01*
X462000Y1577900D01*
Y1584600D01*
X457600Y1589000D01*
Y1592400D01*
X465775Y1600575D01*
Y1641597D01*
X456820Y1650552D01*
X450170D01*
X447090Y1647472D01*
G01X431620Y1541362D02*
X400120D01*
X398420Y1539662D01*
X392720D01*
X389320Y1536262D01*
X371620D01*
X365420Y1542462D01*
X228812D01*
X126920Y1440570D01*
Y1338362D01*
X135120Y1330162D01*
Y1303562D01*
X107320Y1275762D01*
X60220D01*
X52620Y1268162D01*
X52614D01*
X50420Y1265968D01*
Y1013062D01*
X45420Y1008062D01*
X36420D01*
X25820Y997462D01*
Y776049D01*
X27439Y774430D01*
X29243D01*
X33949Y769724D01*
Y758793D01*
X25820Y750664D01*
Y708272D01*
X38470Y695622D01*
G01X33670Y240362D02*
X36834Y237198D01*
X41007D01*
X54001Y224204D01*
X75310D01*
X103245Y196269D01*
X179204D01*
X208311Y167162D01*
X269620D01*
X270520Y168062D01*
X286540D01*
X288040Y169562D01*
X316726D01*
X325925Y160363D01*
X356502D01*
X371473Y145392D01*
X393071D01*
X405320Y133143D01*
Y121449D01*
X415807Y110962D01*
X436105D01*
X464771Y139628D01*
X494964D01*
X497880Y136712D01*
X528440D01*
X550090Y115062D01*
X616733D01*
X638310Y93485D01*
Y84242D01*
X641330Y81222D01*
Y60192D01*
X638500Y57362D01*
G01X33670Y232362D02*
X36806Y235498D01*
X40302D01*
X53296Y222504D01*
X69697D01*
X97632Y194569D01*
X178499D01*
X208106Y164962D01*
X271520D01*
X272620Y166062D01*
X287620D01*
X289220Y167662D01*
X316220D01*
X325219Y158663D01*
X355797D01*
X370768Y143692D01*
X392366D01*
X403620Y132438D01*
Y120744D01*
X415102Y109262D01*
X436810D01*
X465476Y137928D01*
X494084D01*
X497230Y134782D01*
X527661D01*
X549081Y113362D01*
X616027D01*
X636580Y92809D01*
Y83202D01*
X639270Y80512D01*
Y61632D01*
X635000Y57362D01*
G01X1291420Y320662D02*
X1188683D01*
X1171698Y337647D01*
X970735D01*
X949220Y359162D01*
X832992D01*
X808292Y334462D01*
X758220D01*
X756201Y332443D01*
X688901D01*
X643120Y286662D01*
X602388D01*
X589588Y273862D01*
X570320D01*
X566580Y270122D01*
X538090D01*
X533670Y274542D01*
X261740D01*
X212879Y323403D01*
X69364D01*
X44668Y298707D01*
X40000D01*
G01X36000Y295952D02*
X45810D01*
X71806Y321948D01*
X212276D01*
X261162Y273062D01*
X532900D01*
X537140Y268822D01*
X567338D01*
X570923Y272407D01*
X590191D01*
X602991Y285207D01*
X643723D01*
X689504Y330988D01*
X756804D01*
X758823Y333007D01*
X808895D01*
X833595Y357707D01*
X948617D01*
X969977Y336347D01*
X1171159D01*
X1189344Y318162D01*
X1291420D01*
G01X63930Y739300D02*
X66200Y737030D01*
Y734100D01*
X64610Y732510D01*
Y726752D01*
X62020Y724162D01*
Y662762D01*
X65814Y658968D01*
Y603754D01*
X62237Y600177D01*
X52341D01*
X46356Y606162D01*
X31520D01*
X29220Y603862D01*
Y521942D01*
X88700Y462462D01*
X112900D01*
X118000Y457362D01*
X176320D01*
X193620Y474662D01*
X253900D01*
X310935Y417627D01*
X366101D01*
X370200Y413528D01*
Y409582D01*
G01X583220Y493212D02*
X540470D01*
X525820Y478562D01*
X515290D01*
X501890Y465162D01*
X442874D01*
X418824Y489212D01*
X384264D01*
X376814Y496662D01*
X202020D01*
X171420Y466062D01*
X122120D01*
X116620Y471562D01*
X95320D01*
X57720Y509162D01*
Y582362D01*
X50220Y589862D01*
X38220D01*
G01X584173Y498422D02*
X580663Y494912D01*
X539764D01*
X525114Y480262D01*
X514584D01*
X501184Y466862D01*
X443580D01*
X419530Y490912D01*
X384970D01*
X377520Y498362D01*
X201315D01*
X170715Y467762D01*
X122825D01*
X117325Y473262D01*
X96025D01*
X59420Y509867D01*
Y583067D01*
X49625Y592862D01*
X38220D01*
G01X33020Y595232D02*
X36650Y598862D01*
X46030D01*
X61120Y583772D01*
Y510572D01*
X96730Y474962D01*
X118030D01*
X123530Y469462D01*
X170010D01*
X200610Y500062D01*
X396020D01*
X414091Y518133D01*
X431220D01*
G01X32720Y598402D02*
X36180Y601862D01*
X45435D01*
X62820Y584477D01*
Y511277D01*
X97435Y476662D01*
X118735D01*
X124235Y471162D01*
X169305D01*
X199905Y501762D01*
X395315D01*
X413386Y519833D01*
X427691D01*
X431220Y523362D01*
G01X641235Y477377D02*
X639415D01*
X637900Y475862D01*
X620800D01*
X620200Y475262D01*
X604700D01*
X601900Y472462D01*
X593892D01*
X589750Y468320D01*
X582327D01*
X579835Y470812D01*
X550850D01*
X546800Y474862D01*
Y477027D01*
X547935Y478162D01*
X549900D01*
X551500Y479762D01*
Y481562D01*
X550700Y482362D01*
X547100D01*
X526500Y461762D01*
X508612D01*
X506050Y459200D01*
X436466D01*
X419804Y475862D01*
X260695D01*
X256195Y480362D01*
X191505D01*
X173805Y462662D01*
X120710D01*
X115310Y468062D01*
X91099D01*
X77000Y482161D01*
Y485362D01*
G01X74550Y487812D02*
Y481812D01*
X90000Y466362D01*
X114605D01*
X120005Y460962D01*
X174510D01*
X192210Y478662D01*
X254900D01*
X259700Y473862D01*
X384700D01*
X389400Y469162D01*
X421100D01*
X434800Y455462D01*
X517712D01*
X519680Y457430D01*
X540732D01*
X548700Y449462D01*
X577220D01*
G01X84623Y741249D02*
X84780D01*
X90825Y735204D01*
Y731131D01*
X80941Y721247D01*
X76032D01*
X74465Y719680D01*
Y715930D01*
X71200Y712665D01*
Y663292D01*
X72530Y661962D01*
Y508971D01*
X100089Y481412D01*
X120321D01*
X125831Y475902D01*
X167321D01*
X197621Y506202D01*
X353481D01*
X409471Y562192D01*
X545609D01*
X552829Y554972D01*
X566140D01*
G01X82357Y737803D02*
Y735662D01*
X82997Y735022D01*
X87189D01*
X88310Y733901D01*
Y732831D01*
X78976Y723497D01*
X72965D01*
X67307Y717839D01*
Y663954D01*
X69802Y661459D01*
Y508180D01*
X99020Y478962D01*
X119320D01*
X124720Y473562D01*
X168520D01*
X199020Y504062D01*
X354520D01*
X410420Y559962D01*
X544320D01*
X552810Y551472D01*
X566140D01*
G01X370635Y1675820D02*
X371112D01*
X374430Y1672502D01*
X382540D01*
X406410Y1648632D01*
Y1631712D01*
X399540Y1624842D01*
Y1613030D01*
X381352Y1594842D01*
X150810D01*
X133340Y1612312D01*
X107790D01*
X96190Y1623912D01*
Y1639762D01*
X105070Y1648642D01*
Y1665822D01*
X100120Y1670772D01*
X73520D01*
X71690Y1672602D01*
Y1675842D01*
X74750Y1678902D01*
X77833D01*
G01X73833Y1674252D02*
X75409Y1672676D01*
X101296D01*
X107700Y1666272D01*
Y1647802D01*
X97890Y1637992D01*
Y1625272D01*
X109400Y1613762D01*
X133941D01*
X151411Y1596292D01*
X380632D01*
X397990Y1613650D01*
Y1627472D01*
X402940Y1632422D01*
Y1640332D01*
X378065Y1665207D01*
X374915D01*
X372640Y1662932D01*
Y1662112D01*
G01X640620Y483422D02*
X634360D01*
X631200Y480262D01*
X620588D01*
X618888Y481962D01*
X606022D01*
X599982Y475922D01*
X592237D01*
X589745Y473430D01*
X583370D01*
X572738Y484062D01*
X546395D01*
X525795Y463462D01*
X506802D01*
X504720Y461380D01*
X436691D01*
X420509Y477562D01*
X261400D01*
X256900Y482062D01*
X190800D01*
X173100Y464362D01*
X121415D01*
X116015Y469762D01*
X92500D01*
X79400Y482862D01*
G01X99600Y1668332D02*
X103220Y1664712D01*
Y1651962D01*
X93900Y1642642D01*
Y1615342D01*
X99450Y1609792D01*
X131620D01*
X149762Y1591650D01*
X165250D01*
X183790Y1573110D01*
X205381D01*
X219629Y1558862D01*
X387774D01*
X401694Y1572782D01*
X429800D01*
X432280Y1575262D01*
X437740D01*
X440220Y1572782D01*
X444110D01*
X446190Y1574862D01*
X448740D01*
G01X434430Y1567562D02*
X431450Y1570542D01*
X401860D01*
X388480Y1557162D01*
X218740D01*
X204852Y1571050D01*
X177820D01*
X159070Y1589800D01*
X149082D01*
X130920Y1607962D01*
X90630D01*
X88200Y1610392D01*
Y1644222D01*
X99645Y1655667D01*
Y1663217D01*
G01X370500Y1654362D02*
X369260Y1653122D01*
Y1644223D01*
X386870Y1626613D01*
Y1617208D01*
X382220Y1612558D01*
Y1610142D01*
X381720Y1609642D01*
X151426D01*
X132726Y1628342D01*
X120760D01*
X112180Y1636922D01*
Y1666062D01*
X97910Y1680332D01*
X85517D01*
X81833Y1676648D01*
Y1674526D01*
G01X104318Y1637862D02*
X104260D01*
X101930Y1635532D01*
Y1627832D01*
X114560Y1615202D01*
X134538D01*
X152008Y1597732D01*
X379912D01*
X396230Y1614050D01*
Y1628162D01*
X401310Y1633242D01*
Y1640022D01*
X381330Y1660002D01*
X380170D01*
G01X380077Y1654049D02*
X382090Y1652036D01*
Y1634792D01*
X388550Y1628332D01*
Y1616512D01*
X383900Y1611862D01*
Y1609446D01*
X382416Y1607962D01*
X150730D01*
X132030Y1626662D01*
X105780D01*
X104430Y1628012D01*
G01X1141957Y227277D02*
Y232733D01*
X1126629Y248061D01*
Y286952D01*
X1088034Y325547D01*
X964223D01*
X943960Y345810D01*
X837526D01*
X813162Y321446D01*
X782900D01*
X780216Y318762D01*
X763129D01*
X762500Y319391D01*
X694661D01*
X643480Y268210D01*
X604880D01*
X598232Y261562D01*
X589093D01*
X582723Y255192D01*
X549752D01*
X548190Y256754D01*
X530908D01*
X525400Y262262D01*
X274305D01*
X229947Y217904D01*
X125592D01*
X122000Y214312D01*
Y207362D01*
G01X116920Y207462D02*
Y212062D01*
X124802Y219944D01*
X229102D01*
X273420Y264262D01*
X526700D01*
X531380Y259582D01*
X584284D01*
X588264Y263562D01*
X594720D01*
X607060Y275902D01*
X648287D01*
X693816Y321431D01*
X760716D01*
X762771Y323486D01*
X812317D01*
X836681Y347850D01*
X944805D01*
X965108Y327547D01*
X1088863D01*
X1128849Y287561D01*
Y249311D01*
X1142468Y235692D01*
X1173750D01*
X1187550Y249492D01*
X1210240D01*
X1212584Y247148D01*
X1219220D01*
G01X615220Y76862D02*
X610120Y71762D01*
X596323D01*
X571723Y96362D01*
X552769D01*
X552269Y96862D01*
Y98906D01*
X551769Y99406D01*
X550269D01*
X549769Y98906D01*
Y96862D01*
X549269Y96362D01*
X542158D01*
X515458Y123062D01*
X482515D01*
X458015Y98562D01*
X437425D01*
X435225Y100762D01*
X411577D01*
X394920Y117419D01*
Y128567D01*
X388295Y135192D01*
X370065D01*
X366935Y132062D01*
X364300D01*
X351600Y144762D01*
X315210D01*
X312110Y147862D01*
X302500D01*
X300900Y146262D01*
X268220D01*
X267120Y145162D01*
X260520D01*
X257720Y147962D01*
X212557D01*
X179057Y181462D01*
X141520D01*
G01X139720Y179162D02*
X178952D01*
X211852Y146262D01*
X256719D01*
X259519Y143462D01*
X267919D01*
X268619Y144162D01*
X301400D01*
X303400Y146162D01*
X311405D01*
X314505Y143062D01*
X350300D01*
X363700Y129662D01*
X367106D01*
X370936Y133492D01*
X387590D01*
X393220Y127862D01*
Y116714D01*
X410872Y99062D01*
X434520D01*
X436720Y96862D01*
X458720D01*
X483220Y121362D01*
X514668D01*
X541368Y94662D01*
X571018D01*
X598818Y66862D01*
X608220D01*
X615170Y73812D01*
G01X601220Y73862D02*
X599100Y75982D01*
Y81150D01*
X574928Y105322D01*
X540570D01*
X521130Y124762D01*
X481810D01*
X457310Y100262D01*
X438130D01*
X435930Y102462D01*
X412282D01*
X396620Y118124D01*
Y129272D01*
X389000Y136892D01*
X367570D01*
X358000Y146462D01*
X315915D01*
X310815Y151562D01*
X293000D01*
X289900Y154662D01*
X274121D01*
X268621Y149162D01*
X259420D01*
X258720Y149862D01*
X213345D01*
X179195Y184012D01*
X143470D01*
G01X601220Y76862D02*
Y81435D01*
X584458Y98197D01*
Y98903D01*
X585594Y100039D01*
Y100744D01*
X584532Y101806D01*
X583826D01*
X582691Y100671D01*
X581984D01*
X575533Y107122D01*
X541175D01*
X521835Y126462D01*
X481105D01*
X456605Y101962D01*
X438835D01*
X436635Y104162D01*
X412987D01*
X398320Y118829D01*
Y129977D01*
X389705Y138592D01*
X368370D01*
X353700Y153262D01*
X299100D01*
X293300Y159062D01*
X274700D01*
X268900Y153262D01*
X258120D01*
X256420Y154962D01*
X248200D01*
X246900Y153662D01*
X212020D01*
X179220Y186462D01*
X145720D01*
G01X254713Y518465D02*
Y522009D01*
X253089Y523633D01*
X153256D01*
X149504Y519881D01*
G01X154647Y521783D02*
X250100D01*
G01X245700Y513262D02*
Y517752D01*
X243369Y520083D01*
X164641D01*
X160000Y515442D01*
Y510052D01*
G01X1041420Y443962D02*
Y446674D01*
X1035732Y452362D01*
X961894D01*
X951114Y441582D01*
X938837D01*
X934009Y436754D01*
X878445D01*
X874899Y440300D01*
X821900D01*
X808322Y426722D01*
X806900D01*
X790430Y410252D01*
X786992D01*
X785220Y408480D01*
Y397862D01*
X782420Y395062D01*
X779920D01*
X775950Y391092D01*
X764990D01*
X763500Y392582D01*
X717161D01*
X708491Y388991D01*
X704092Y384592D01*
X693400D01*
X691920Y383112D01*
X678816D01*
X668356Y372652D01*
X628130D01*
X623939Y376843D01*
X583491D01*
X560930Y354282D01*
X425730D01*
X413710Y342262D01*
X307466D01*
X260066Y389662D01*
X241806D01*
X217727Y413741D01*
X217019D01*
X215574Y412296D01*
X214866D01*
X213806Y413356D01*
Y414064D01*
X215251Y415509D01*
Y416217D01*
X213806Y417662D01*
X210279D01*
X204699Y423242D01*
G01Y428742D02*
Y426774D01*
X211711Y419762D01*
X214660D01*
X242430Y391992D01*
X260880D01*
X308680Y344192D01*
X412590D01*
X425230Y356832D01*
X560730D01*
X582480Y378582D01*
X626650D01*
X630880Y374352D01*
X666540D01*
X677000Y384812D01*
X691215D01*
X692715Y386312D01*
X703312D01*
X707479Y390479D01*
X716926Y394392D01*
X763320D01*
X764580Y395652D01*
X768720D01*
X770510Y393862D01*
X775720D01*
X778970Y397112D01*
Y399112D01*
X783520Y403662D01*
Y409186D01*
X786316Y411982D01*
X789700D01*
X806330Y428612D01*
X807612D01*
X821000Y442000D01*
X876000D01*
X879380Y438620D01*
X932409D01*
X937314Y443525D01*
X947139D01*
X957676Y454062D01*
X1036437D01*
X1043920Y446579D01*
Y443962D01*
G01X328167Y379073D02*
X307640Y399600D01*
X238642D01*
X215280Y422962D01*
X212760D01*
X209530Y426192D01*
G01X217770Y428262D02*
Y425652D01*
X240822Y402600D01*
X314862D01*
X334960Y382502D01*
X357280D01*
X359520Y384742D01*
X370030D01*
X370570Y385282D01*
X379270D01*
X388360Y376192D01*
X395510D01*
X400300Y380982D01*
X407359D01*
X418540Y392163D01*
G01X626720Y482880D02*
X624590Y485010D01*
X606350D01*
X603980Y482640D01*
X592940D01*
X585620Y475320D01*
X584020D01*
X581480Y477860D01*
Y480490D01*
X574250Y487720D01*
X540630D01*
X529970Y477060D01*
Y472160D01*
X523650Y465840D01*
X506280D01*
X503590Y463150D01*
X440970D01*
X418580Y485540D01*
X383650D01*
X375680Y493510D01*
X208200D01*
G01X696676Y418013D02*
Y414224D01*
X699100Y411800D01*
Y398127D01*
X697573Y396600D01*
X692458D01*
X691558Y395700D01*
X691553D01*
X689575Y393722D01*
X685265D01*
X677246Y390400D01*
X671850D01*
X662462Y381012D01*
X612988D01*
X611600Y382400D01*
X583300D01*
X579800Y378900D01*
X571400D01*
X555600Y363100D01*
X442900D01*
X439900Y360100D01*
X424400D01*
X412300Y348000D01*
X310800D01*
X263400Y395400D01*
X252000D01*
G01X407970Y59612D02*
X404600Y56242D01*
X321999D01*
X308640Y42883D01*
Y38395D01*
X306107Y35862D01*
X292520D01*
X288437Y31779D01*
Y22299D01*
X287000Y20862D01*
G01X340440Y120552D02*
X335940Y116052D01*
Y76052D01*
X324350Y64462D01*
X320010D01*
X313470Y57922D01*
X279080D01*
X273450Y52292D01*
Y44932D01*
X275120Y43262D01*
Y28562D01*
G01X396380Y62742D02*
Y61994D01*
X392498Y58112D01*
X321370D01*
X309420Y46162D01*
X277120D01*
X275900Y47382D01*
Y48872D01*
G01X289400Y54222D02*
X291400Y56222D01*
X314179D01*
X320481Y62524D01*
X384020D01*
X387788Y66292D01*
X398558D01*
X402100Y62750D01*
Y62632D01*
G01X407790Y62652D02*
X409820Y60622D01*
Y56003D01*
X407859Y54042D01*
X322299D01*
X310840Y42583D01*
Y36943D01*
X307559Y33662D01*
X293120D01*
X290799Y31341D01*
Y28362D01*
G01X404910Y62562D02*
Y63282D01*
X406130Y64502D01*
X410080D01*
X411080Y63502D01*
Y61764D01*
X411520Y61324D01*
Y55162D01*
X408420Y52062D01*
X407331D01*
X406831Y51562D01*
Y49212D01*
X406331Y48712D01*
X404821D01*
X404321Y49212D01*
Y51562D01*
X403821Y52062D01*
X402311D01*
X401811Y51562D01*
Y49212D01*
X401311Y48712D01*
X399801D01*
X399301Y49212D01*
Y51562D01*
X398801Y52062D01*
X397291D01*
X396791Y51562D01*
Y49212D01*
X396291Y48712D01*
X394781D01*
X394281Y49212D01*
Y51562D01*
X393781Y52062D01*
X392271D01*
X391771Y51562D01*
Y49212D01*
X391271Y48712D01*
X389761D01*
X389261Y49212D01*
Y51562D01*
X388761Y52062D01*
X387251D01*
X386751Y51562D01*
Y49212D01*
X386251Y48712D01*
X384741D01*
X384241Y49212D01*
Y51562D01*
X383741Y52062D01*
X382231D01*
X381731Y51562D01*
Y49212D01*
X381231Y48712D01*
X379721D01*
X379221Y49212D01*
Y51562D01*
X378721Y52062D01*
X377211D01*
X376711Y51562D01*
Y49212D01*
X376211Y48712D01*
X374701D01*
X374201Y49212D01*
Y51562D01*
X373701Y52062D01*
X372191D01*
X371691Y51562D01*
Y49212D01*
X371191Y48712D01*
X369681D01*
X369181Y49212D01*
Y51562D01*
X368681Y52062D01*
X367171D01*
X366671Y51562D01*
Y49212D01*
X366171Y48712D01*
X364661D01*
X364161Y49212D01*
Y51562D01*
X363661Y52062D01*
X323020D01*
X312820Y41862D01*
Y36472D01*
X308030Y31682D01*
X294230D01*
X293010Y30462D01*
Y25422D01*
X292060Y24472D01*
G01X399240Y62722D02*
Y62840D01*
X397488Y64592D01*
X389350D01*
X388393Y63635D01*
Y62927D01*
X389285Y62035D01*
Y61327D01*
X388218Y60260D01*
X387510D01*
X386618Y61152D01*
X385910D01*
X384920Y60162D01*
X320720D01*
X315080Y54522D01*
X293130D01*
X292590Y53982D01*
G01X680928Y414864D02*
Y412720D01*
X679200Y410992D01*
Y407452D01*
X678010Y406262D01*
X667830D01*
X663760Y402192D01*
X657760D01*
X655230Y399662D01*
X650050D01*
X648050Y401662D01*
X647200D01*
X644250Y398712D01*
X638050D01*
X634900Y401862D01*
X631000D01*
X629400Y400262D01*
X574250D01*
X570340Y396352D01*
X565455D01*
X550415Y381312D01*
X456270D01*
X437100Y400482D01*
X408040D01*
X396180Y388622D01*
X387610D01*
X379160Y397072D01*
X367150D01*
X362570Y401652D01*
X347750D01*
X340100Y409302D01*
X332620D01*
X330990Y407672D01*
Y402272D01*
X341619Y391643D01*
X343354D01*
G01X684077Y421163D02*
X682480Y419566D01*
Y413812D01*
X682790Y413502D01*
Y405862D01*
X680343Y403415D01*
X677511Y402242D01*
X668842D01*
X661812Y395212D01*
X574270D01*
X571910Y392852D01*
X566906D01*
X551786Y377732D01*
X454550D01*
X435620Y396662D01*
X415830D01*
X403870Y384702D01*
X385810D01*
X376980Y393532D01*
X372350D01*
X367130Y388312D01*
X350950D01*
X336270Y402992D01*
G01X343450Y131167D02*
X346210Y128407D01*
Y73242D01*
X354770Y64682D01*
X383750D01*
X387060Y67992D01*
X411444D01*
X416314Y72862D01*
X419782D01*
X420282Y73362D01*
Y86032D01*
X420782Y86532D01*
X422282D01*
X422782Y86032D01*
Y73362D01*
X423282Y72862D01*
X424782D01*
X425282Y73362D01*
Y86032D01*
X425782Y86532D01*
X427282D01*
X427782Y86032D01*
Y73362D01*
X428282Y72862D01*
X429782D01*
X430282Y73362D01*
Y86032D01*
X430782Y86532D01*
X432282D01*
X432782Y86032D01*
Y73362D01*
X433282Y72862D01*
X440979D01*
X444633Y69208D01*
Y68502D01*
X438110Y61980D01*
Y61274D01*
X439172Y60212D01*
X439878D01*
X446401Y66734D01*
X447107D01*
X448169Y65672D01*
Y64966D01*
X441646Y58444D01*
Y57738D01*
X442708Y56676D01*
X443414D01*
X449937Y63198D01*
X450643D01*
X451705Y62136D01*
Y61430D01*
X445182Y54908D01*
Y54202D01*
X446244Y53140D01*
X446950D01*
X453473Y59662D01*
X454179D01*
X461094Y52747D01*
X465863D01*
X466363Y53247D01*
Y65152D01*
X466863Y65652D01*
X468363D01*
X468863Y65152D01*
Y53247D01*
X469363Y52747D01*
X470863D01*
X471363Y53247D01*
Y65152D01*
X471863Y65652D01*
X473363D01*
X473863Y65152D01*
Y53247D01*
X474363Y52747D01*
X481665D01*
X482165Y53247D01*
Y61512D01*
X482665Y62012D01*
X484165D01*
X484665Y61512D01*
Y53247D01*
X485165Y52747D01*
X486665D01*
X487165Y53247D01*
Y61512D01*
X487665Y62012D01*
X489165D01*
X489665Y61512D01*
Y53247D01*
X490165Y52747D01*
X491665D01*
X492165Y53247D01*
Y63820D01*
X492665Y64320D01*
X494165D01*
X494665Y63820D01*
Y53247D01*
X495165Y52747D01*
X502693D01*
X527406Y28034D01*
X729097D01*
X761074Y41279D01*
X762890Y43996D01*
Y45050D01*
X763267Y45961D01*
X767141Y49835D01*
X772753Y52160D01*
X850496D01*
X858629Y60293D01*
G01X345600Y188162D02*
Y176358D01*
X354396Y167562D01*
X385095D01*
X407615Y145042D01*
X430640D01*
X443360Y157762D01*
X458760D01*
X461640Y154882D01*
X531430D01*
X532550Y153762D01*
Y148052D01*
X543640Y136962D01*
X681450D01*
X692700Y148212D01*
X754970D01*
X765320Y137862D01*
X773200D01*
X804150Y168812D01*
X834500D01*
X835220Y168092D01*
Y163862D01*
G01X348100Y185162D02*
Y176282D01*
X355120Y169262D01*
X385800D01*
X408320Y146742D01*
X429935D01*
X442655Y159462D01*
X459465D01*
X462345Y156582D01*
X532135D01*
X534250Y154467D01*
Y148757D01*
X544345Y138662D01*
X680745D01*
X691995Y149912D01*
X771851D01*
X778201Y156262D01*
X783599D01*
X797849Y170512D01*
X835205D01*
X837570Y168147D01*
Y166084D01*
X838220Y165434D01*
Y163862D01*
G01X680928Y418013D02*
X679340Y416425D01*
Y413832D01*
X675630Y410122D01*
X666600D01*
X662740Y406262D01*
X656500D01*
X656250Y406012D01*
X565969D01*
X546529Y386572D01*
X471090D01*
X458240Y399422D01*
X445310D01*
X436610Y408122D01*
X426170D01*
X422350Y404302D01*
X409120D01*
X405140Y408282D01*
X401770D01*
X394080Y400592D01*
X379720D01*
X374630Y405682D01*
X365630D01*
X363590Y407722D01*
X347600D01*
X347340Y407462D01*
G01X356295Y219362D02*
X369225Y232292D01*
X405200D01*
X407430Y230062D01*
X430670D01*
X432900Y232292D01*
X489870D01*
X492800Y229362D01*
X551472D01*
X553402Y231292D01*
G01X687227Y424313D02*
X685670Y422756D01*
Y411002D01*
X687260Y409412D01*
Y403634D01*
X684787Y401161D01*
X675905Y397482D01*
X669032D01*
X659562Y388012D01*
X629250D01*
X625700Y391562D01*
X575660D01*
X573450Y389352D01*
X568460D01*
X553340Y374232D01*
X407890D01*
X406070Y372412D01*
X386890D01*
X377660Y381642D01*
X372350D01*
X369357Y378649D01*
X364014D01*
G01X678900Y1595400D02*
X672600D01*
X672100Y1595900D01*
Y1604227D01*
X666427Y1609900D01*
X476300D01*
X474200Y1612000D01*
Y1642201D01*
X460201Y1656200D01*
X426900D01*
X426400Y1656700D01*
Y1674500D01*
X421100Y1679800D01*
X385500D01*
X379300Y1686000D01*
X369200D01*
X366700Y1683500D01*
Y1649000D01*
G01X678900Y1589800D02*
X672500D01*
X668900Y1593400D01*
Y1602900D01*
X665100Y1606700D01*
X473600D01*
X467300Y1613000D01*
Y1643500D01*
X457400Y1653400D01*
X450000D01*
X444100Y1647500D01*
X430100D01*
X423300Y1654300D01*
Y1672800D01*
X419400Y1676700D01*
X379100D01*
X375400Y1680400D01*
X369300D01*
G01X678900Y1592600D02*
X672500D01*
X670400Y1594700D01*
Y1603522D01*
X665722Y1608200D01*
X475100D01*
X469400Y1613900D01*
Y1637475D01*
X471430Y1639505D01*
Y1642370D01*
X458900Y1654900D01*
X425800D01*
X424900Y1655800D01*
Y1673463D01*
X420063Y1678300D01*
X383200D01*
X377000Y1684500D01*
X370900D01*
X369300Y1682900D01*
G01X376500Y378649D02*
Y371500D01*
X385000Y363000D01*
X395888D01*
X401800Y368912D01*
X407520D01*
X409340Y370732D01*
X439550D01*
X442274Y368008D01*
X470597D01*
X472005Y366600D01*
X551008D01*
X570250Y385842D01*
X575158D01*
X575878Y386562D01*
X612481D01*
X614531Y384512D01*
X661012D01*
X670482Y393982D01*
X676686D01*
X684509Y397222D01*
X688125D01*
X690103Y399200D01*
X690108D01*
X692735Y401827D01*
X694770D01*
X695270Y402327D01*
Y413032D01*
X691860Y416442D01*
X689460D01*
X688780Y417122D01*
Y421842D01*
X689700Y422762D01*
X691200D01*
X691923Y423485D01*
Y425915D01*
X690376Y427462D01*
G01X677778Y414864D02*
X676196Y413282D01*
X669970D01*
X669600Y413652D01*
X664910D01*
X662090Y410832D01*
X646270D01*
X644950Y409512D01*
X540370D01*
X525860Y395002D01*
X467950D01*
X461290Y401662D01*
Y403492D01*
X458020Y406762D01*
X444570D01*
X435410Y415922D01*
X395440D01*
X383060Y403542D01*
G01X558220Y459362D02*
X518720D01*
X518120Y459962D01*
X510572D01*
X508060Y457450D01*
X435412D01*
X421300Y471562D01*
X401170D01*
X400080Y472652D01*
G01X690220Y519662D02*
X687720Y517162D01*
Y515862D01*
X682860Y511002D01*
X656628D01*
X654721Y512909D01*
X622767D01*
X616720Y506862D01*
X598020D01*
X596620Y508262D01*
X588620D01*
X577520Y497162D01*
X537920D01*
X532120Y491362D01*
X513920D01*
X501920Y479362D01*
X486520D01*
X484820Y477662D01*
Y474462D01*
X478920Y468562D01*
X453288D01*
X441980Y479870D01*
X436580D01*
X423838Y492612D01*
X390250D01*
X387500Y495362D01*
G01X591500Y516862D02*
Y513547D01*
X576815Y498862D01*
X537215D01*
X531415Y493062D01*
X513215D01*
X501215Y481062D01*
X485815D01*
X483120Y478367D01*
Y475167D01*
X478215Y470262D01*
X454188D01*
X441660Y482790D01*
X436190D01*
X423618Y495362D01*
X402500D01*
G01X524720Y525293D02*
X465769D01*
X460000Y531062D01*
X393515D01*
X389020Y526567D01*
Y522862D01*
G01X524720Y519743D02*
X468259D01*
X458640Y529362D01*
X406815D01*
X406315Y528862D01*
Y528035D01*
X405815Y527535D01*
X404315D01*
X403815Y528035D01*
Y528862D01*
X403315Y529362D01*
X395220D01*
X394500Y528642D01*
Y522862D01*
G01X681980Y58157D02*
Y62212D01*
X664190Y80002D01*
Y98689D01*
X627857Y135022D01*
X566520D01*
X562400Y130902D01*
X544085D01*
X522925Y152062D01*
X461015D01*
X452702Y143749D01*
X433702D01*
X427033Y137080D01*
Y123371D01*
X428889Y121515D01*
G01X678050Y58157D02*
Y63712D01*
X676094Y65668D01*
X675386D01*
X674150Y64432D01*
X673442D01*
X672382Y65492D01*
Y66200D01*
X673618Y67436D01*
Y68144D01*
X672558Y69204D01*
X671850D01*
X670614Y67968D01*
X669906D01*
X668846Y69028D01*
Y69736D01*
X670082Y70972D01*
Y71680D01*
X662260Y79502D01*
Y98213D01*
X631641Y128832D01*
X610803D01*
X610303Y129332D01*
Y130892D01*
X609803Y131392D01*
X608303D01*
X607803Y130892D01*
Y129332D01*
X607303Y128832D01*
X605803D01*
X605303Y129332D01*
Y130892D01*
X604803Y131392D01*
X603303D01*
X602803Y130892D01*
Y129332D01*
X602303Y128832D01*
X600803D01*
X600303Y129332D01*
Y130892D01*
X599803Y131392D01*
X598303D01*
X597803Y130892D01*
Y129332D01*
X597303Y128832D01*
X573230D01*
X571450Y127052D01*
X563530D01*
X561750Y128832D01*
X543750D01*
X522220Y150362D01*
X461720D01*
X453375Y142017D01*
X434375D01*
X428883Y136525D01*
Y131015D01*
G01X590820Y330962D02*
X589118Y329260D01*
X501522D01*
X499600Y331182D01*
X446290D01*
X434600Y319492D01*
X425720D01*
G01X466300Y225480D02*
X464918Y226862D01*
X452500D01*
X450000Y224362D01*
Y211861D01*
X456469Y205392D01*
X546115D01*
X554872Y196635D01*
G01X583820Y314662D02*
X581520Y316962D01*
X519489D01*
X517474Y318977D01*
X451310D01*
X449295Y316962D01*
X441520D01*
X439120Y314562D01*
G01X590720Y327862D02*
X590140Y327282D01*
X446140D01*
X442220Y323362D01*
G01X590720Y324582D02*
X568780D01*
X564740Y320542D01*
X522400D01*
X519360Y323582D01*
X448220D01*
G01X590470Y319192D02*
X590060Y318782D01*
X520393D01*
X518062Y321113D01*
X449471D01*
X448220Y319862D01*
G01X466300Y217803D02*
X476111Y207992D01*
X548165D01*
X557248Y198909D01*
G01X456520Y476337D02*
Y475352D01*
X458020Y473852D01*
X467960D01*
X468960Y474852D01*
Y481432D01*
X469970Y482442D01*
Y485592D01*
X482230Y497852D01*
X530778D01*
X557458Y524532D01*
X629360D01*
X633830Y520062D01*
X660230D01*
X660976Y519316D01*
X675954D01*
X678150Y521512D01*
X697220D01*
X699380Y519352D01*
X753998D01*
X756024Y521378D01*
X768244D01*
X771428Y524562D01*
X795918D01*
X796568Y525212D01*
X825740D01*
X828632Y522320D01*
X840800D01*
X843692Y525212D01*
X845052D01*
X848302Y528462D01*
X883196D01*
X886626Y525032D01*
X901822D01*
X907962Y518892D01*
X934090D01*
X936844Y521646D01*
X953972D01*
X962406Y513212D01*
X967487D01*
X968283Y512416D01*
X969351D01*
G01X980720Y512362D02*
Y519292D01*
X974866Y525146D01*
X935394D01*
X932640Y522392D01*
X923300D01*
X917160Y528532D01*
X888076D01*
X884646Y531962D01*
X793121D01*
X789671Y528512D01*
X744200D01*
X742912Y529800D01*
X728300D01*
X727328Y530772D01*
X715010D01*
X712750Y528512D01*
X667289D01*
X664408Y529705D01*
X662581Y531532D01*
X553150D01*
X542710Y521092D01*
Y519571D01*
X529303Y506164D01*
Y504330D01*
X528055Y503082D01*
X482460D01*
X466435Y487057D01*
Y483907D01*
X464905Y482377D01*
X462560D01*
X461520Y481337D01*
Y476337D01*
G01X692280Y1302532D02*
X687990D01*
X685327Y1299869D01*
Y1284341D01*
X682297Y1281311D01*
X679354D01*
X659367Y1273031D01*
X657711Y1271375D01*
X641107D01*
X639094Y1269362D01*
X617120D01*
X593391Y1245633D01*
Y1194065D01*
X552894Y1153568D01*
Y1132889D01*
X549888Y1129883D01*
X545441D01*
G01X696810Y1300162D02*
Y1294604D01*
X702587Y1288827D01*
Y1282835D01*
X699157Y1279405D01*
X693380D01*
X692910Y1278935D01*
Y1277575D01*
X692440Y1277105D01*
X690800D01*
X690330Y1277575D01*
Y1278935D01*
X689860Y1279405D01*
X688220D01*
X687750Y1278935D01*
Y1277575D01*
X687280Y1277105D01*
X685640D01*
X685170Y1277575D01*
Y1278935D01*
X684700Y1279405D01*
X679372D01*
X660705Y1271673D01*
X658394Y1269362D01*
X642220D01*
X640120Y1267262D01*
X618034D01*
X595297Y1244525D01*
Y1193275D01*
X554800Y1152778D01*
Y1129901D01*
X551626Y1126727D01*
X545654D01*
G01X486800Y259162D02*
X488200Y260562D01*
X524500D01*
X530330Y254732D01*
X547020D01*
X551429Y250323D01*
X580259D01*
X589798Y259862D01*
X598938D01*
X603418Y264342D01*
X612750D01*
X614200Y265792D01*
G01X496028Y258590D02*
X523772D01*
X529660Y252702D01*
X546550D01*
X550629Y248623D01*
X580965D01*
X590504Y258162D01*
X599644D01*
X604024Y262542D01*
X615280D01*
X618470Y265732D01*
G01X503100Y215244D02*
X503982Y214362D01*
X546200D01*
X559400Y201162D01*
G01X512500Y223362D02*
X555300D01*
X564600Y214062D01*
Y202662D01*
G01X629220Y426362D02*
X626700Y428882D01*
X599020D01*
X591000Y420862D01*
X576080D01*
X571880Y416662D01*
X540020D01*
X524690Y401332D01*
X505850D01*
X502260Y397742D01*
G01X677778Y427462D02*
Y426400D01*
X677278Y425900D01*
X672899D01*
X672699Y425700D01*
X660100D01*
X658400Y424000D01*
X635800D01*
X634300Y425500D01*
Y430600D01*
X631100Y433800D01*
X599490D01*
X594580Y428890D01*
X576970D01*
X575020Y426940D01*
X516430D01*
X506980Y436390D01*
Y438520D01*
X510836Y442376D01*
X532650D01*
G01X599080Y448062D02*
X590062D01*
X574260Y432260D01*
X517022D01*
X511320Y437962D01*
G01X569490Y437600D02*
X568790Y436900D01*
X557970D01*
X555840Y434770D01*
X540540D01*
X536930Y438380D01*
Y449990D01*
X532650Y454270D01*
G01X571110Y446706D02*
X567360Y442956D01*
Y440470D01*
X566600Y439710D01*
X558200D01*
X556810Y438320D01*
X542870D01*
G01X626390Y467882D02*
X624510Y469762D01*
X597812D01*
X593650Y465600D01*
X582642D01*
X579130Y469112D01*
X549950D01*
X544900Y474162D01*
Y477532D01*
X547750Y480382D01*
X548550D01*
G01X548780Y475932D02*
X551842Y472870D01*
X580470D01*
X582590Y470750D01*
X589470D01*
X592942Y474222D01*
X600822D01*
X606462Y479862D01*
X616610D01*
X618470Y478002D01*
X626210D01*
G01X546210Y519642D02*
X554600Y528032D01*
X637240D01*
X641400Y523872D01*
X661160D01*
X662950Y525662D01*
X664810D01*
X665460Y525012D01*
X714270D01*
X716515Y527257D01*
X725645D01*
X726710Y526192D01*
X738680D01*
X740050Y524822D01*
X755400D01*
X756650Y526072D01*
G01X755305Y298847D02*
X745825D01*
X734510Y287532D01*
Y248372D01*
X715330Y229192D01*
X707180D01*
X635580Y157592D01*
X601870D01*
X597990Y161472D01*
X592070D01*
X588060Y157462D01*
X586230D01*
X571171Y142403D01*
X566870D01*
X566640Y142173D01*
X564890D01*
G01X651730Y177212D02*
X652620Y178102D01*
Y182722D01*
X623180Y212162D01*
X619160D01*
X606460Y224862D01*
X583100D01*
X580260Y227702D01*
X567030D01*
X565640Y226312D01*
Y223452D01*
X567730Y221362D01*
G01X649870Y181942D02*
X649864D01*
X622088Y209718D01*
X618068D01*
X605424Y222362D01*
X582270D01*
X581280Y223352D01*
X569740D01*
X567730Y225362D01*
G01X674628Y484006D02*
X674454Y484180D01*
X665020D01*
X655478Y493722D01*
X592562D01*
X584100Y485260D01*
Y477952D01*
G01X680928Y477856D02*
Y478552D01*
X679440Y480040D01*
X673320D01*
X671970Y478690D01*
X666020D01*
X652730Y491980D01*
X594180D01*
X590210Y488010D01*
Y484132D01*
G01X699825Y474707D02*
Y477237D01*
X697510Y479552D01*
X682258D01*
X665460Y496350D01*
X658540D01*
X657780Y495590D01*
X588965D01*
X587867Y494492D01*
X587750D01*
X587100Y493842D01*
G01X745220Y503842D02*
X742603D01*
X740137Y501376D01*
X669204D01*
X667290Y503290D01*
X660520D01*
X652761Y511049D01*
X623890D01*
X617237Y504396D01*
Y503165D01*
X613337Y499265D01*
X593965D01*
X591070Y502160D01*
Y504900D01*
G01X699825Y471557D02*
X701560Y473292D01*
Y477322D01*
X697700Y481182D01*
X689560D01*
X683092Y487650D01*
X677200D01*
X666960Y497890D01*
X657959D01*
X656959Y496890D01*
X587648D01*
X587100Y496342D01*
G01X674628Y424313D02*
X662413D01*
X657372Y419272D01*
X642927D01*
X641487Y420712D01*
X639953D01*
X638513Y419272D01*
X635420D01*
X630379Y424313D01*
X625269D01*
X623220Y426362D01*
G01X677778Y436911D02*
X676217Y438472D01*
X665923D01*
X662774Y441621D01*
X645986D01*
X645707Y441900D01*
X633702D01*
X630320Y445282D01*
X628200D01*
X625620Y447862D01*
G01X680928Y440061D02*
X679360Y438493D01*
Y436092D01*
X678590Y435322D01*
X666910D01*
X666090Y436142D01*
X636120D01*
X632450Y439812D01*
X625270D01*
X622220Y442862D01*
G01Y452862D02*
X624070Y454712D01*
X629988D01*
X638808Y445892D01*
X666508D01*
X670768Y441632D01*
X676207D01*
X677778Y440061D01*
G01X674628D02*
X666739D01*
X663479Y443321D01*
X646691D01*
X645840Y444172D01*
X635770D01*
X629692Y450250D01*
X624608D01*
X622220Y447862D01*
G01X687227Y455809D02*
X686294D01*
X685639Y456464D01*
Y460517D01*
X685116Y461040D01*
X683100D01*
X682480Y460420D01*
Y458020D01*
X681842Y457382D01*
X655618D01*
X652740Y460260D01*
X647870D01*
X646710Y459100D01*
X642580D01*
X641138Y460542D01*
X628670D01*
X626400Y462812D01*
G01X680928Y462108D02*
X679354Y463682D01*
X676970D01*
X676200Y464452D01*
Y465972D01*
X675310Y466862D01*
X661719D01*
X660669Y465812D01*
X654740D01*
X653720Y466832D01*
X647505D01*
X646140Y465467D01*
X624825D01*
X622220Y462862D01*
G01X629480Y508862D02*
X632362Y505980D01*
X643750D01*
X646230Y508460D01*
X651840D01*
X659400Y500900D01*
X667002D01*
X668540Y499362D01*
X744250D01*
X757140Y512252D01*
X774630D01*
X779080Y507802D01*
X799740D01*
X804600Y512662D01*
X816750D01*
X817320Y513232D01*
X824020D01*
X827542Y509710D01*
X841642D01*
X844282Y512350D01*
X854268D01*
X857710Y515792D01*
X880204D01*
X888584Y507412D01*
X917098D01*
X917587Y507901D01*
X938259D01*
X945458Y500702D01*
X949800D01*
X954390Y505292D01*
X984949D01*
X989300Y509643D01*
Y517762D01*
X999412Y527874D01*
X1076708D01*
X1082220Y522362D01*
G01X1139457Y227277D02*
Y233050D01*
X1117438Y255069D01*
Y293863D01*
X1087188Y324113D01*
X962191D01*
X941814Y344490D01*
X839483D01*
X814531Y319538D01*
X785000D01*
X782224Y316762D01*
X768650D01*
X759575Y307687D01*
X752621D01*
X731929Y286995D01*
Y251886D01*
X715732Y235689D01*
X645263D01*
G01X643800Y298297D02*
X644925Y299422D01*
X653280D01*
X688001Y334143D01*
X755495D01*
X757514Y336162D01*
X807202D01*
X832072Y361032D01*
X950356D01*
X957006Y354382D01*
X982203D01*
X985410Y353054D01*
X991277Y347187D01*
X1024597D01*
X1029082Y342702D01*
X1170274D01*
X1190464Y322512D01*
X1296990D01*
X1311510Y307992D01*
Y299002D01*
X1325450Y285062D01*
X1328008D01*
X1343108Y269962D01*
X1352500D01*
X1355100Y267362D01*
Y253182D01*
X1364710Y243572D01*
Y223052D01*
X1367140Y220622D01*
X1374690D01*
X1382860Y228792D01*
X1389640D01*
X1398243Y237395D01*
Y264291D01*
X1423390Y289438D01*
Y333952D01*
X1442480Y353042D01*
Y368733D01*
X1464559Y390812D01*
X1498030D01*
X1541830Y434612D01*
Y563567D01*
X1557140Y578877D01*
Y588060D01*
X1553198Y592002D01*
X1541860D01*
X1539720Y589862D01*
G01X1552720D02*
X1555440Y587142D01*
Y579582D01*
X1540130Y564272D01*
Y435317D01*
X1497325Y392512D01*
X1463774D01*
X1439720Y368458D01*
Y352687D01*
X1421690Y334657D01*
Y320626D01*
X1421190Y320126D01*
X1418340D01*
X1417840Y319626D01*
Y317226D01*
X1418340Y316726D01*
X1421190D01*
X1421690Y316226D01*
Y313826D01*
X1421190Y313326D01*
X1418340D01*
X1417840Y312826D01*
Y310426D01*
X1418340Y309926D01*
X1421190D01*
X1421690Y309426D01*
Y307026D01*
X1421190Y306526D01*
X1418340D01*
X1417840Y306026D01*
Y303626D01*
X1418340Y303126D01*
X1421190D01*
X1421690Y302626D01*
Y290143D01*
X1396294Y264747D01*
Y238199D01*
X1388587Y230492D01*
X1382155D01*
X1373985Y222322D01*
X1367845D01*
X1366410Y223757D01*
Y244277D01*
X1357012Y253675D01*
Y268550D01*
X1353600Y271962D01*
X1343748D01*
X1328648Y287062D01*
X1325855D01*
X1313210Y299707D01*
Y308697D01*
X1297695Y324212D01*
X1191169D01*
X1170979Y344402D01*
X1030711D01*
X1025719Y349394D01*
X991550D01*
X986347Y354597D01*
X982762Y356082D01*
X957711D01*
X951061Y362732D01*
X843415D01*
X839910Y366237D01*
X831572D01*
X824360Y359025D01*
Y356251D01*
X805971Y337862D01*
X756809D01*
X754790Y335843D01*
X687296D01*
X652575Y301122D01*
X644925D01*
X643800Y302247D01*
G01X1552720Y581862D02*
X1549450Y585132D01*
X1539610D01*
X1533590Y579112D01*
Y438027D01*
X1494615Y399052D01*
X1465420D01*
X1434640Y368272D01*
Y353252D01*
X1418160Y336772D01*
Y329582D01*
X1405630Y317052D01*
Y287402D01*
X1392833Y274605D01*
Y239592D01*
X1387411Y234170D01*
X1374682D01*
X1372500Y236352D01*
Y244852D01*
X1361495Y255857D01*
Y270967D01*
X1356300Y276162D01*
X1345268D01*
X1334080Y287350D01*
Y294692D01*
X1319262Y309510D01*
X1317337D01*
X1299235Y327612D01*
X1194859D01*
X1174649Y347822D01*
X1033180D01*
X1027886Y353116D01*
X993354D01*
X988916Y357554D01*
X983983Y359597D01*
X959006D01*
X952471Y366132D01*
X852109D01*
X848173Y370068D01*
X827440D01*
X816172Y358800D01*
Y352873D01*
X804561Y341262D01*
X755399D01*
X753380Y339243D01*
X684436D01*
X659318Y314125D01*
X646347D01*
X645990Y314482D01*
G01X643800Y310962D02*
X645263Y312425D01*
X660023D01*
X685141Y337543D01*
X754085D01*
X756104Y339562D01*
X805266D01*
X817975Y352271D01*
Y358049D01*
X828116Y368190D01*
X847121D01*
X850879Y364432D01*
X951766D01*
X958301Y357897D01*
X983084D01*
X987681Y355993D01*
X992429Y351245D01*
X1026796D01*
X1031919Y346122D01*
X1173944D01*
X1194154Y325912D01*
X1298530D01*
X1316632Y307810D01*
X1318557D01*
X1332380Y293987D01*
Y286260D01*
X1344378Y274262D01*
X1354600D01*
X1359400Y269462D01*
Y255547D01*
X1370800Y244147D01*
Y235647D01*
X1373977Y232470D01*
X1388116D01*
X1394533Y238887D01*
Y273900D01*
X1407330Y286697D01*
Y295798D01*
X1407830Y296298D01*
X1411156D01*
X1411656Y296798D01*
Y298298D01*
X1411156Y298798D01*
X1407830D01*
X1407330Y299298D01*
Y300798D01*
X1407830Y301298D01*
X1411156D01*
X1411656Y301798D01*
Y303298D01*
X1411156Y303798D01*
X1407830D01*
X1407330Y304298D01*
Y316347D01*
X1419860Y328877D01*
Y336067D01*
X1436460Y352667D01*
Y367645D01*
X1466167Y397352D01*
X1495320D01*
X1535290Y437322D01*
Y577432D01*
X1539720Y581862D01*
G01X637220Y411362D02*
X640120Y414262D01*
X644750D01*
X644820Y414332D01*
X660070D01*
X665020Y419282D01*
X673359D01*
X674628Y418013D01*
G01X637220Y416362D02*
X658520D01*
X665150Y422992D01*
X672799D01*
X674628Y421163D01*
G01X640720Y431362D02*
X642720Y433362D01*
X645220D01*
X646420Y432162D01*
X679329D01*
X680928Y433761D01*
G01X684077D02*
X682510Y432194D01*
Y429500D01*
X682010Y429000D01*
X682001Y429009D01*
X672191D01*
X670582Y427400D01*
X661200D01*
X659200Y429400D01*
X639182D01*
X637220Y431362D01*
G01Y462862D02*
X641248D01*
X643098Y461012D01*
X645690D01*
X649470Y464792D01*
X653280D01*
X654417Y463655D01*
X675477D01*
X676220Y462912D01*
Y461302D01*
X677010Y460512D01*
X679375D01*
X680928Y458959D01*
G01X684077Y443210D02*
X679387Y447900D01*
X672127D01*
X672120Y447907D01*
X670838D01*
X670831Y447900D01*
X648682D01*
X646380Y450202D01*
X643380D01*
X640720Y452862D01*
G01X684077Y465258D02*
X682485Y466850D01*
Y469518D01*
X682020Y469983D01*
X675973D01*
X675212Y469222D01*
X671158D01*
X667560Y472820D01*
X652928D01*
X650360Y470252D01*
X639610D01*
X637220Y467862D01*
G01X677778Y471557D02*
X671303D01*
X668340Y474520D01*
X654142D01*
X653630Y475032D01*
X639970D01*
X637800Y472862D01*
X637220D01*
G01X680928Y471557D02*
X679363Y473122D01*
X676158D01*
X672750Y476530D01*
X654712D01*
X650990Y480252D01*
X639610D01*
X637220Y477862D01*
G01X651520Y378662D02*
X668310D01*
X676160Y386512D01*
X689161D01*
X690400Y387751D01*
Y392142D01*
X692258Y394000D01*
X710352D01*
X712654Y394954D01*
X719962Y402262D01*
X761790D01*
X765882Y398170D01*
X769912D01*
X771720Y396362D01*
X774220D01*
X776220Y398362D01*
Y408658D01*
X768701Y416177D01*
Y418662D01*
G01X655820Y452662D02*
X657382Y451100D01*
X676500D01*
X677778Y449822D01*
Y449510D01*
G01X655800Y461432D02*
Y461362D01*
X656650Y460512D01*
X673075D01*
X674628Y458959D01*
G01X692389Y72692D02*
Y69887D01*
X690474Y67972D01*
X681870D01*
X677140Y72702D01*
Y79283D01*
X691119Y93262D01*
X706090D01*
X707790Y94962D01*
X732114D01*
X734054Y96902D01*
X741376D01*
X746850Y102376D01*
X750000Y109979D01*
Y111162D01*
X759951Y121113D01*
X762249D01*
X797088Y155952D01*
X837119D01*
X847080Y165913D01*
X850345Y173795D01*
Y197922D01*
X912565Y260142D01*
X952880D01*
X958260Y254762D01*
X1022857D01*
X1035979Y249327D01*
X1046486Y238820D01*
X1074952D01*
X1191530Y122242D01*
X1206830D01*
X1210101Y118971D01*
X1258686D01*
X1259077Y119362D01*
X1263801D01*
X1272791Y110372D01*
X1278115D01*
X1280720Y112977D01*
X1298225D01*
X1300540Y110662D01*
X1307572D01*
X1319968Y98266D01*
G01X673987Y87662D02*
X675187Y86462D01*
X681420D01*
X690220Y95262D01*
X705200D01*
X706930Y96992D01*
X723430D01*
X726400Y99962D01*
X732320D01*
X735900Y103542D01*
X739200D01*
X759310Y123652D01*
Y130582D01*
X762580Y133852D01*
X772090D01*
X796190Y157952D01*
X836290D01*
X842070Y163732D01*
Y175492D01*
X839500Y178062D01*
Y189906D01*
X918656Y269062D01*
X970220D01*
X977420Y261862D01*
X1024275D01*
X1040006Y255346D01*
X1043490Y251862D01*
X1083720D01*
X1117107Y218475D01*
X1143387D01*
X1144490Y219578D01*
X1158566D01*
X1165550Y226562D01*
X1188000D01*
X1188600Y225962D01*
G01X664590Y1631620D02*
X668410Y1635440D01*
Y1654910D01*
X679520Y1666020D01*
X690890D01*
X695960Y1671090D01*
X731065D01*
X732705Y1669450D01*
G01X1292880Y93162D02*
X1286990Y99052D01*
X1275843D01*
X1275343Y98552D01*
Y96562D01*
X1274843Y96062D01*
X1274033D01*
X1273533Y96562D01*
Y98552D01*
X1273033Y99052D01*
X1272223D01*
X1271723Y98552D01*
Y96562D01*
X1271223Y96062D01*
X1270413D01*
X1269913Y96562D01*
Y98552D01*
X1269413Y99052D01*
X1268603D01*
X1268103Y98552D01*
Y96562D01*
X1267603Y96062D01*
X1266793D01*
X1266293Y96562D01*
Y98300D01*
X1265793Y98800D01*
X1257782D01*
X1254961Y101621D01*
X1195662D01*
X1167944Y129339D01*
Y134585D01*
X1071337Y231192D01*
X1044491D01*
X1032121Y243562D01*
X1021499Y247962D01*
X955440D01*
X950060Y253342D01*
X915388D01*
X857145Y195099D01*
Y155778D01*
X831589Y130222D01*
X781419D01*
X765419Y114222D01*
X761243Y104140D01*
Y91194D01*
X750561Y80512D01*
X727970D01*
X725110Y83372D01*
X717430D01*
X715570Y85232D01*
X709690D01*
X706118Y81660D01*
X705410D01*
X704368Y82702D01*
X703660D01*
X703088Y82130D01*
Y81422D01*
X704130Y80380D01*
Y79672D01*
X703558Y79100D01*
X702850D01*
X701808Y80142D01*
X701100D01*
X698500Y77542D01*
Y73752D01*
X698690Y73562D01*
Y71822D01*
X697080Y70212D01*
X694751D01*
G01X1310906Y97807D02*
X1308175D01*
X1298120Y107862D01*
X1293119D01*
X1288419Y103162D01*
X1275620D01*
X1273761Y105021D01*
X1197673D01*
X1171344Y131350D01*
Y136517D01*
X1072899Y234962D01*
X1045533D01*
X1034050Y246445D01*
X1022179Y251362D01*
X956850D01*
X951470Y256742D01*
X913975D01*
X853745Y196512D01*
Y157308D01*
X848989Y152552D01*
X798938D01*
X762918Y116532D01*
X761772D01*
X757020Y111780D01*
Y104482D01*
X747025Y94487D01*
Y89657D01*
X743906Y86538D01*
X727774D01*
X722830Y91482D01*
X709379D01*
X707759Y89862D01*
X697320D01*
X691890Y84432D01*
Y75155D01*
X690027Y73292D01*
Y70142D01*
G01X696700Y72462D02*
X694470Y74692D01*
Y84412D01*
X698200Y88142D01*
X708480D01*
X710070Y89732D01*
X721250D01*
X728770Y82212D01*
X737602D01*
X739602Y84212D01*
X751855D01*
X759543Y91900D01*
Y104774D01*
X763770Y114979D01*
X780713Y131922D01*
X830884D01*
X855445Y156483D01*
Y195804D01*
X914683Y255042D01*
X950765D01*
X956145Y249662D01*
X1021839D01*
X1033085Y245004D01*
X1045077Y233012D01*
X1072091D01*
X1169644Y135459D01*
Y130239D01*
X1196562Y103321D01*
X1272861D01*
X1274866Y101316D01*
X1301066D01*
X1311220Y91162D01*
Y89182D01*
X1311260Y89142D01*
Y83032D01*
G01X687664Y73202D02*
Y74552D01*
X689780Y76668D01*
Y89422D01*
X691920Y91562D01*
X706970D01*
X708650Y93242D01*
X733319D01*
X734099Y92462D01*
X738240D01*
X738980Y93202D01*
X740620D01*
X752660Y105242D01*
Y110922D01*
X760479Y118741D01*
X762721D01*
X798232Y154252D01*
X837824D01*
X852045Y168473D01*
Y197217D01*
X913270Y258442D01*
X952175D01*
X957555Y253062D01*
X1022518D01*
X1035014Y247886D01*
X1045798Y237102D01*
X1073164D01*
X1173044Y137222D01*
Y132220D01*
X1198326Y106938D01*
X1278054D01*
X1282393Y111277D01*
X1297519D01*
X1308523Y100273D01*
X1311889D01*
X1314406Y97756D01*
G01X771426Y158026D02*
X766747Y153347D01*
X702079D01*
X687238Y168188D01*
Y171071D01*
G01X961320Y476242D02*
X960550Y475472D01*
X941500D01*
X935560Y469532D01*
X916290D01*
X915090Y468332D01*
X880280D01*
X861330Y487282D01*
X815800D01*
X812060Y491022D01*
X756460D01*
X743130Y477692D01*
X734350D01*
X732960Y476302D01*
X727460D01*
X726605Y475447D01*
Y473917D01*
X725820Y473132D01*
X724290D01*
X723445Y472287D01*
Y470877D01*
X722550Y469982D01*
X721140D01*
X720320Y469162D01*
Y467672D01*
X719490Y466842D01*
X706560D01*
X703280Y463562D01*
Y447982D01*
X700260Y444962D01*
X689460D01*
X688820Y444322D01*
Y423522D01*
X687227Y421929D01*
Y417086D01*
X688810Y415503D01*
Y413642D01*
X691510Y410942D01*
Y405572D01*
X692400Y404682D01*
G01X687227Y424313D02*
X685650Y425890D01*
Y444252D01*
X687560Y446162D01*
X699690D01*
X701910Y448382D01*
Y466722D01*
X705190Y470002D01*
X719450D01*
X720280Y470832D01*
Y472272D01*
X721140Y473132D01*
X722560D01*
X723470Y474042D01*
Y475492D01*
X724250Y476272D01*
X725690D01*
X726610Y477192D01*
Y478652D01*
X727380Y479422D01*
X730040D01*
X735180Y484562D01*
X745050D01*
X755010Y494522D01*
X763530D01*
X766880Y497872D01*
X810710D01*
X817680Y490902D01*
X867070D01*
X882010Y475962D01*
X895660D01*
X900795Y481097D01*
X962625D01*
X968380Y475342D01*
X970550D01*
X992800Y497592D01*
Y514642D01*
X1002470Y524312D01*
X1072619D01*
X1078249Y518682D01*
X1275140D01*
X1306500Y550042D01*
X1334350D01*
X1377780Y593472D01*
X1405000D01*
X1453410Y641882D01*
X1463390D01*
X1465240Y643732D01*
Y647063D01*
X1465171Y647132D01*
G01X1469020Y647102D02*
Y642392D01*
X1464890Y638262D01*
X1454910D01*
X1406500Y589852D01*
X1379280D01*
X1335850Y546422D01*
X1308000D01*
X1276290Y514712D01*
X1016310D01*
X1013840Y517182D01*
X1000440D01*
X996300Y513042D01*
Y496142D01*
X972000Y471842D01*
X942860D01*
X936670Y465652D01*
X918600D01*
X917230Y464282D01*
X878420D01*
X860102Y482600D01*
X817900D01*
X816490Y481190D01*
X786845D01*
X786567Y480912D01*
X785033D01*
X784345Y481600D01*
X782121D01*
X780609Y483112D01*
X768752D01*
X767352Y481712D01*
X757090D01*
X745210Y469832D01*
X736504D01*
X736344Y469992D01*
X727470D01*
X726590Y469112D01*
Y467787D01*
X725663Y466860D01*
X724436D01*
X723475Y465899D01*
Y464672D01*
X722475Y463672D01*
X705300D01*
X704430Y462802D01*
Y447452D01*
X702200Y445222D01*
Y430300D01*
X700922Y429022D01*
X691936D01*
X690376Y427462D01*
G01X865290Y499032D02*
Y497932D01*
X863740Y496382D01*
X852322D01*
X841412Y507292D01*
X817578D01*
X814108Y503822D01*
X806122D01*
X805236Y504708D01*
X794615D01*
X793221Y506102D01*
X778309D01*
X773946Y510465D01*
X758054D01*
X744079Y496490D01*
X737328D01*
X733100Y492262D01*
X725630D01*
X712800Y479432D01*
X704750D01*
X702960Y477642D01*
Y472372D01*
X700590Y470002D01*
X695358D01*
X695082Y470278D01*
Y473151D01*
X693526Y474707D01*
G01X1085720Y522422D02*
X1078418Y529724D01*
X996382D01*
X986520Y519862D01*
Y511872D01*
X981750Y507102D01*
X954630D01*
X949970Y511762D01*
X944040D01*
X941879Y509601D01*
X914269D01*
X913780Y509112D01*
X889290D01*
X878560Y519842D01*
X843700D01*
X841588Y517730D01*
X825588D01*
X824920Y517062D01*
X818720D01*
X816520Y514862D01*
X806706D01*
X805342Y516226D01*
X792384D01*
X790220Y514062D01*
X693520D01*
X692720Y514862D01*
Y517162D01*
X690220Y519662D01*
G01X751620Y1674312D02*
X750518Y1673210D01*
X740230D01*
X733710Y1666690D01*
X719610D01*
X716630Y1669670D01*
X696480D01*
X693910Y1667100D01*
Y1618200D01*
X688500Y1612790D01*
Y1611900D01*
G01X696800Y42108D02*
X697336D01*
X699950Y44722D01*
Y49482D01*
X701160Y50692D01*
X705080D01*
X712676Y58288D01*
X715990Y66287D01*
Y69662D01*
G01X713000D02*
Y66039D01*
X710510Y63549D01*
X706900D01*
X706400Y63049D01*
Y61549D01*
X706900Y61049D01*
X710510D01*
X711010Y60549D01*
Y59384D01*
X706268Y54642D01*
X701570D01*
X696838Y49910D01*
Y47940D01*
G01X721990Y69762D02*
X716039Y55397D01*
Y53582D01*
X704659Y42202D01*
X701838D01*
G01X718900Y69662D02*
Y68378D01*
X714261Y57179D01*
X706064Y48982D01*
X702880D01*
X701838Y47940D01*
G01X703900Y72112D02*
X705000Y74770D01*
Y75042D01*
X711690Y81732D01*
X713890D01*
X715790Y79832D01*
X723350D01*
X726170Y77012D01*
X752012D01*
X764743Y89743D01*
Y103148D01*
X768595Y112447D01*
X782870Y126722D01*
X833040D01*
X860645Y154327D01*
Y193648D01*
X916839Y249842D01*
X948609D01*
X953989Y244462D01*
X1020800D01*
X1030103Y240609D01*
X1043350Y227362D01*
X1069720D01*
X1130965Y166117D01*
Y165409D01*
X1129473Y163917D01*
Y163209D01*
X1130045Y162637D01*
X1130753D01*
X1132245Y164129D01*
X1132953D01*
X1133525Y163557D01*
Y162849D01*
X1132033Y161357D01*
Y160649D01*
X1132605Y160077D01*
X1133313D01*
X1134805Y161569D01*
X1135513D01*
X1136085Y160997D01*
Y160289D01*
X1134593Y158797D01*
Y158089D01*
X1135165Y157517D01*
X1135873D01*
X1137365Y159009D01*
X1138073D01*
X1138645Y158437D01*
Y157729D01*
X1137153Y156237D01*
Y155529D01*
X1137725Y154957D01*
X1138433D01*
X1139925Y156449D01*
X1140633D01*
X1141205Y155877D01*
Y155169D01*
X1139713Y153677D01*
Y152969D01*
X1140285Y152397D01*
X1140993D01*
X1142485Y153889D01*
X1143193D01*
X1164264Y132818D01*
Y128068D01*
X1194501Y97831D01*
X1251503D01*
X1263487Y85847D01*
X1291425D01*
X1298640Y93062D01*
G01X701400Y72112D02*
Y73120D01*
X703000Y74720D01*
Y75588D01*
X710944Y83532D01*
X714670D01*
X716560Y81642D01*
X724140D01*
X726970Y78812D01*
X751266D01*
X762943Y90489D01*
Y103507D01*
X767068Y113466D01*
X782124Y128522D01*
X832294D01*
X858845Y155073D01*
Y194394D01*
X916093Y251642D01*
X949355D01*
X954735Y246262D01*
X1021159D01*
X1031157Y242121D01*
X1043816Y229462D01*
X1070620D01*
X1166064Y134018D01*
Y128814D01*
X1195137Y99741D01*
X1254435D01*
X1263414Y90762D01*
X1268020D01*
X1270705Y93447D01*
X1279635D01*
X1282820Y90262D01*
X1292820D01*
X1295920Y93362D01*
Y93386D01*
X1299896Y97362D01*
X1301620D01*
X1309220Y89762D01*
Y82162D01*
X1310320Y81062D01*
X1313620D01*
X1322906Y90348D01*
Y94212D01*
G01X707400Y396200D02*
X703300D01*
X701400Y398100D01*
Y415900D01*
X698278Y419022D01*
Y425860D01*
X696676Y427462D01*
G01X705780Y411022D02*
X708100Y413342D01*
Y429330D01*
X704430Y433000D01*
Y443842D01*
X707160Y446572D01*
X735950D01*
X740160Y450782D01*
X773820D01*
X776680Y453642D01*
Y455862D01*
X778430Y457612D01*
X789530D01*
X794070Y462152D01*
X826038D01*
X830758Y466872D01*
X867271D01*
X883035Y451108D01*
X944373D01*
X959880Y466615D01*
X974584D01*
X1002500Y494531D01*
Y500652D01*
X1008680Y506832D01*
Y512242D01*
X1007420Y513502D01*
X1005110D01*
X1004470Y512862D01*
X1003220D01*
G01X1005520Y510932D02*
X1001290D01*
X999800Y509442D01*
Y494349D01*
X973766Y468315D01*
X959174D01*
X944157Y453298D01*
X884055D01*
X868701Y468652D01*
X830020D01*
X828368Y467000D01*
X793968D01*
X789880Y462912D01*
X780080D01*
X774740Y457572D01*
Y454392D01*
X772870Y452522D01*
X739530D01*
X734930Y447922D01*
X706690D01*
X703340Y444572D01*
Y431158D01*
X704522Y429976D01*
Y413022D01*
X703330Y411830D01*
Y406942D01*
X703900Y406372D01*
X712320D01*
X712770Y406822D01*
G01X696676Y462108D02*
X698270Y463702D01*
Y466082D01*
X699030Y466842D01*
X700590D01*
X704160Y470412D01*
Y472902D01*
X707530Y476272D01*
X712450D01*
X727140Y490962D01*
X740838D01*
X758898Y509022D01*
X767560D01*
X771780Y504802D01*
X792420D01*
X794131Y503091D01*
X804731D01*
X805500Y502322D01*
X814730D01*
X818200Y505792D01*
X840790D01*
X851700Y494882D01*
X865040D01*
X868110Y497952D01*
Y499142D01*
G01X928780Y1694890D02*
X923730Y1699940D01*
Y1718800D01*
X919070Y1723460D01*
X783785D01*
X753310Y1692985D01*
Y1682635D01*
X756770Y1679175D01*
Y1671560D01*
X752210Y1667000D01*
X742800D01*
X736730Y1660930D01*
X731940D01*
X731110Y1661760D01*
X718720D01*
X705810Y1648850D01*
Y1631690D01*
X707610Y1629890D01*
X710570D01*
G01X938780Y1694890D02*
X933960Y1699710D01*
Y1718640D01*
X926740Y1725860D01*
X782790D01*
X750910Y1693980D01*
Y1681640D01*
X754370Y1678180D01*
Y1674190D01*
X749200Y1669020D01*
X738445D01*
X734415Y1664990D01*
X717657D01*
X716955Y1665692D01*
X705234D01*
X700460Y1660918D01*
G01X1005720Y498862D02*
X1005220Y498362D01*
Y491974D01*
X977861Y464615D01*
X960930D01*
X945023Y448708D01*
X882074D01*
X868830Y461952D01*
X828667D01*
X826867Y460152D01*
X824335D01*
X811663Y447480D01*
X785250D01*
X782760Y444990D01*
Y438150D01*
X780790Y436180D01*
X758510D01*
X754040Y440650D01*
X739190D01*
X738188Y441652D01*
X714830D01*
X714000Y440822D01*
Y420412D01*
X714830Y419582D01*
X726591D01*
X728172Y421163D01*
G01X725022Y424313D02*
X726601Y425892D01*
X745140D01*
X762982Y408050D01*
X767300D01*
X770880Y404470D01*
Y400577D01*
X773245Y398212D01*
G01X735220Y410842D02*
X731410D01*
X729750Y412502D01*
Y422142D01*
X729160Y422732D01*
X717800D01*
X717170Y423362D01*
Y437822D01*
X717830Y438482D01*
X736780D01*
X739182Y436080D01*
X752642D01*
X757920Y430802D01*
X769080D01*
X770410Y429472D01*
X784137D01*
X786580Y431915D01*
X786745D01*
X787112Y432282D01*
X793158D01*
X794525Y433649D01*
X799943D01*
X802540Y431052D01*
X806487D01*
X807717Y432282D01*
X807982D01*
X809910Y434210D01*
Y438809D01*
X830663Y459562D01*
X838220D01*
G01X773245Y403212D02*
Y405045D01*
X767408Y410882D01*
X764510D01*
X746340Y429052D01*
X729762D01*
X728172Y427462D01*
G01X771050Y416940D02*
Y419429D01*
X769117Y421362D01*
X764430D01*
X751912Y433880D01*
X735410D01*
X733968Y435322D01*
X720284D01*
X718723Y433761D01*
G01X773245Y408212D02*
Y409227D01*
X766930Y415542D01*
X764460D01*
X747840Y432162D01*
X726572D01*
X725022Y430612D01*
G01X787360Y469862D02*
X786152Y471070D01*
X779676D01*
X778986Y471760D01*
X763110D01*
X751249Y459899D01*
X740052D01*
X739411Y460540D01*
X730050D01*
X728469Y458959D01*
X728172D01*
G01X772365Y454862D02*
X769465Y457762D01*
X763330D01*
X759939Y454371D01*
X738779D01*
X735500Y451092D01*
X723440D01*
X721873Y452659D01*
G01X725022Y458959D02*
X723475Y460506D01*
Y462749D01*
X724437Y463711D01*
X725663D01*
X726569Y464617D01*
Y465843D01*
X727572Y466846D01*
X732636D01*
X733320Y466162D01*
X746490D01*
X758340Y478012D01*
X782983D01*
X783583Y477412D01*
X788017D01*
X788275Y477670D01*
X788276D01*
X788296Y477690D01*
X796162D01*
X798990Y474862D01*
G01X802865D02*
Y473715D01*
X800462Y471312D01*
X791742D01*
X787330Y466900D01*
X761260D01*
X752550Y458190D01*
X739920D01*
X739120Y457390D01*
X727270D01*
X725689Y455809D01*
X721873D01*
G01X772365Y459862D02*
X770115Y462112D01*
X763590D01*
X757599Y456121D01*
X734519D01*
X732610Y454212D01*
X720276D01*
X718723Y452659D01*
G01Y462108D02*
X718952D01*
X720270Y460790D01*
Y458318D01*
X721232Y457356D01*
X725646D01*
X726580Y458290D01*
Y462960D01*
X727300Y463680D01*
X746730D01*
X754370Y471320D01*
X760150D01*
X761890Y473060D01*
X779525D01*
X780215Y472370D01*
X788620D01*
X789262Y473012D01*
X799757D01*
X801015Y474270D01*
Y476135D01*
X801780Y476900D01*
X812400D01*
X816400Y472900D01*
G01X801940Y485932D02*
X799830Y488042D01*
X784488D01*
X783058Y486612D01*
X756210D01*
X745370Y475772D01*
X736140D01*
X733500Y473132D01*
X727470D01*
X726580Y472242D01*
Y470802D01*
X725760Y469982D01*
X724250D01*
X723430Y469162D01*
Y467602D01*
X722670Y466842D01*
X720999D01*
X719415Y465258D01*
X718723D01*
G01X752500Y495762D02*
X751300D01*
X743600Y488062D01*
X729400D01*
X720300Y478962D01*
Y476280D01*
X721873Y474707D01*
G01X1091880Y1673720D02*
X1090640D01*
X1077310Y1660390D01*
X954140D01*
X946090Y1668440D01*
Y1674210D01*
X942440Y1677860D01*
X915250D01*
X912520Y1680590D01*
Y1716440D01*
X907660Y1721300D01*
X784800D01*
X759225Y1695725D01*
Y1690665D01*
X761740Y1688150D01*
Y1671030D01*
X749290Y1658580D01*
X733650D01*
X727500Y1652430D01*
X726810D01*
G01X732700Y351500D02*
Y349600D01*
X733800Y348500D01*
X740100D01*
X743100Y351500D01*
X796100D01*
X797900Y353300D01*
Y354800D01*
G01X757430Y408212D02*
Y409623D01*
X744321Y422732D01*
X732891D01*
X731322Y421163D01*
G01X801750Y444330D02*
X797680D01*
X795720Y442370D01*
X785830D01*
X784800Y441340D01*
Y437361D01*
X781619Y434180D01*
X778019D01*
X777311Y433472D01*
X758148D01*
X753090Y438530D01*
X739060D01*
X737529Y440061D01*
X731322D01*
G01X752875Y1726670D02*
X746380Y1720175D01*
Y1676600D01*
X745880Y1676100D01*
X739355D01*
X732705Y1669450D01*
G01X755305Y298847D02*
X752950Y296492D01*
Y292560D01*
X755435Y290075D01*
X773687D01*
X785200Y278562D01*
X790400D01*
X794980Y283142D01*
X831100D01*
X839450Y274792D01*
Y272662D01*
G01X758390Y295450D02*
X762140Y299200D01*
X774840D01*
X776730Y301090D01*
X782250D01*
X787980Y306820D01*
X798440D01*
X806530Y314910D01*
X819050D01*
X826670Y322530D01*
X872510D01*
X899160Y295880D01*
Y257250D01*
X860050Y218140D01*
Y215310D01*
G01X996320Y1280683D02*
X997099Y1281462D01*
X998820D01*
X1001220Y1283862D01*
Y1328602D01*
X974060Y1355762D01*
X920020D01*
X884920Y1390862D01*
X836120D01*
X801620Y1425362D01*
X756320D01*
X755420Y1426262D01*
G01X996320Y1284062D02*
X997220Y1283162D01*
X998114D01*
X999520Y1284568D01*
Y1327896D01*
X973354Y1354062D01*
X919314D01*
X884214Y1389162D01*
X835414D01*
X800914Y1423662D01*
X767614D01*
X767114Y1423162D01*
Y1422248D01*
X766614Y1421748D01*
X765114D01*
X764614Y1422248D01*
Y1423162D01*
X764114Y1423662D01*
X762614D01*
X762114Y1423162D01*
Y1422248D01*
X761614Y1421748D01*
X760114D01*
X759614Y1422248D01*
Y1423162D01*
X759114Y1423662D01*
X756220D01*
X755420Y1422862D01*
G01X792943Y312642D02*
X791337Y311036D01*
X778434D01*
X769860Y302462D01*
G01X785220Y284762D02*
X790520D01*
X802420Y296662D01*
Y301762D01*
X803620Y302962D01*
G01X1144457Y227277D02*
Y225945D01*
X1143752Y225240D01*
X1136720D01*
X1115995Y245965D01*
Y293265D01*
X1086590Y322670D01*
X961593D01*
X941216Y343047D01*
X840081D01*
X813752Y316718D01*
X787399D01*
X784415Y313734D01*
G01X790120Y354862D02*
Y370562D01*
X812920Y393362D01*
X823706D01*
X833806Y403462D01*
X862203D01*
X868113Y409372D01*
G01X803620Y302962D02*
X827620D01*
G01X847580Y232222D02*
X853630Y238272D01*
X875260D01*
X892800Y255812D01*
Y299066D01*
X872414Y319452D01*
X827320D01*
X823650Y315782D01*
Y312112D01*
X823800Y311962D01*
G01X826300D02*
Y314962D01*
X828750Y317412D01*
X870042D01*
X889847Y297607D01*
Y256329D01*
X875870Y242352D01*
X850570D01*
X839660Y231442D01*
Y216142D01*
X841300Y214502D01*
Y194972D01*
X836810Y190482D01*
Y175622D01*
X837320Y175112D01*
G01X827620Y302962D02*
X830417Y305759D01*
Y311865D01*
G01X1181300Y584762D02*
X1177740Y588322D01*
X1175340D01*
X1171550Y592112D01*
X1158751D01*
X1155001Y595862D01*
X1120000D01*
X1106498Y582360D01*
X1079531D01*
X1071094Y590797D01*
X1051844D01*
X1045695Y584648D01*
X1002871D01*
X998376Y589143D01*
X957925D01*
X953685Y584903D01*
X861251D01*
X858792Y587362D01*
X828560D01*
X828009Y587913D01*
G01X1127402Y456174D02*
X1125240Y458336D01*
X957535D01*
X945815Y446616D01*
X935281D01*
X930507Y441842D01*
X881604D01*
X874948Y448498D01*
X858241D01*
X855062Y445319D01*
X851577D01*
X850610Y444352D01*
G01X927034Y445594D02*
X924683Y443243D01*
X919615D01*
X916945Y445913D01*
X881265D01*
X875498Y451680D01*
X856333D01*
X852580Y447927D01*
X851606D01*
G01X863415Y445829D02*
X874870D01*
X880214Y440485D01*
X931070D01*
X935844Y445259D01*
X946378D01*
X957251Y456132D01*
X1117820D01*
G01X970788Y501230D02*
Y499860D01*
X957975Y487047D01*
X933735D01*
X929654Y491128D01*
Y492103D01*
G01X964347Y501262D02*
Y496530D01*
X961059Y493242D01*
X938240D01*
X934420Y497062D01*
X925820D01*
X924623Y495865D01*
Y492097D01*
G01X1217210Y1684520D02*
Y1676910D01*
X1212000Y1671700D01*
X1151200D01*
X1145900Y1677000D01*
X1124900D01*
X1120041Y1681859D01*
Y1720459D01*
X1111500Y1729000D01*
X954260D01*
X945810Y1720550D01*
Y1692580D01*
X943170Y1689940D01*
X934890D01*
X933410Y1691420D01*
Y1696740D01*
X928780Y1701370D01*
Y1704890D01*
G01X960020Y264862D02*
Y263067D01*
X964925Y258162D01*
X1023536D01*
X1037908Y252209D01*
X1047755Y242362D01*
X1076222D01*
X1081018Y237566D01*
X1085828D01*
X1116445Y206949D01*
X1169133D01*
X1170620Y205462D01*
X1175490D01*
X1176930Y206902D01*
X1182240D01*
X1183200Y207862D01*
X1198970D01*
X1200830Y206002D01*
G01X963020Y264862D02*
Y262472D01*
X965630Y259862D01*
X1023877D01*
X1038871Y253651D01*
X1048460Y244062D01*
X1076927D01*
X1081723Y239266D01*
X1088938D01*
X1112104Y216100D01*
X1144023D01*
X1145485Y217562D01*
X1161300D01*
X1168300Y224562D01*
X1185650D01*
X1187125Y223087D01*
X1190025D01*
X1191200Y224262D01*
X1198110D01*
X1204800Y217572D01*
X1217430D01*
X1220220Y220362D01*
X1233220D01*
X1234220Y219362D01*
X1241720D01*
X1244720Y216362D01*
X1247220D01*
X1250220Y213362D01*
Y209862D01*
X1252410Y207672D01*
X1261030D01*
X1264874Y211516D01*
Y217462D01*
G01X957020Y264862D02*
Y263662D01*
X964220Y256462D01*
X1023197D01*
X1036944Y250768D01*
X1047050Y240662D01*
X1075516D01*
X1174866Y141312D01*
X1178570D01*
X1194720Y125162D01*
X1219520D01*
X1223120Y121562D01*
X1240020D01*
X1242720Y124262D01*
X1261320D01*
X1273510Y112072D01*
X1277410D01*
X1280015Y114677D01*
X1295135D01*
X1299620Y119162D01*
X1303020D01*
X1322420Y99762D01*
Y97562D01*
X1320620Y95762D01*
X1315944D01*
X1314059Y93877D01*
G01X972220Y386251D02*
X972027Y386058D01*
X965470D01*
X956697Y394831D01*
X956487D01*
G01X1106480Y1641275D02*
X1098030Y1649725D01*
Y1672410D01*
X1096720Y1673720D01*
X1091880D01*
G01X1223180Y210552D02*
X1218010D01*
X1212690Y215872D01*
X1199210D01*
X1197300Y213962D01*
X1165120D01*
X1163220Y215862D01*
X1146584D01*
X1145084Y214362D01*
X1123906D01*
X1118486Y208942D01*
G01X1112130Y1711600D02*
X1106470Y1705940D01*
Y1648490D01*
X1120648Y1634312D01*
Y1628350D01*
X1136911Y1612087D01*
X1139077D01*
X1145414Y1605750D01*
X1149850D01*
X1158620Y1596980D01*
Y1574260D01*
X1172300Y1560580D01*
Y1547720D01*
X1148730Y1524150D01*
X1138430D01*
G01X1112252Y1706170D02*
Y1674782D01*
X1111130Y1673660D01*
Y1648600D01*
X1124020Y1635710D01*
Y1629224D01*
X1138157Y1615087D01*
X1140323D01*
X1146430Y1608980D01*
X1151120D01*
X1165150Y1594950D01*
X1166389D01*
X1169502Y1591837D01*
Y1573268D01*
X1175672Y1567098D01*
Y1546322D01*
X1167245Y1537895D01*
Y1524187D01*
G01X1159371D02*
Y1532311D01*
X1174053Y1546993D01*
Y1566427D01*
X1167883Y1572597D01*
Y1591617D01*
X1165850Y1593650D01*
X1164450D01*
X1150520Y1607580D01*
X1145990D01*
X1139783Y1613787D01*
X1137617D01*
X1122401Y1629003D01*
Y1635039D01*
X1109471Y1647969D01*
Y1674291D01*
X1110402Y1675222D01*
Y1707202D01*
X1112200Y1709000D01*
G01X1155433Y1524187D02*
X1158540Y1521080D01*
X1173200D01*
X1180000Y1527880D01*
Y1543674D01*
X1177460Y1546214D01*
Y1592650D01*
X1175370Y1594740D01*
X1168438D01*
X1166928Y1596250D01*
X1165689D01*
X1151659Y1610280D01*
X1146970D01*
X1134900Y1622350D01*
Y1627140D01*
X1113110Y1648930D01*
Y1666460D01*
G01X1110663Y1719189D02*
Y1715797D01*
X1114149Y1712311D01*
Y1680251D01*
X1122500Y1671900D01*
X1141830D01*
X1153030Y1660700D01*
Y1645986D01*
X1141330Y1634286D01*
Y1619020D01*
X1148350Y1612000D01*
X1156795D01*
X1164642Y1604153D01*
Y1602658D01*
X1170770Y1596530D01*
X1179690D01*
X1183060Y1599900D01*
X1184200D01*
G01Y1602700D02*
X1183455D01*
X1178985Y1598230D01*
X1171475D01*
X1166342Y1603363D01*
Y1604858D01*
X1157500Y1613700D01*
X1149420D01*
X1143420Y1619700D01*
Y1633420D01*
X1155120Y1645120D01*
Y1661700D01*
X1142520Y1674300D01*
X1123200D01*
X1118612Y1678888D01*
Y1680883D01*
X1118341Y1681154D01*
Y1713403D01*
X1116018Y1715726D01*
X1114150D01*
G01X1297007Y172249D02*
X1289207D01*
X1287916Y170958D01*
X1238661D01*
X1233411Y165708D01*
X1219871D01*
X1203225Y149062D01*
X1169522D01*
X1124858Y193726D01*
Y197309D01*
G01X1309817Y175949D02*
X1306620D01*
X1306482Y175948D01*
G03X1305014Y175024I139J-1850D01*
G02X1303539Y174100I-1607J925D01*
G01X1303414Y174099D01*
G02X1301875Y174912I-7J1850D01*
G01X1301810Y175024D01*
X1301807Y175029D01*
G03X1300209Y175949I-1596J-924D01*
G01X1300210D01*
X1300098Y175948D01*
G03X1298606Y175024I113J-1850D01*
G02X1297010Y174100I-1599J922D01*
G01X1297003Y174099D01*
X1287657D01*
X1286295Y172737D01*
X1238861D01*
X1236092Y175506D01*
X1225566D01*
X1217339Y167279D01*
Y165581D01*
X1202520Y150762D01*
X1170227D01*
X1128485Y192504D01*
Y198159D01*
G01X1119200Y1727200D02*
X1123962Y1722438D01*
Y1685338D01*
X1127779Y1681521D01*
X1147879D01*
X1153500Y1675900D01*
X1203100D01*
X1215500Y1688300D01*
X1218700D01*
X1221200Y1685800D01*
Y1672999D01*
X1199700Y1651499D01*
Y1635800D01*
X1192900Y1629000D01*
Y1588200D01*
X1196700Y1584400D01*
X1385500D01*
X1389400Y1588300D01*
Y1591500D01*
X1393100Y1595200D01*
Y1638300D01*
X1396900Y1642100D01*
G01X1119300Y1724100D02*
X1121841Y1721559D01*
Y1684459D01*
X1126900Y1679400D01*
X1147200D01*
X1153000Y1673600D01*
X1203400D01*
X1216300Y1686500D01*
X1218300D01*
X1219600Y1685200D01*
Y1673900D01*
X1194850Y1649150D01*
Y1633950D01*
X1191600Y1630700D01*
Y1587661D01*
X1196161Y1583100D01*
X1386039D01*
X1393000Y1590061D01*
Y1590300D01*
G01X1158325Y1642600D02*
X1159380D01*
X1160980Y1641000D01*
Y1616510D01*
X1167840Y1609650D01*
X1170110D01*
X1175168Y1604592D01*
X1185700D01*
X1186200Y1604092D01*
Y1578464D01*
X1195002Y1569662D01*
X1382976D01*
X1391814Y1578500D01*
X1406940D01*
X1407440Y1578000D01*
Y1557552D01*
G01X1296999Y183349D02*
X1295086Y185262D01*
X1283120D01*
X1277910Y180052D01*
X1235830D01*
X1234240Y181642D01*
X1219940D01*
X1215460Y177162D01*
X1189720D01*
X1181420Y168862D01*
Y157962D01*
G01X1296999Y194449D02*
Y194783D01*
X1295420Y196362D01*
X1289020D01*
X1281020Y188362D01*
X1265380D01*
X1260380Y193362D01*
X1240620D01*
X1240420Y193562D01*
X1236920D01*
X1227600Y184242D01*
X1211800D01*
X1207980Y180422D01*
X1188240D01*
X1181700Y186962D01*
G01X1300207Y196299D02*
X1299720Y195812D01*
Y194662D01*
X1297620Y192562D01*
X1292520D01*
X1286620Y186662D01*
X1234320D01*
X1230600Y182942D01*
X1219400D01*
X1215580Y179122D01*
X1175984D01*
X1173314Y176452D01*
G01X1300207Y207399D02*
X1295783D01*
X1295220Y207962D01*
X1293020D01*
X1290258Y205200D01*
X1277665D01*
X1275924Y203459D01*
X1270977D01*
X1267380Y199862D01*
X1258220D01*
X1254720Y203362D01*
X1249720D01*
X1245420Y207662D01*
X1235520D01*
X1235352Y207830D01*
X1217222D01*
X1215190Y209862D01*
X1182530D01*
X1181470Y208802D01*
G01X1183410Y1594450D02*
X1180260Y1591300D01*
Y1568749D01*
X1182249Y1566760D01*
X1202207D01*
X1205487Y1563480D01*
X1382600D01*
G01X1183320Y1597080D02*
X1178960Y1592720D01*
Y1568210D01*
X1181710Y1565460D01*
X1201668D01*
X1205888Y1561240D01*
X1384420D01*
X1386790Y1563610D01*
G01X1183440Y1591640D02*
X1181560Y1589760D01*
Y1569288D01*
X1182788Y1568060D01*
X1202746D01*
X1205166Y1565640D01*
X1384840D01*
G01X1174550Y1615630D02*
Y1610021D01*
X1177321Y1607250D01*
X1179017D01*
X1180830Y1609063D01*
X1184707D01*
X1187900Y1605870D01*
Y1579170D01*
X1195708Y1571362D01*
X1382270D01*
X1391454Y1580546D01*
X1402146D01*
X1404800Y1583200D01*
Y1593892D01*
X1406720Y1595812D01*
Y1637896D01*
X1421197Y1652373D01*
X1430591D01*
X1435100Y1656882D01*
Y1665072D01*
X1438320Y1668292D01*
G01X1178250Y1609100D02*
X1179913Y1610763D01*
X1186217D01*
X1189700Y1607280D01*
Y1579783D01*
X1196421Y1573062D01*
X1381565D01*
X1392951Y1584448D01*
X1400848D01*
X1403000Y1586600D01*
Y1594497D01*
X1405020Y1596517D01*
Y1638693D01*
X1420420Y1654093D01*
X1429864D01*
X1433280Y1657509D01*
Y1669012D01*
X1438220Y1673955D01*
G01X1303407Y175949D02*
X1301807Y178724D01*
X1301765Y178796D01*
G03X1300206Y179649I-1558J-997D01*
G01X1300204D01*
G02X1298601Y180574I-1J1849D01*
G01X1298602D01*
G03X1297052Y181499I-1603J-925D01*
G01X1282057D01*
X1278040Y177482D01*
X1234115D01*
X1231693Y179904D01*
X1222598D01*
X1214838Y172144D01*
X1198402D01*
X1191220Y164962D01*
Y159562D01*
X1185420Y153762D01*
G01X1275493Y193962D02*
Y194089D01*
X1274720Y194862D01*
X1228220D01*
X1227220Y195862D01*
X1221720D01*
X1218720Y192862D01*
X1201720D01*
X1200408Y194174D01*
X1189722D01*
X1184510Y188962D01*
G01X1367170Y1453142D02*
X1363919D01*
X1350325Y1466736D01*
X1300286D01*
X1249334Y1517688D01*
X1187720D01*
G01X1377054Y1394028D02*
X1367954D01*
X1364120Y1397862D01*
Y1419662D01*
X1359650Y1424132D01*
Y1433302D01*
X1372380Y1446032D01*
Y1461612D01*
X1362518Y1471474D01*
X1302108D01*
X1251394Y1522188D01*
X1187830D01*
G01X1370577Y1421899D02*
X1367743D01*
X1363130Y1426512D01*
Y1431942D01*
X1375910Y1444722D01*
Y1462892D01*
X1363928Y1474874D01*
X1304248D01*
X1252434Y1526688D01*
X1187830D01*
G01X1364860Y1455172D02*
X1351596Y1468436D01*
X1301568D01*
X1249816Y1520188D01*
X1198546D01*
G01X1367436Y1414778D02*
X1365871Y1416343D01*
Y1420681D01*
X1361370Y1425182D01*
Y1432592D01*
X1374140Y1445362D01*
Y1462257D01*
X1363223Y1473174D01*
X1303438D01*
X1251924Y1524688D01*
X1198546D01*
G01X1400220Y1518862D02*
X1265220D01*
X1254720Y1529362D01*
X1198436D01*
G01X1409248Y1528862D02*
X1406820D01*
X1401220Y1523262D01*
X1264820D01*
X1256220Y1531862D01*
X1187720D01*
G01Y1563182D02*
X1196812Y1554090D01*
X1409448D01*
X1422820Y1567462D01*
X1437410D01*
X1444200Y1574252D01*
Y1633962D01*
X1441320Y1636842D01*
Y1648609D01*
X1442573Y1649862D01*
G01X1194510Y1563076D02*
Y1561600D01*
X1197280Y1558830D01*
X1392210D01*
X1396520Y1563140D01*
Y1572120D01*
X1400497Y1576097D01*
X1402536D01*
G01X1214415Y153962D02*
X1215415D01*
X1222885Y161432D01*
X1239770D01*
X1240700Y162362D01*
X1262380D01*
X1264130Y164112D01*
X1291215D01*
X1293802Y166699D01*
G01X1293798Y205833D02*
X1291865Y203900D01*
X1278204D01*
X1276192Y201888D01*
X1271246D01*
X1267720Y198362D01*
X1244920D01*
X1239460Y203822D01*
X1235250D01*
X1234010Y205062D01*
X1226920D01*
X1222167Y200309D01*
X1213720D01*
G01X1210900Y265300D02*
X1222700Y253500D01*
Y243100D01*
X1224000Y241800D01*
X1239032D01*
X1241440Y239392D01*
X1249230D01*
X1251180Y237442D01*
Y218402D01*
X1259703Y209879D01*
Y209808D01*
G01X1300220Y222199D02*
X1298383Y220362D01*
X1292720D01*
X1288720Y216362D01*
Y209862D01*
X1286180Y207322D01*
X1276180D01*
X1274720Y205862D01*
X1269220D01*
X1267970Y204612D01*
X1259470D01*
X1258410Y205672D01*
X1251410D01*
X1247720Y209362D01*
X1241220D01*
X1239120Y211462D01*
X1235120D01*
X1234600Y211982D01*
X1226000D01*
X1224670Y213312D01*
X1219060D01*
G01X1278183Y201262D02*
X1273783Y196862D01*
X1241220D01*
X1236620Y201462D01*
X1236410D01*
G01X1273093Y213962D02*
X1274091Y214960D01*
Y225991D01*
X1260220Y239862D01*
Y248102D01*
X1258250Y250072D01*
X1252660D01*
X1249350Y246762D01*
X1242070D01*
X1240500Y248332D01*
G01X1275727Y209597D02*
X1273462Y211862D01*
X1271120D01*
X1268220Y214762D01*
Y216862D01*
X1258920Y226162D01*
Y244332D01*
X1257930Y245322D01*
X1255690D01*
X1254700Y244332D01*
X1240500D01*
G01X1770220Y382952D02*
X1780720Y372452D01*
Y338357D01*
X1776125Y333762D01*
X1719315D01*
X1715515Y337562D01*
X1443815D01*
X1427520Y321267D01*
Y288757D01*
X1411890Y273127D01*
Y234160D01*
X1409336Y231606D01*
X1404780D01*
X1402140Y228966D01*
Y225462D01*
X1398660Y221982D01*
X1393500D01*
X1388620Y217102D01*
X1364240D01*
X1355290Y226052D01*
Y244572D01*
X1340600Y259262D01*
Y266820D01*
X1327680Y279740D01*
X1305122D01*
X1298013Y286849D01*
Y308047D01*
X1293198Y312862D01*
X1291500D01*
G01X1770220Y377452D02*
X1779020Y368652D01*
Y360340D01*
X1778520Y359840D01*
X1776701D01*
X1776201Y359340D01*
Y357840D01*
X1776701Y357340D01*
X1778520D01*
X1779020Y356840D01*
Y355340D01*
X1778520Y354840D01*
X1776701D01*
X1776201Y354340D01*
Y352840D01*
X1776701Y352340D01*
X1778520D01*
X1779020Y351840D01*
Y339062D01*
X1775420Y335462D01*
X1720020D01*
X1716220Y339262D01*
X1443110D01*
X1425820Y321972D01*
Y289462D01*
X1410190Y273832D01*
Y234865D01*
X1408631Y233306D01*
X1404075D01*
X1400440Y229671D01*
Y226167D01*
X1397955Y223682D01*
X1392795D01*
X1387915Y218802D01*
X1364945D01*
X1356990Y226757D01*
Y246472D01*
X1342600Y260862D01*
Y267680D01*
X1328480Y281800D01*
X1306326D01*
X1303764Y284362D01*
Y285798D01*
X1300333Y289229D01*
Y308133D01*
X1293104Y315362D01*
X1291500D01*
G01X1474660Y252878D02*
X1470104Y248322D01*
X1438800D01*
X1419320Y228842D01*
X1413460D01*
X1408720Y224102D01*
X1405180D01*
X1400990Y219912D01*
X1395500D01*
X1363380Y187792D01*
Y159322D01*
X1359516Y155458D01*
X1355961D01*
G01X1703306Y550064D02*
X1713466D01*
X1725871Y562469D01*
X1751107D01*
X1764871Y576233D01*
Y638629D01*
X1827630Y701388D01*
Y1315024D01*
X1714773Y1427881D01*
Y1456309D01*
X1675620Y1495462D01*
X1612020D01*
X1591906Y1515576D01*
X1537218D01*
X1531350Y1509708D01*
X1392416D01*
X1384976Y1502268D01*
Y1434578D01*
X1379035Y1428637D01*
X1365235D01*
G01X1674651Y1506721D02*
X1607060D01*
X1594256Y1519525D01*
X1535823D01*
X1530106Y1513808D01*
X1390716D01*
X1380876Y1503968D01*
Y1436938D01*
X1377653Y1433715D01*
X1370250D01*
G01X1367620Y1431472D02*
X1378970D01*
X1382926Y1435428D01*
Y1503118D01*
X1391566Y1511758D01*
X1530956D01*
X1536824Y1517626D01*
X1592456D01*
X1610820Y1499262D01*
X1674420D01*
X1716473Y1457209D01*
Y1428587D01*
X1829805Y1315255D01*
X1833320Y1306769D01*
Y704178D01*
X1766921Y637779D01*
Y575383D01*
X1751957Y560419D01*
X1726721D01*
X1711734Y545432D01*
X1709680D01*
G01X1387068Y1413991D02*
X1390343D01*
X1391067Y1414715D01*
Y1419895D01*
X1387780Y1423182D01*
Y1426032D01*
X1392057Y1430309D01*
Y1440135D01*
X1396247Y1444325D01*
Y1453175D01*
X1443487Y1500415D01*
X1545417D01*
X1554137Y1509135D01*
X1595220D01*
G01X1774274Y50742D02*
X1776204Y48812D01*
X1787350D01*
X1802050Y63512D01*
Y140298D01*
X1782866Y159482D01*
X1730571D01*
X1719501Y170552D01*
X1705678D01*
X1702959Y173271D01*
Y181312D01*
X1677582Y206689D01*
X1669683D01*
X1651460Y224912D01*
Y243673D01*
X1567591Y327542D01*
X1451220D01*
X1436270Y312592D01*
G01X1776710Y53562D02*
X1777670Y52602D01*
X1787350D01*
X1799550Y64802D01*
Y139262D01*
X1781830Y156982D01*
X1729528D01*
X1717810Y168700D01*
X1704189D01*
X1700459Y172430D01*
Y180276D01*
X1676546Y204189D01*
X1668647D01*
X1648960Y223876D01*
Y242637D01*
X1566555Y325042D01*
X1451970D01*
X1436335Y309407D01*
G01X1754120Y171562D02*
X1750020Y167462D01*
X1740661D01*
X1726738Y181385D01*
X1713888D01*
X1681173Y214100D01*
Y223330D01*
X1646223Y258280D01*
Y300190D01*
X1612318Y334095D01*
X1445252D01*
X1432287Y321130D01*
Y309894D01*
X1436319Y305862D01*
X1436320D01*
G01X1750920Y171662D02*
X1748620Y169362D01*
X1741260D01*
X1727470Y183152D01*
X1714620D01*
X1682940Y214832D01*
Y224062D01*
X1647990Y259012D01*
Y300922D01*
X1613050Y335862D01*
X1444520D01*
X1430520Y321862D01*
Y307602D01*
X1434760Y303362D01*
X1436320D01*
G01X1769274Y50742D02*
Y49598D01*
X1773670Y45202D01*
X1789910D01*
X1806680Y61972D01*
Y142217D01*
X1784785Y164112D01*
X1740178D01*
X1725060Y179230D01*
X1711590D01*
X1679501Y211319D01*
X1671602D01*
X1656090Y226831D01*
Y245592D01*
X1569510Y332172D01*
X1448934D01*
X1438114Y321352D01*
X1436050D01*
G01X1771774Y53682D02*
Y49748D01*
X1774520Y47002D01*
X1788750D01*
X1804180Y62432D01*
Y141181D01*
X1783749Y161612D01*
X1731454D01*
X1720524Y172542D01*
X1708471D01*
X1705089Y175924D01*
Y182195D01*
X1678465Y208819D01*
X1670566D01*
X1653590Y225795D01*
Y244556D01*
X1568474Y329672D01*
X1449210D01*
X1437810Y318272D01*
X1436120D01*
G01X1640812Y1270020D02*
X1639687Y1271145D01*
X1604011D01*
X1590021Y1257155D01*
Y1241473D01*
X1569533Y1220985D01*
Y1198675D01*
X1529036Y1158178D01*
Y1139783D01*
X1519016Y1129763D01*
X1518324Y1129404D01*
G02X1517108Y1129687I-170J2023D01*
G03X1515431Y1129728I-875J-1458D01*
G01X1515180Y1129595D01*
G03X1514208Y1128188I882J-1649D01*
G01X1514206Y1127959D01*
X1514204Y1127775D01*
G02X1513282Y1126356I-1854J195D01*
G01X1513073Y1126236D01*
G03X1512334Y1124696I1140J-1494D01*
G02X1511672Y1123219I-1880J-44D01*
G01X1511341Y1123027D01*
G02X1509528Y1123049I-887J1624D01*
G03X1507678I-925J-1602D01*
G02X1505828I-925J1602D01*
G01X1505775Y1123080D01*
G03X1503978Y1123049I-871J-1633D01*
G01X1503979D01*
G02X1502129I-925J1602D01*
G01X1502128D01*
G03X1500278I-925J-1602D01*
G03X1499354Y1121485I926J-1602D01*
G01Y1121447D01*
G02X1498429Y1119846I-1848J0D01*
G01X1498428Y1119845D01*
X1498375Y1119814D01*
G02X1496578Y1119845I-871J1633D01*
G03X1494728I-925J-1602D01*
G01X1494675Y1119814D01*
G02X1492878Y1119845I-871J1633D01*
G03X1491028I-925J-1602D01*
G01X1490975Y1119814D01*
G02X1489178Y1119845I-871J1633D01*
G03X1487328I-925J-1602D01*
G01X1487275Y1119814D01*
G02X1485478Y1119845I-871J1633D01*
G03X1483628I-925J-1602D01*
G01X1483575Y1119814D01*
G02X1481778Y1119845I-871J1633D01*
G03X1479928I-925J-1602D01*
G01X1479875Y1119814D01*
G02X1478078Y1119845I-871J1633D01*
G03X1476228I-925J-1602D01*
G01X1476175Y1119814D01*
G02X1474378Y1119845I-871J1633D01*
G03X1472528I-925J-1602D01*
G01X1472490Y1119823D01*
G02X1470679Y1119845I-886J1624D01*
G03X1468829I-925J-1602D01*
G01X1468791Y1119823D01*
G02X1466978Y1119845I-887J1624D01*
G03X1465128I-925J-1602D01*
G01X1465075Y1119814D01*
G02X1463278Y1119845I-871J1633D01*
G01X1463279D01*
G03X1461429I-925J-1602D01*
G01X1461428D01*
X1461409Y1119834D01*
G03X1460503Y1118243I944J-1591D01*
G02X1459597Y1116652I-1850J0D01*
G01X1459578Y1116641D01*
G03X1458654Y1115077I926J-1602D01*
G01Y1115039D01*
G02X1457784Y1113470I-1850J0D01*
G01X1457728Y1113437D01*
G03X1456803Y1111887I925J-1603D01*
G01Y1111834D01*
G03X1457709Y1110243I1850J0D01*
G01X1457728Y1110232D01*
X1457770Y1110207D01*
G02X1458654Y1108630I-965J-1577D01*
G01Y1108592D01*
G03X1459578Y1107028I1850J38D01*
G01X1459597Y1107017D01*
G02X1460503Y1105426I-944J-1591D01*
G01Y1105373D01*
G02X1459578Y1103823I-1850J53D01*
G03X1458654Y1102259I926J-1602D01*
G01Y1102221D01*
G02X1457770Y1100644I-1849J0D01*
G01X1457728Y1100619D01*
X1457709Y1100608D01*
G03X1456803Y1099017I944J-1591D01*
G02X1455897Y1097426I-1850J0D01*
G01X1455878Y1097415D01*
G03X1454954Y1095870I925J-1602D01*
G01Y1095813D01*
G02X1454070Y1094236I-1849J0D01*
G01X1454028Y1094211D01*
G03X1453103Y1092661I925J-1603D01*
G01Y1092608D01*
G02X1452197Y1091017I-1850J0D01*
G01X1452178Y1091006D01*
G03X1451254Y1089442I926J-1602D01*
G01Y1089366D01*
G03X1452178Y1087802I1850J38D01*
G01Y1087801D01*
G02X1453103Y1086200I-924J-1602D01*
G01Y1086147D01*
G02X1452178Y1084597I-1850J53D01*
G02X1450332I-923J1599D01*
G01X1450329Y1084598D01*
X1450328Y1084597D01*
X1450275Y1084628D01*
G03X1448478Y1084597I-871J-1633D01*
G03X1447554Y1082996I925J-1601D01*
G01Y1082995D01*
G02X1446670Y1081418I-1849J0D01*
G01X1446628Y1081393D01*
X1446609Y1081382D01*
G03X1445703Y1079791I944J-1591D01*
G02X1444797Y1078200I-1850J0D01*
G01X1444778Y1078189D01*
X1444779D01*
X1442004Y1076587D01*
G01X1638277Y1269065D02*
X1631441D01*
X1630611Y1268235D01*
X1628751D01*
X1627921Y1269065D01*
X1619329D01*
X1618859Y1268595D01*
Y1267425D01*
X1618389Y1266955D01*
X1616749D01*
X1616279Y1267425D01*
Y1268595D01*
X1615809Y1269065D01*
X1614169D01*
X1613699Y1268595D01*
Y1267085D01*
X1613229Y1266615D01*
X1611589D01*
X1611119Y1267085D01*
Y1268595D01*
X1610649Y1269065D01*
X1604627D01*
X1591927Y1256365D01*
Y1240683D01*
X1571439Y1220195D01*
Y1197885D01*
X1530942Y1157388D01*
Y1135469D01*
X1522200Y1126727D01*
X1521796D01*
G03X1520838Y1126467I0J-1893D01*
G01X1520449Y1126239D01*
G02X1518896Y1126421I-569J1861D01*
G03X1517513Y1126647I-984J-1680D01*
G01X1516987Y1126343D01*
Y1126344D01*
G03X1516062Y1124742I925J-1602D01*
G01Y1124684D01*
G02X1515138Y1123139I-1849J57D01*
G01X1514851Y1122973D01*
G03X1514183Y1121491I1211J-1437D01*
G01Y1121492D01*
G02X1513271Y1119871I-1822J-42D01*
G01X1513228Y1119845D01*
G02X1511378I-925J1602D01*
G03X1509528I-925J-1602D01*
G02X1507678I-925J1602D01*
G03X1505828I-925J-1602D01*
G01X1505775Y1119814D01*
G02X1503978Y1119845I-871J1633D01*
G01X1503979D01*
G03X1502129I-925J-1602D01*
G01X1502128D01*
X1502109Y1119834D01*
G03X1501203Y1118243I944J-1591D01*
G02X1500278Y1116642I-1848J0D01*
G01Y1116641D01*
G02X1498428I-925J1602D01*
G03X1496578I-925J-1602D01*
G02X1494728I-925J1602D01*
G01X1494675Y1116672D01*
G03X1492878Y1116641I-871J-1633D01*
G02X1491028I-925J1602D01*
G03X1489178I-925J-1602D01*
G02X1487328I-925J1602D01*
G03X1485478I-925J-1602D01*
G02X1483628I-925J1602D01*
G01X1483575Y1116672D01*
G03X1481778Y1116641I-871J-1633D01*
G02X1479928I-925J1602D01*
G01X1479875Y1116672D01*
G03X1478078Y1116641I-871J-1633D01*
G02X1476228I-925J1602D01*
G03X1474378I-925J-1602D01*
G03X1473454Y1115096I925J-1602D01*
G01Y1115039D01*
G02X1472548Y1113448I-1850J0D01*
G01X1472491Y1113415D01*
G02X1470678Y1113437I-887J1624D01*
G01X1470679D01*
G03X1468829I-925J-1603D01*
G01X1468828D01*
G03X1467903Y1111887I925J-1603D01*
G01Y1111834D01*
G02X1466997Y1110243I-1850J0D01*
G01X1466978Y1110232D01*
G03X1466054Y1108668I926J-1602D01*
G01Y1108630D01*
G02X1465170Y1107053I-1849J0D01*
G01X1465128Y1107028D01*
X1465109Y1107017D01*
G03X1464203Y1105426I944J-1591D01*
G01Y1105425D01*
G02X1463278Y1103823I-1850J0D01*
G03X1462354Y1102278I925J-1602D01*
G01Y1102221D01*
G02X1461448Y1100630I-1850J0D01*
G01X1461410Y1100608D01*
G03X1460504Y1099017I944J-1591D01*
G02X1459580Y1097417I-1847J0D01*
G01X1459578Y1097415D01*
G03X1458654Y1095851I926J-1602D01*
G01Y1095812D01*
G03X1459578Y1094211I1849J0D01*
G02X1460503Y1092661I-925J-1603D01*
G01Y1092608D01*
G02X1459597Y1091017I-1850J0D01*
G01X1459578Y1091006D01*
G03X1458654Y1089442I926J-1602D01*
G01Y1089404D01*
G02X1457748Y1087813I-1850J0D01*
G01X1457710Y1087791D01*
G03X1456804Y1086200I944J-1591D01*
G02X1455905Y1084613I-1850J0D01*
G01X1455878Y1084597D01*
G03X1454954Y1083033I926J-1602D01*
G01Y1082995D01*
G02X1454048Y1081404I-1850J0D01*
G01X1454010Y1081382D01*
G03X1453104Y1079791I944J-1591D01*
G02X1452234Y1078222I-1850J0D01*
G01X1452178Y1078189D01*
X1451254Y1076625D01*
Y1076587D01*
X1451253Y1073383D01*
G01X1604240Y238242D02*
X1602220Y240262D01*
X1590030D01*
X1572930Y257362D01*
X1564020D01*
X1551780Y269602D01*
X1501060D01*
X1489720Y258262D01*
X1473290D01*
X1471690Y259862D01*
G01X1485320Y260362D02*
Y266862D01*
X1481520Y270662D01*
X1467820D01*
X1463330Y266172D01*
Y264060D01*
G01X1604240Y227892D02*
X1602530Y229602D01*
X1565400D01*
X1550850Y244152D01*
X1512920D01*
X1511360Y245712D01*
X1504130D01*
X1498830Y240412D01*
X1493120D01*
G01X1478320Y1522962D02*
X1478830Y1522452D01*
X1483110D01*
X1483610Y1521952D01*
Y1517512D01*
X1484110Y1517012D01*
X1485610D01*
X1486110Y1517512D01*
Y1521952D01*
X1486610Y1522452D01*
X1595050D01*
X1608142Y1509360D01*
X1681132D01*
X1685820Y1504672D01*
Y1497432D01*
X1720883Y1462369D01*
Y1430265D01*
X1833916Y1317232D01*
X1837740Y1308000D01*
Y702047D01*
X1772160Y636467D01*
Y554032D01*
X1766060Y547932D01*
Y539042D01*
G01X1768560D02*
X1784040Y554522D01*
Y611380D01*
X1782840Y612580D01*
Y643062D01*
X1840270Y700492D01*
Y1308463D01*
X1836057Y1318634D01*
X1723390Y1431301D01*
Y1463729D01*
X1688650Y1498469D01*
Y1506270D01*
X1679700Y1515220D01*
X1606271D01*
X1595471Y1526020D01*
X1483688D01*
X1482830Y1525162D01*
G01X1536310Y47492D02*
Y29572D01*
X1556220Y9662D01*
X1600820D01*
X1609120Y17962D01*
X1614120D01*
X1625320Y6762D01*
X1725020D01*
X1739320Y21062D01*
Y33862D01*
X1714950Y58232D01*
Y69172D01*
X1715962Y70184D01*
Y83890D01*
X1705820Y94032D01*
Y127362D01*
X1717120Y138662D01*
X1729420D01*
X1738320Y147562D01*
X1748465D01*
G01X1552960Y124359D02*
X1541624Y113023D01*
Y72552D01*
X1544010Y70166D01*
Y27552D01*
G01X1603530Y202402D02*
X1609073Y207945D01*
Y210735D01*
X1609573Y211235D01*
Y252045D01*
X1602744Y258874D01*
X1596958D01*
X1568723Y287109D01*
Y305777D01*
X1572396Y309450D01*
G01X1603747Y192951D02*
X1612295Y201499D01*
Y253173D01*
X1603872Y261596D01*
X1598086D01*
X1571445Y288237D01*
Y304849D01*
X1573246Y306650D01*
G01X1680720Y1487062D02*
X1677370Y1490412D01*
X1613943D01*
X1595220Y1509135D01*
G01X1621920Y25962D02*
Y14162D01*
X1628020Y8062D01*
X1649320D01*
X1658920Y17662D01*
X1666820D01*
X1676220Y8262D01*
X1724398D01*
X1737820Y21684D01*
Y33240D01*
X1713650Y57410D01*
Y69742D01*
X1714662Y70754D01*
Y83068D01*
X1704320Y93410D01*
Y127984D01*
X1716498Y140162D01*
X1728798D01*
X1738520Y149884D01*
Y151362D01*
G01X1730765D02*
Y151343D01*
X1726052Y146630D01*
X1711759D01*
X1699220Y134091D01*
Y87946D01*
X1709962Y77204D01*
Y72914D01*
X1708950Y71902D01*
Y62892D01*
X1701120Y55062D01*
X1627920D01*
X1622720Y49862D01*
X1622220D01*
G01X1685270Y1494442D02*
X1683230Y1496482D01*
Y1503652D01*
X1680161Y1506721D01*
X1674651D01*
G01X1709356Y541144D02*
X1709694Y541482D01*
X1713170D01*
X1716270Y544582D01*
Y547282D01*
X1727508Y558520D01*
X1752744D01*
X1768820Y574596D01*
Y636992D01*
X1835200Y703372D01*
Y1307222D01*
X1831634Y1315832D01*
X1718173Y1429293D01*
Y1461539D01*
X1685270Y1494442D01*
G01X1714589Y21562D02*
Y30531D01*
X1718820Y34762D01*
Y47762D01*
X1710650Y55932D01*
Y71122D01*
X1711662Y72134D01*
Y78333D01*
X1701220Y88775D01*
Y133262D01*
X1712808Y144850D01*
X1729101D01*
X1733920Y149669D01*
Y151362D01*
G01X1707220Y15662D02*
Y15362D01*
X1712920Y9662D01*
X1723818D01*
X1736420Y22264D01*
Y32660D01*
X1712350Y56730D01*
Y70352D01*
X1713362Y71364D01*
Y82388D01*
X1702920Y92830D01*
Y128564D01*
X1715918Y141562D01*
X1728218D01*
X1736120Y149464D01*
Y152762D01*
X1737620Y154262D01*
X1744520D01*
X1751220Y147562D01*
G01X1907608Y1001506D02*
Y1296142D01*
X1906642Y1297108D01*
X1898654D01*
X1897608Y1296062D01*
Y1001506D01*
G54D16*
X559236Y1441207D03*
X688500Y1611900D03*
X1099970Y1702570D03*
G54D26*
G01X-6350Y-464479D02*
Y-539479D01*
X493650D01*
Y-464479D01*
X-6350D01*
G01X5650Y-529479D02*
Y-534479D01*
G01X4193Y-529479D02*
X7107D01*
G01X12017Y-534479D02*
X9483D01*
Y-529479D01*
X12017D01*
G01X11003Y-531896D02*
X9483D01*
G01X14583Y-529479D02*
Y-534479D01*
X17117D01*
G01X20950Y-534646D02*
X20823Y-534562D01*
Y-534396D01*
X20950Y-534312D01*
X21077Y-534396D01*
Y-534562D01*
X20950Y-534646D01*
G01Y-532396D02*
X20823Y-532312D01*
Y-532146D01*
X20950Y-532062D01*
X21077Y-532146D01*
Y-532312D01*
X20950Y-532396D01*
G01X25733Y-536146D02*
X25100Y-535312D01*
X24783Y-534479D01*
Y-531146D01*
X25100Y-530312D01*
X25733Y-529479D01*
G01X31150D02*
X30643Y-529646D01*
X30263Y-530062D01*
X30010Y-530562D01*
X29820Y-531229D01*
X29757Y-531979D01*
X29820Y-532729D01*
X30010Y-533396D01*
X30263Y-533896D01*
X30643Y-534312D01*
X31150Y-534479D01*
X31657Y-534312D01*
X32037Y-533896D01*
X32290Y-533396D01*
X32480Y-532729D01*
X32543Y-531979D01*
X32480Y-531229D01*
X32290Y-530562D01*
X32037Y-530062D01*
X31657Y-529646D01*
X31150Y-529479D01*
G01X34857Y-533479D02*
X35237Y-534062D01*
X35743Y-534396D01*
X36313Y-534479D01*
X36820Y-534396D01*
X37327Y-533979D01*
X37643Y-533479D01*
X37707Y-532979D01*
X37580Y-532396D01*
X37137Y-531979D01*
X36693Y-531812D01*
X36123D01*
G01X36693D02*
X37073Y-531562D01*
X37390Y-531146D01*
X37517Y-530646D01*
X37390Y-530146D01*
X37073Y-529729D01*
X36503Y-529479D01*
X35933Y-529562D01*
X35363Y-529896D01*
G01X41667Y-536146D02*
X42300Y-535312D01*
X42617Y-534479D01*
Y-531146D01*
X42300Y-530312D01*
X41667Y-529479D01*
G01X45057Y-533479D02*
X45437Y-534062D01*
X45943Y-534396D01*
X46513Y-534479D01*
X47020Y-534396D01*
X47527Y-533979D01*
X47843Y-533479D01*
X47907Y-532979D01*
X47780Y-532396D01*
X47337Y-531979D01*
X46893Y-531812D01*
X46323D01*
G01X46893D02*
X47273Y-531562D01*
X47590Y-531146D01*
X47717Y-530646D01*
X47590Y-530146D01*
X47273Y-529729D01*
X46703Y-529479D01*
X46133Y-529562D01*
X45563Y-529896D01*
G01X50347Y-530312D02*
X50727Y-529812D01*
X51170Y-529562D01*
X51677Y-529479D01*
X52310Y-529646D01*
X52753Y-530062D01*
X52880Y-530562D01*
X52817Y-531062D01*
X52563Y-531479D01*
X51297Y-532312D01*
X50727Y-532896D01*
X50347Y-533729D01*
X50220Y-534479D01*
X52880D01*
G01X56523D02*
X56650Y-533396D01*
X56840Y-532479D01*
X57093Y-531646D01*
X57410Y-530729D01*
X57917Y-529479D01*
X55383D01*
G01X60927Y-532812D02*
X62573D01*
G01X65647Y-530312D02*
X66027Y-529812D01*
X66470Y-529562D01*
X66977Y-529479D01*
X67610Y-529646D01*
X68053Y-530062D01*
X68180Y-530562D01*
X68117Y-531062D01*
X67863Y-531479D01*
X66597Y-532312D01*
X66027Y-532896D01*
X65647Y-533729D01*
X65520Y-534479D01*
X68180D01*
G01X70557Y-533479D02*
X70937Y-534062D01*
X71443Y-534396D01*
X72013Y-534479D01*
X72520Y-534396D01*
X73027Y-533979D01*
X73343Y-533479D01*
X73407Y-532979D01*
X73280Y-532396D01*
X72837Y-531979D01*
X72393Y-531812D01*
X71823D01*
G01X72393D02*
X72773Y-531562D01*
X73090Y-531146D01*
X73217Y-530646D01*
X73090Y-530146D01*
X72773Y-529729D01*
X72203Y-529479D01*
X71633Y-529562D01*
X71063Y-529896D01*
G01X77810Y-534479D02*
Y-529479D01*
X75467Y-533062D01*
X78633D01*
G01X80757Y-533729D02*
X81137Y-534146D01*
X81580Y-534396D01*
X82150Y-534479D01*
X82720Y-534312D01*
X83163Y-533979D01*
X83480Y-533396D01*
X83543Y-532729D01*
X83417Y-532062D01*
X83100Y-531646D01*
X82657Y-531312D01*
X82213Y-531229D01*
X81770Y-531312D01*
X81200Y-531646D01*
X81390Y-529479D01*
X83100D01*
G01X91147Y-534479D02*
Y-529479D01*
X93553D01*
G01X92667Y-531896D02*
X91147D01*
G01X95867Y-534479D02*
X97450Y-529479D01*
X99033Y-534479D01*
G01X98463Y-532729D02*
X96437D01*
G01X101220Y-534479D02*
X103880Y-529479D01*
G01X101220D02*
X103880Y-534479D01*
G01X107650Y-534646D02*
X107523Y-534562D01*
Y-534396D01*
X107650Y-534312D01*
X107777Y-534396D01*
Y-534562D01*
X107650Y-534646D01*
G01Y-532396D02*
X107523Y-532312D01*
Y-532146D01*
X107650Y-532062D01*
X107777Y-532146D01*
Y-532312D01*
X107650Y-532396D01*
G01X112433Y-536146D02*
X111800Y-535312D01*
X111483Y-534479D01*
Y-531146D01*
X111800Y-530312D01*
X112433Y-529479D01*
G01X117850D02*
X117343Y-529646D01*
X116963Y-530062D01*
X116710Y-530562D01*
X116520Y-531229D01*
X116457Y-531979D01*
X116520Y-532729D01*
X116710Y-533396D01*
X116963Y-533896D01*
X117343Y-534312D01*
X117850Y-534479D01*
X118357Y-534312D01*
X118737Y-533896D01*
X118990Y-533396D01*
X119180Y-532729D01*
X119243Y-531979D01*
X119180Y-531229D01*
X118990Y-530562D01*
X118737Y-530062D01*
X118357Y-529646D01*
X117850Y-529479D01*
G01X121557Y-533479D02*
X121937Y-534062D01*
X122443Y-534396D01*
X123013Y-534479D01*
X123520Y-534396D01*
X124027Y-533979D01*
X124343Y-533479D01*
X124407Y-532979D01*
X124280Y-532396D01*
X123837Y-531979D01*
X123393Y-531812D01*
X122823D01*
G01X123393D02*
X123773Y-531562D01*
X124090Y-531146D01*
X124217Y-530646D01*
X124090Y-530146D01*
X123773Y-529729D01*
X123203Y-529479D01*
X122633Y-529562D01*
X122063Y-529896D01*
G01X128367Y-536146D02*
X129000Y-535312D01*
X129317Y-534479D01*
Y-531146D01*
X129000Y-530312D01*
X128367Y-529479D01*
G01X131757Y-533479D02*
X132137Y-534062D01*
X132643Y-534396D01*
X133213Y-534479D01*
X133720Y-534396D01*
X134227Y-533979D01*
X134543Y-533479D01*
X134607Y-532979D01*
X134480Y-532396D01*
X134037Y-531979D01*
X133593Y-531812D01*
X133023D01*
G01X133593D02*
X133973Y-531562D01*
X134290Y-531146D01*
X134417Y-530646D01*
X134290Y-530146D01*
X133973Y-529729D01*
X133403Y-529479D01*
X132833Y-529562D01*
X132263Y-529896D01*
G01X137173Y-533896D02*
X137617Y-534312D01*
X138123Y-534479D01*
X138630Y-534312D01*
X139073Y-533812D01*
X139390Y-533062D01*
X139517Y-532312D01*
Y-531396D01*
X139390Y-530646D01*
X139073Y-529979D01*
X138693Y-529646D01*
X138250Y-529479D01*
X137743Y-529646D01*
X137363Y-529979D01*
X137110Y-530479D01*
X136983Y-531146D01*
X137110Y-531729D01*
X137427Y-532312D01*
X137807Y-532646D01*
X138250Y-532729D01*
X138757Y-532562D01*
X139137Y-532146D01*
X139517Y-531396D01*
G01X143223Y-534479D02*
X143350Y-533396D01*
X143540Y-532479D01*
X143793Y-531646D01*
X144110Y-530729D01*
X144617Y-529479D01*
X142083D01*
G01X147627Y-532812D02*
X149273D01*
G01X152157Y-533479D02*
X152537Y-534062D01*
X153043Y-534396D01*
X153613Y-534479D01*
X154120Y-534396D01*
X154627Y-533979D01*
X154943Y-533479D01*
X155007Y-532979D01*
X154880Y-532396D01*
X154437Y-531979D01*
X153993Y-531812D01*
X153423D01*
G01X153993D02*
X154373Y-531562D01*
X154690Y-531146D01*
X154817Y-530646D01*
X154690Y-530146D01*
X154373Y-529729D01*
X153803Y-529479D01*
X153233Y-529562D01*
X152663Y-529896D01*
G01X157447Y-532396D02*
X157890Y-531812D01*
X158270Y-531479D01*
X158777Y-531312D01*
X159220Y-531479D01*
X159537Y-531812D01*
X159790Y-532312D01*
X159853Y-532896D01*
X159790Y-533396D01*
X159537Y-533896D01*
X159157Y-534312D01*
X158713Y-534479D01*
X158207Y-534312D01*
X157763Y-533812D01*
X157510Y-533062D01*
X157447Y-532229D01*
X157573Y-531146D01*
X157763Y-530562D01*
X158080Y-529979D01*
X158523Y-529562D01*
X158967Y-529479D01*
X159410Y-529646D01*
X159727Y-530062D01*
G01X163750Y-534479D02*
Y-529479D01*
X162990Y-530479D01*
G01Y-534479D02*
X164510D01*
G01X169610D02*
Y-529479D01*
X167267Y-533062D01*
X170433D01*
G01X188650Y-464479D02*
Y-539479D01*
G01Y-514479D02*
X291650D01*
Y-489479D01*
G01X188650D02*
X291650D01*
G01Y-464479D02*
Y-539479D01*
G01X293650Y-464479D02*
Y-539479D01*
G01X299157Y-524479D02*
Y-519479D01*
X300423D01*
X300930Y-519729D01*
X301310Y-520062D01*
X301627Y-520562D01*
X301880Y-521146D01*
X301943Y-521979D01*
X301880Y-522812D01*
X301627Y-523396D01*
X301310Y-523896D01*
X300930Y-524229D01*
X300423Y-524479D01*
X299157D01*
G01X304067D02*
X305650Y-519479D01*
X307233Y-524479D01*
G01X306663Y-522729D02*
X304637D01*
G01X310750Y-519479D02*
Y-524479D01*
G01X309293Y-519479D02*
X312207D01*
G01X317117Y-524479D02*
X314583D01*
Y-519479D01*
X317117D01*
G01X316103Y-521896D02*
X314583D01*
G01X320950Y-524646D02*
X320823Y-524562D01*
Y-524396D01*
X320950Y-524312D01*
X321077Y-524396D01*
Y-524562D01*
X320950Y-524646D01*
G01Y-522396D02*
X320823Y-522312D01*
Y-522146D01*
X320950Y-522062D01*
X321077Y-522146D01*
Y-522312D01*
X320950Y-522396D01*
G01X299283Y-499479D02*
Y-494479D01*
X300803D01*
X301310Y-494729D01*
X301690Y-495312D01*
X301817Y-495979D01*
X301690Y-496646D01*
X301373Y-497146D01*
X300803Y-497396D01*
X299283D01*
G01X304510Y-499646D02*
X306790Y-494479D01*
G01X309293Y-499479D02*
Y-494479D01*
X312207Y-499479D01*
Y-494479D01*
G01X315850Y-499646D02*
X315723Y-499562D01*
Y-499396D01*
X315850Y-499312D01*
X315977Y-499396D01*
Y-499562D01*
X315850Y-499646D01*
G01Y-497396D02*
X315723Y-497312D01*
Y-497146D01*
X315850Y-497062D01*
X315977Y-497146D01*
Y-497312D01*
X315850Y-497396D01*
G01X293650Y-514479D02*
X493650D01*
G01X293650Y-489479D02*
X493650D01*
G01X299283Y-474479D02*
Y-469479D01*
X300803D01*
X301310Y-469729D01*
X301690Y-470312D01*
X301817Y-470979D01*
X301690Y-471646D01*
X301373Y-472146D01*
X300803Y-472396D01*
X299283D01*
G01X304383Y-474479D02*
Y-469479D01*
X305967D01*
X306473Y-469729D01*
X306790Y-470062D01*
X306917Y-470729D01*
X306790Y-471396D01*
X306410Y-471812D01*
X305967Y-472062D01*
X304383D01*
G01X305967D02*
X306917Y-474479D01*
G01X310750D02*
X310243Y-474396D01*
X309800Y-474062D01*
X309420Y-473562D01*
X309167Y-472979D01*
X309040Y-472312D01*
Y-471646D01*
X309167Y-470979D01*
X309420Y-470396D01*
X309800Y-469896D01*
X310243Y-469562D01*
X310750Y-469479D01*
X311257Y-469562D01*
X311700Y-469896D01*
X312080Y-470396D01*
X312333Y-470979D01*
X312460Y-471646D01*
Y-472312D01*
X312333Y-472979D01*
X312080Y-473562D01*
X311700Y-474062D01*
X311257Y-474396D01*
X310750Y-474479D01*
G01X314583Y-473479D02*
X314900Y-473979D01*
X315280Y-474312D01*
X315723Y-474479D01*
X316230Y-474312D01*
X316610Y-473979D01*
X316990Y-473479D01*
X317117Y-472812D01*
Y-469479D01*
G01X322217Y-474479D02*
X319683D01*
Y-469479D01*
X322217D01*
G01X321203Y-471896D02*
X319683D01*
G01X327443Y-469896D02*
X327063Y-469646D01*
X326620Y-469479D01*
X326113D01*
X325543Y-469729D01*
X325100Y-470146D01*
X324783Y-470646D01*
X324530Y-471479D01*
X324467Y-472229D01*
X324593Y-472979D01*
X324783Y-473479D01*
X325163Y-473979D01*
X325607Y-474312D01*
X326050Y-474479D01*
X326493D01*
X326937Y-474312D01*
X327317Y-474062D01*
X327633Y-473729D01*
G01X331150Y-469479D02*
Y-474479D01*
G01X329693Y-469479D02*
X332607D01*
G01X336250Y-474646D02*
X336123Y-474562D01*
Y-474396D01*
X336250Y-474312D01*
X336377Y-474396D01*
Y-474562D01*
X336250Y-474646D01*
G01Y-472396D02*
X336123Y-472312D01*
Y-472146D01*
X336250Y-472062D01*
X336377Y-472146D01*
Y-472312D01*
X336250Y-472396D01*
G01X408650Y-514479D02*
Y-539479D01*
G01X411283Y-516979D02*
Y-521979D01*
X413817D01*
G01X416890Y-516979D02*
X418410D01*
G01X417650D02*
Y-521979D01*
G01X416890D02*
X418410D01*
G01X423257Y-519312D02*
X423510Y-519062D01*
X423700Y-518646D01*
X423827Y-518062D01*
X423700Y-517562D01*
X423447Y-517229D01*
X423003Y-516979D01*
X421293D01*
Y-521979D01*
X423383D01*
X423827Y-521646D01*
X424080Y-521146D01*
X424207Y-520562D01*
X424080Y-519979D01*
X423700Y-519479D01*
X423257Y-519312D01*
X421293D01*
G01X427850Y-522146D02*
X427723Y-522062D01*
Y-521896D01*
X427850Y-521812D01*
X427977Y-521896D01*
Y-522062D01*
X427850Y-522146D01*
G01Y-519896D02*
X427723Y-519812D01*
Y-519646D01*
X427850Y-519562D01*
X427977Y-519646D01*
Y-519812D01*
X427850Y-519896D01*
G01X451650Y-514479D02*
Y-539479D01*
G01Y-489479D02*
Y-514479D01*
G01X456663Y-541646D02*
X456770Y-541521D01*
X456850Y-541312D01*
X456903Y-541021D01*
X456850Y-540771D01*
X456743Y-540604D01*
X456557Y-540479D01*
X455837D01*
Y-542979D01*
X456717D01*
X456903Y-542812D01*
X457010Y-542562D01*
X457063Y-542271D01*
X457010Y-541979D01*
X456850Y-541729D01*
X456663Y-541646D01*
X455837D01*
G01X459130Y-542979D02*
Y-541312D01*
G01Y-541604D02*
X459023Y-541437D01*
X458863Y-541354D01*
X458677Y-541312D01*
X458490Y-541396D01*
X458330Y-541562D01*
X458223Y-541812D01*
X458170Y-542146D01*
X458223Y-542479D01*
X458330Y-542729D01*
X458490Y-542896D01*
X458677Y-542979D01*
X458863Y-542937D01*
X459023Y-542812D01*
X459130Y-542646D01*
G01X460450Y-542687D02*
X460583Y-542854D01*
X460770Y-542979D01*
X460930D01*
X461090Y-542896D01*
X461197Y-542771D01*
X461250Y-542604D01*
X461223Y-542354D01*
X461117Y-542229D01*
X460637Y-541979D01*
X460530Y-541687D01*
X460583Y-541479D01*
X460690Y-541354D01*
X460850Y-541312D01*
X461010Y-541354D01*
X461170Y-541479D01*
G01X462650Y-541854D02*
X463503D01*
X463423Y-541562D01*
X463290Y-541396D01*
X463103Y-541312D01*
X462917Y-541354D01*
X462757Y-541479D01*
X462650Y-541771D01*
X462597Y-542021D01*
Y-542271D01*
X462650Y-542521D01*
X462783Y-542771D01*
X462943Y-542937D01*
X463130Y-542979D01*
X463317Y-542896D01*
X463503Y-542646D01*
G01X464770Y-542979D02*
Y-540479D01*
G01Y-541729D02*
X464903Y-541479D01*
X465063Y-541354D01*
X465223Y-541312D01*
X465463Y-541396D01*
X465623Y-541562D01*
X465730Y-541854D01*
Y-542187D01*
X465677Y-542521D01*
X465570Y-542771D01*
X465383Y-542937D01*
X465223Y-542979D01*
X465063Y-542937D01*
X464903Y-542812D01*
X464770Y-542604D01*
G01X467450Y-542979D02*
X467290Y-542937D01*
X467130Y-542771D01*
X467023Y-542479D01*
X466970Y-542146D01*
X467023Y-541812D01*
X467130Y-541521D01*
X467290Y-541354D01*
X467450Y-541312D01*
X467610Y-541354D01*
X467770Y-541521D01*
X467877Y-541812D01*
X467903Y-542146D01*
X467877Y-542479D01*
X467770Y-542771D01*
X467610Y-542937D01*
X467450Y-542979D01*
G01X470130D02*
Y-541312D01*
G01Y-541604D02*
X470023Y-541437D01*
X469863Y-541354D01*
X469677Y-541312D01*
X469490Y-541396D01*
X469330Y-541562D01*
X469223Y-541812D01*
X469170Y-542146D01*
X469223Y-542479D01*
X469330Y-542729D01*
X469490Y-542896D01*
X469677Y-542979D01*
X469863Y-542937D01*
X470023Y-542812D01*
X470130Y-542646D01*
G01X471477Y-542979D02*
Y-541312D01*
G01Y-541646D02*
X471610Y-541479D01*
X471743Y-541354D01*
X471930Y-541312D01*
X472063Y-541354D01*
X472223Y-541479D01*
G01X474530Y-540479D02*
Y-542979D01*
G01Y-542604D02*
X474423Y-542812D01*
X474263Y-542937D01*
X474077Y-542979D01*
X473863Y-542896D01*
X473703Y-542687D01*
X473597Y-542437D01*
X473570Y-542146D01*
X473597Y-541854D01*
X473703Y-541604D01*
X473863Y-541396D01*
X474077Y-541312D01*
X474263Y-541354D01*
X474397Y-541437D01*
X474530Y-541604D01*
G01X477917Y-542979D02*
Y-540479D01*
X478583D01*
X478797Y-540604D01*
X478930Y-540771D01*
X478983Y-541104D01*
X478930Y-541437D01*
X478770Y-541646D01*
X478583Y-541771D01*
X477917D01*
G01X478583D02*
X478983Y-542979D01*
G01X480250Y-541854D02*
X481103D01*
X481023Y-541562D01*
X480890Y-541396D01*
X480703Y-541312D01*
X480517Y-541354D01*
X480357Y-541479D01*
X480250Y-541771D01*
X480197Y-542021D01*
Y-542271D01*
X480250Y-542521D01*
X480383Y-542771D01*
X480543Y-542937D01*
X480730Y-542979D01*
X480917Y-542896D01*
X481103Y-542646D01*
G01X482370Y-541312D02*
X482850Y-542979D01*
X483330Y-541312D01*
G01X485050Y-543062D02*
X484997Y-543021D01*
Y-542937D01*
X485050Y-542896D01*
X485103Y-542937D01*
Y-543021D01*
X485050Y-543062D01*
G01X487250Y-542979D02*
X487437Y-542937D01*
X487650Y-542812D01*
X487783Y-542604D01*
X487837Y-542312D01*
X487783Y-542021D01*
X487623Y-541771D01*
X487383Y-541646D01*
X487117D01*
X486957Y-541562D01*
X486823Y-541354D01*
X486770Y-541062D01*
X486850Y-540771D01*
X487037Y-540562D01*
X487250Y-540479D01*
X487463Y-540562D01*
X487650Y-540771D01*
X487730Y-541062D01*
X487677Y-541354D01*
X487543Y-541562D01*
X487383Y-541646D01*
X487117D01*
X486877Y-541771D01*
X486717Y-542021D01*
X486663Y-542312D01*
X486717Y-542604D01*
X486850Y-542812D01*
X487063Y-542937D01*
X487250Y-542979D01*
G01X489663Y-541646D02*
X489770Y-541521D01*
X489850Y-541312D01*
X489903Y-541021D01*
X489850Y-540771D01*
X489743Y-540604D01*
X489557Y-540479D01*
X488837D01*
Y-542979D01*
X489717D01*
X489903Y-542812D01*
X490010Y-542562D01*
X490063Y-542271D01*
X490010Y-541979D01*
X489850Y-541729D01*
X489663Y-541646D01*
X488837D01*
G01X455550Y-516979D02*
Y-521979D01*
G01X454093Y-516979D02*
X457007D01*
G01X460650Y-521979D02*
X460270Y-521896D01*
X459890Y-521562D01*
X459637Y-520979D01*
X459510Y-520312D01*
X459637Y-519646D01*
X459890Y-519062D01*
X460270Y-518729D01*
X460650Y-518646D01*
X461030Y-518729D01*
X461410Y-519062D01*
X461663Y-519646D01*
X461727Y-520312D01*
X461663Y-520979D01*
X461410Y-521562D01*
X461030Y-521896D01*
X460650Y-521979D01*
G01X465750D02*
X465370Y-521896D01*
X464990Y-521562D01*
X464737Y-520979D01*
X464610Y-520312D01*
X464737Y-519646D01*
X464990Y-519062D01*
X465370Y-518729D01*
X465750Y-518646D01*
X466130Y-518729D01*
X466510Y-519062D01*
X466763Y-519646D01*
X466827Y-520312D01*
X466763Y-520979D01*
X466510Y-521562D01*
X466130Y-521896D01*
X465750Y-521979D01*
G01X470850D02*
Y-516979D01*
G01X475950Y-522146D02*
X475823Y-522062D01*
Y-521896D01*
X475950Y-521812D01*
X476077Y-521896D01*
Y-522062D01*
X475950Y-522146D01*
G01Y-519896D02*
X475823Y-519812D01*
Y-519646D01*
X475950Y-519562D01*
X476077Y-519646D01*
Y-519812D01*
X475950Y-519896D01*
G01X454283Y-496979D02*
Y-491979D01*
X455867D01*
X456373Y-492229D01*
X456690Y-492562D01*
X456817Y-493229D01*
X456690Y-493896D01*
X456310Y-494312D01*
X455867Y-494562D01*
X454283D01*
G01X455867D02*
X456817Y-496979D01*
G01X461917D02*
X459383D01*
Y-491979D01*
X461917D01*
G01X460903Y-494396D02*
X459383D01*
G01X464167Y-491979D02*
X465750Y-496979D01*
X467333Y-491979D01*
G01X470850Y-497146D02*
X470723Y-497062D01*
Y-496896D01*
X470850Y-496812D01*
X470977Y-496896D01*
Y-497062D01*
X470850Y-497146D01*
G01Y-494896D02*
X470723Y-494812D01*
Y-494646D01*
X470850Y-494562D01*
X470977Y-494646D01*
Y-494812D01*
X470850Y-494896D01*
G01X-984580Y-698988D02*
Y4193602D01*
X5868320D01*
Y-698988D01*
X-984580D01*
G01X7723Y-521204D02*
X7253Y-520889D01*
X6705Y-520679D01*
X6078D01*
X5373Y-520994D01*
X4825Y-521519D01*
X4433Y-522149D01*
X4120Y-523199D01*
X4042Y-524144D01*
X4198Y-525089D01*
X4433Y-525719D01*
X4903Y-526349D01*
X5452Y-526769D01*
X6000Y-526979D01*
X6548D01*
X7097Y-526769D01*
X7567Y-526454D01*
X7958Y-526034D01*
G01X11360Y-520679D02*
X13240D01*
G01X12300D02*
Y-526979D01*
G01X11360D02*
X13240D01*
G01X18600Y-520679D02*
Y-526979D01*
G01X16798Y-520679D02*
X20402D01*
G01X24900Y-526979D02*
Y-524144D01*
X23333Y-520679D01*
G01X26467D02*
X24900Y-524144D01*
G01X35777Y-525719D02*
X36247Y-526454D01*
X36873Y-526874D01*
X37578Y-526979D01*
X38205Y-526874D01*
X38832Y-526349D01*
X39223Y-525719D01*
X39302Y-525089D01*
X39145Y-524354D01*
X38597Y-523829D01*
X38048Y-523619D01*
X37343D01*
G01X38048D02*
X38518Y-523304D01*
X38910Y-522779D01*
X39067Y-522149D01*
X38910Y-521519D01*
X38518Y-520994D01*
X37813Y-520679D01*
X37108Y-520784D01*
X36403Y-521204D01*
G01X42077Y-525719D02*
X42547Y-526454D01*
X43173Y-526874D01*
X43878Y-526979D01*
X44505Y-526874D01*
X45132Y-526349D01*
X45523Y-525719D01*
X45602Y-525089D01*
X45445Y-524354D01*
X44897Y-523829D01*
X44348Y-523619D01*
X43643D01*
G01X44348D02*
X44818Y-523304D01*
X45210Y-522779D01*
X45367Y-522149D01*
X45210Y-521519D01*
X44818Y-520994D01*
X44113Y-520679D01*
X43408Y-520784D01*
X42703Y-521204D01*
G01X48377Y-525719D02*
X48847Y-526454D01*
X49473Y-526874D01*
X50178Y-526979D01*
X50805Y-526874D01*
X51432Y-526349D01*
X51823Y-525719D01*
X51902Y-525089D01*
X51745Y-524354D01*
X51197Y-523829D01*
X50648Y-523619D01*
X49943D01*
G01X50648D02*
X51118Y-523304D01*
X51510Y-522779D01*
X51667Y-522149D01*
X51510Y-521519D01*
X51118Y-520994D01*
X50413Y-520679D01*
X49708Y-520784D01*
X49003Y-521204D01*
G01X56243Y-526979D02*
X56400Y-525614D01*
X56635Y-524459D01*
X56948Y-523409D01*
X57340Y-522254D01*
X57967Y-520679D01*
X54833D01*
G01X62543Y-526979D02*
X62700Y-525614D01*
X62935Y-524459D01*
X63248Y-523409D01*
X63640Y-522254D01*
X64267Y-520679D01*
X61133D01*
G01X68843Y-528134D02*
X69157Y-526769D01*
G01X75300Y-520679D02*
Y-526979D01*
G01X73498Y-520679D02*
X77102D01*
G01X79642Y-526979D02*
X81600Y-520679D01*
X83558Y-526979D01*
G01X82853Y-524774D02*
X80347D01*
G01X86960Y-520679D02*
X88840D01*
G01X87900D02*
Y-526979D01*
G01X86960D02*
X88840D01*
G01X91850Y-520679D02*
X92947Y-526979D01*
X94200Y-520679D01*
X95453Y-526979D01*
X96550Y-520679D01*
G01X98542Y-526979D02*
X100500Y-520679D01*
X102458Y-526979D01*
G01X101753Y-524774D02*
X99247D01*
G01X104998Y-526979D02*
Y-520679D01*
X108602Y-526979D01*
Y-520679D01*
G01X119008Y-529079D02*
X118225Y-528029D01*
X117833Y-526979D01*
Y-522779D01*
X118225Y-521729D01*
X119008Y-520679D01*
G01X130433Y-526979D02*
Y-520679D01*
X132392D01*
X133018Y-520994D01*
X133410Y-521414D01*
X133567Y-522254D01*
X133410Y-523094D01*
X132940Y-523619D01*
X132392Y-523934D01*
X130433D01*
G01X132392D02*
X133567Y-526979D01*
G01X138300Y-527189D02*
X138143Y-527084D01*
Y-526874D01*
X138300Y-526769D01*
X138457Y-526874D01*
Y-527084D01*
X138300Y-527189D01*
G01X144600Y-526979D02*
X143973Y-526874D01*
X143425Y-526454D01*
X142955Y-525824D01*
X142642Y-525089D01*
X142485Y-524249D01*
Y-523409D01*
X142642Y-522569D01*
X142955Y-521834D01*
X143425Y-521204D01*
X143973Y-520784D01*
X144600Y-520679D01*
X145227Y-520784D01*
X145775Y-521204D01*
X146245Y-521834D01*
X146558Y-522569D01*
X146715Y-523409D01*
Y-524249D01*
X146558Y-525089D01*
X146245Y-525824D01*
X145775Y-526454D01*
X145227Y-526874D01*
X144600Y-526979D01*
G01X150900Y-527189D02*
X150743Y-527084D01*
Y-526874D01*
X150900Y-526769D01*
X151057Y-526874D01*
Y-527084D01*
X150900Y-527189D01*
G01X158923Y-521204D02*
X158453Y-520889D01*
X157905Y-520679D01*
X157278D01*
X156573Y-520994D01*
X156025Y-521519D01*
X155633Y-522149D01*
X155320Y-523199D01*
X155242Y-524144D01*
X155398Y-525089D01*
X155633Y-525719D01*
X156103Y-526349D01*
X156652Y-526769D01*
X157200Y-526979D01*
X157748D01*
X158297Y-526769D01*
X158767Y-526454D01*
X159158Y-526034D01*
G01X163500Y-527189D02*
X163343Y-527084D01*
Y-526874D01*
X163500Y-526769D01*
X163657Y-526874D01*
Y-527084D01*
X163500Y-527189D01*
G01X170192Y-529079D02*
X170975Y-528029D01*
X171367Y-526979D01*
Y-522779D01*
X170975Y-521729D01*
X170192Y-520679D01*
G01X6470Y-513829D02*
X8037D01*
Y-515719D01*
X7567Y-516349D01*
X7018Y-516769D01*
X6235Y-516979D01*
X5452Y-516769D01*
X4903Y-516349D01*
X4433Y-515719D01*
X4120Y-514984D01*
X3963Y-514144D01*
Y-513409D01*
X4120Y-512779D01*
X4433Y-512044D01*
X4903Y-511414D01*
X5373Y-510994D01*
X6000Y-510679D01*
X6548D01*
X7175Y-510889D01*
X7645Y-511309D01*
G01X10577Y-510679D02*
Y-515194D01*
X10890Y-516139D01*
X11517Y-516769D01*
X12300Y-516979D01*
X13083Y-516769D01*
X13710Y-516139D01*
X14023Y-515194D01*
Y-510679D01*
G01X17660D02*
X19540D01*
G01X18600D02*
Y-516979D01*
G01X17660D02*
X19540D01*
G01X23255Y-516139D02*
X23882Y-516664D01*
X24587Y-516979D01*
X25213D01*
X25840Y-516664D01*
X26310Y-516139D01*
X26545Y-515404D01*
X26388Y-514669D01*
X25997Y-514039D01*
X25292Y-513619D01*
X24352Y-513409D01*
X23803Y-512989D01*
X23568Y-512254D01*
X23725Y-511519D01*
X24117Y-510994D01*
X24665Y-510679D01*
X25213D01*
X25762Y-510889D01*
X26232Y-511414D01*
G01X29555Y-516979D02*
Y-510679D01*
G01X32845D02*
Y-516979D01*
G01Y-513829D02*
X29555D01*
G01X35542Y-516979D02*
X37500Y-510679D01*
X39458Y-516979D01*
G01X38753Y-514774D02*
X36247D01*
G01X41998Y-516979D02*
Y-510679D01*
X45602Y-516979D01*
Y-510679D01*
G01X54677Y-516979D02*
Y-510679D01*
X56243D01*
X56870Y-510994D01*
X57340Y-511414D01*
X57732Y-512044D01*
X58045Y-512779D01*
X58123Y-513829D01*
X58045Y-514879D01*
X57732Y-515614D01*
X57340Y-516244D01*
X56870Y-516664D01*
X56243Y-516979D01*
X54677D01*
G01X61760Y-510679D02*
X63640D01*
G01X62700D02*
Y-516979D01*
G01X61760D02*
X63640D01*
G01X67355Y-516139D02*
X67982Y-516664D01*
X68687Y-516979D01*
X69313D01*
X69940Y-516664D01*
X70410Y-516139D01*
X70645Y-515404D01*
X70488Y-514669D01*
X70097Y-514039D01*
X69392Y-513619D01*
X68452Y-513409D01*
X67903Y-512989D01*
X67668Y-512254D01*
X67825Y-511519D01*
X68217Y-510994D01*
X68765Y-510679D01*
X69313D01*
X69862Y-510889D01*
X70332Y-511414D01*
G01X75300Y-510679D02*
Y-516979D01*
G01X73498Y-510679D02*
X77102D01*
G01X81600Y-517189D02*
X81443Y-517084D01*
Y-516874D01*
X81600Y-516769D01*
X81757Y-516874D01*
Y-517084D01*
X81600Y-517189D01*
G01X87743Y-518134D02*
X88057Y-516769D01*
G01X94200Y-510679D02*
Y-516979D01*
G01X92398Y-510679D02*
X96002D01*
G01X98542Y-516979D02*
X100500Y-510679D01*
X102458Y-516979D01*
G01X101753Y-514774D02*
X99247D01*
G01X106800Y-516979D02*
X106173Y-516874D01*
X105625Y-516454D01*
X105155Y-515824D01*
X104842Y-515089D01*
X104685Y-514249D01*
Y-513409D01*
X104842Y-512569D01*
X105155Y-511834D01*
X105625Y-511204D01*
X106173Y-510784D01*
X106800Y-510679D01*
X107427Y-510784D01*
X107975Y-511204D01*
X108445Y-511834D01*
X108758Y-512569D01*
X108915Y-513409D01*
Y-514249D01*
X108758Y-515089D01*
X108445Y-515824D01*
X107975Y-516454D01*
X107427Y-516874D01*
X106800Y-516979D01*
G01X113100D02*
Y-514144D01*
X111533Y-510679D01*
G01X114667D02*
X113100Y-514144D01*
G01X117677Y-510679D02*
Y-515194D01*
X117990Y-516139D01*
X118617Y-516769D01*
X119400Y-516979D01*
X120183Y-516769D01*
X120810Y-516139D01*
X121123Y-515194D01*
Y-510679D01*
G01X123742Y-516979D02*
X125700Y-510679D01*
X127658Y-516979D01*
G01X126953Y-514774D02*
X124447D01*
G01X130198Y-516979D02*
Y-510679D01*
X133802Y-516979D01*
Y-510679D01*
G01X4198Y-506979D02*
Y-500679D01*
X7802Y-506979D01*
Y-500679D01*
G01X12300Y-506979D02*
X11673Y-506874D01*
X11125Y-506454D01*
X10655Y-505824D01*
X10342Y-505089D01*
X10185Y-504249D01*
Y-503409D01*
X10342Y-502569D01*
X10655Y-501834D01*
X11125Y-501204D01*
X11673Y-500784D01*
X12300Y-500679D01*
X12927Y-500784D01*
X13475Y-501204D01*
X13945Y-501834D01*
X14258Y-502569D01*
X14415Y-503409D01*
Y-504249D01*
X14258Y-505089D01*
X13945Y-505824D01*
X13475Y-506454D01*
X12927Y-506874D01*
X12300Y-506979D01*
G01X18600Y-507189D02*
X18443Y-507084D01*
Y-506874D01*
X18600Y-506769D01*
X18757Y-506874D01*
Y-507084D01*
X18600Y-507189D01*
G01X23412Y-501729D02*
X23882Y-501099D01*
X24430Y-500784D01*
X25057Y-500679D01*
X25840Y-500889D01*
X26388Y-501414D01*
X26545Y-502044D01*
X26467Y-502674D01*
X26153Y-503199D01*
X24587Y-504249D01*
X23882Y-504984D01*
X23412Y-506034D01*
X23255Y-506979D01*
X26545D01*
G01X31200D02*
Y-500679D01*
X30260Y-501939D01*
G01Y-506979D02*
X32140D01*
G01X37500D02*
Y-500679D01*
X36560Y-501939D01*
G01Y-506979D02*
X38440D01*
G01X43643Y-508134D02*
X43957Y-506769D01*
G01X47750Y-500679D02*
X48847Y-506979D01*
X50100Y-500679D01*
X51353Y-506979D01*
X52450Y-500679D01*
G01X57967Y-506979D02*
X54833D01*
Y-500679D01*
X57967D01*
G01X56713Y-503724D02*
X54833D01*
G01X60898Y-506979D02*
Y-500679D01*
X64502Y-506979D01*
Y-500679D01*
G01X67355Y-506979D02*
Y-500679D01*
G01X70645D02*
Y-506979D01*
G01Y-503829D02*
X67355D01*
G01X73577Y-500679D02*
Y-505194D01*
X73890Y-506139D01*
X74517Y-506769D01*
X75300Y-506979D01*
X76083Y-506769D01*
X76710Y-506139D01*
X77023Y-505194D01*
Y-500679D01*
G01X79642Y-506979D02*
X81600Y-500679D01*
X83558Y-506979D01*
G01X82853Y-504774D02*
X80347D01*
G01X92712Y-501729D02*
X93182Y-501099D01*
X93730Y-500784D01*
X94357Y-500679D01*
X95140Y-500889D01*
X95688Y-501414D01*
X95845Y-502044D01*
X95767Y-502674D01*
X95453Y-503199D01*
X93887Y-504249D01*
X93182Y-504984D01*
X92712Y-506034D01*
X92555Y-506979D01*
X95845D01*
G01X98698D02*
Y-500679D01*
X102302Y-506979D01*
Y-500679D01*
G01X105077Y-506979D02*
Y-500679D01*
X106643D01*
X107270Y-500994D01*
X107740Y-501414D01*
X108132Y-502044D01*
X108445Y-502779D01*
X108523Y-503829D01*
X108445Y-504879D01*
X108132Y-505614D01*
X107740Y-506244D01*
X107270Y-506664D01*
X106643Y-506979D01*
X105077D01*
G01X117833D02*
Y-500679D01*
X119792D01*
X120418Y-500994D01*
X120810Y-501414D01*
X120967Y-502254D01*
X120810Y-503094D01*
X120340Y-503619D01*
X119792Y-503934D01*
X117833D01*
G01X119792D02*
X120967Y-506979D01*
G01X123977D02*
Y-500679D01*
X125543D01*
X126170Y-500994D01*
X126640Y-501414D01*
X127032Y-502044D01*
X127345Y-502779D01*
X127423Y-503829D01*
X127345Y-504879D01*
X127032Y-505614D01*
X126640Y-506244D01*
X126170Y-506664D01*
X125543Y-506979D01*
X123977D01*
G01X132000Y-507189D02*
X131843Y-507084D01*
Y-506874D01*
X132000Y-506769D01*
X132157Y-506874D01*
Y-507084D01*
X132000Y-507189D01*
G01X28300Y-494279D02*
X25780Y-493862D01*
X23575Y-492196D01*
X21685Y-489696D01*
X20425Y-486779D01*
X19795Y-483446D01*
Y-480112D01*
X20425Y-476779D01*
X21685Y-473862D01*
X23575Y-471363D01*
X25780Y-469696D01*
X28300Y-469279D01*
X30820Y-469696D01*
X33025Y-471363D01*
X34915Y-473862D01*
X36175Y-476779D01*
X36805Y-480112D01*
Y-483446D01*
X36175Y-486779D01*
X34915Y-489696D01*
X33025Y-492196D01*
X30820Y-493862D01*
X28300Y-494279D01*
G01X30820Y-487612D02*
X34600Y-494279D01*
G01X48145Y-477613D02*
Y-489279D01*
X49405Y-492196D01*
X51295Y-493862D01*
X53500Y-494279D01*
X55705Y-493862D01*
X57595Y-492196D01*
X58855Y-489279D01*
G01Y-494279D02*
Y-477613D01*
G01X84370Y-494279D02*
Y-477613D01*
G01Y-480529D02*
X83110Y-478863D01*
X81220Y-478029D01*
X79015Y-477613D01*
X76810Y-478446D01*
X74920Y-480112D01*
X73660Y-482613D01*
X73030Y-485946D01*
X73660Y-489279D01*
X74920Y-491780D01*
X76810Y-493446D01*
X79015Y-494279D01*
X81220Y-493862D01*
X83110Y-492613D01*
X84370Y-490946D01*
G01X98545Y-494279D02*
Y-477613D01*
G01Y-481779D02*
X99805Y-479696D01*
X101695Y-478029D01*
X104215Y-477613D01*
X106420Y-478029D01*
X108310Y-479696D01*
X109255Y-482613D01*
Y-494279D01*
G01X129100Y-469279D02*
Y-494279D01*
G01X124690Y-477613D02*
X133510D01*
G01X159970Y-494279D02*
Y-477613D01*
G01Y-480529D02*
X158710Y-478863D01*
X156820Y-478029D01*
X154615Y-477613D01*
X152410Y-478446D01*
X150520Y-480112D01*
X149260Y-482613D01*
X148630Y-485946D01*
X149260Y-489279D01*
X150520Y-491780D01*
X152410Y-493446D01*
X154615Y-494279D01*
X156820Y-493862D01*
X158710Y-492613D01*
X159970Y-490946D01*
G01X199650Y-473979D02*
Y-481979D01*
X203650D01*
G01X211450D02*
Y-476646D01*
G01Y-477579D02*
X211050Y-477046D01*
X210450Y-476779D01*
X209750Y-476646D01*
X209050Y-476912D01*
X208450Y-477446D01*
X208050Y-478246D01*
X207850Y-479312D01*
X208050Y-480379D01*
X208450Y-481179D01*
X209050Y-481712D01*
X209750Y-481979D01*
X210450Y-481846D01*
X211050Y-481446D01*
X211450Y-480913D01*
G01X215550Y-484379D02*
X216150Y-484646D01*
X216950Y-484379D01*
X217450Y-483846D01*
X217850Y-483179D01*
X218450Y-481046D01*
X219750Y-476646D01*
G01X216550D02*
X218450Y-481046D01*
G01X224150Y-478379D02*
X227350D01*
X227050Y-477446D01*
X226550Y-476912D01*
X225850Y-476646D01*
X225150Y-476779D01*
X224550Y-477179D01*
X224150Y-478112D01*
X223950Y-478913D01*
Y-479712D01*
X224150Y-480512D01*
X224650Y-481312D01*
X225250Y-481846D01*
X225950Y-481979D01*
X226650Y-481712D01*
X227350Y-480913D01*
G01X232250Y-481979D02*
Y-476646D01*
G01Y-477712D02*
X232750Y-477179D01*
X233250Y-476779D01*
X233950Y-476646D01*
X234450Y-476779D01*
X235050Y-477179D01*
G01X223350Y-531979D02*
Y-523979D01*
X227950Y-531979D01*
Y-523979D01*
G01X233650Y-526646D02*
Y-531979D01*
G01Y-524512D02*
X233450Y-524379D01*
Y-524112D01*
X233650Y-523979D01*
X233850Y-524112D01*
Y-524379D01*
X233650Y-524512D01*
G01X239950Y-531979D02*
Y-526646D01*
G01Y-527979D02*
X240350Y-527312D01*
X240950Y-526779D01*
X241750Y-526646D01*
X242450Y-526779D01*
X243050Y-527312D01*
X243350Y-528246D01*
Y-531979D01*
G01X251450D02*
Y-526646D01*
G01Y-527579D02*
X251050Y-527046D01*
X250450Y-526779D01*
X249750Y-526646D01*
X249050Y-526912D01*
X248450Y-527446D01*
X248050Y-528246D01*
X247850Y-529312D01*
X248050Y-530379D01*
X248450Y-531179D01*
X249050Y-531712D01*
X249750Y-531979D01*
X250450Y-531846D01*
X251050Y-531446D01*
X251450Y-530913D01*
G01X225479Y-500436D02*
X227879D01*
G01X226679D02*
Y-508436D01*
G01X225479D02*
X227879D01*
G01X232379D02*
Y-500436D01*
X236979Y-508436D01*
Y-500436D01*
G01X240479Y-506836D02*
X241079Y-507769D01*
X241879Y-508303D01*
X242779Y-508436D01*
X243579Y-508303D01*
X244379Y-507636D01*
X244879Y-506836D01*
X244979Y-506036D01*
X244779Y-505103D01*
X244079Y-504436D01*
X243379Y-504169D01*
X242479D01*
G01X243379D02*
X243979Y-503769D01*
X244479Y-503103D01*
X244679Y-502303D01*
X244479Y-501503D01*
X243979Y-500836D01*
X243079Y-500436D01*
X242179Y-500569D01*
X241279Y-501103D01*
G01X246479Y-483436D02*
X246679Y-481703D01*
X246979Y-480236D01*
X247379Y-478903D01*
X247879Y-477436D01*
X248679Y-475436D01*
X244679D01*
G01X326250Y-525312D02*
X326850Y-524512D01*
X327550Y-524112D01*
X328350Y-523979D01*
X329350Y-524246D01*
X330050Y-524912D01*
X330250Y-525712D01*
X330150Y-526513D01*
X329750Y-527179D01*
X327750Y-528512D01*
X326850Y-529446D01*
X326250Y-530779D01*
X326050Y-531979D01*
X330250D01*
G01X336150Y-523979D02*
X335350Y-524246D01*
X334750Y-524912D01*
X334350Y-525712D01*
X334050Y-526779D01*
X333950Y-527979D01*
X334050Y-529179D01*
X334350Y-530246D01*
X334750Y-531046D01*
X335350Y-531712D01*
X336150Y-531979D01*
X336950Y-531712D01*
X337550Y-531046D01*
X337950Y-530246D01*
X338250Y-529179D01*
X338350Y-527979D01*
X338250Y-526779D01*
X337950Y-525712D01*
X337550Y-524912D01*
X336950Y-524246D01*
X336150Y-523979D01*
G01X342250Y-525312D02*
X342850Y-524512D01*
X343550Y-524112D01*
X344350Y-523979D01*
X345350Y-524246D01*
X346050Y-524912D01*
X346250Y-525712D01*
X346150Y-526513D01*
X345750Y-527179D01*
X343750Y-528512D01*
X342850Y-529446D01*
X342250Y-530779D01*
X342050Y-531979D01*
X346250D01*
G01X349950Y-530379D02*
X350550Y-531312D01*
X351350Y-531846D01*
X352250Y-531979D01*
X353050Y-531846D01*
X353850Y-531179D01*
X354350Y-530379D01*
X354450Y-529579D01*
X354250Y-528646D01*
X353550Y-527979D01*
X352850Y-527712D01*
X351950D01*
G01X352850D02*
X353450Y-527312D01*
X353950Y-526646D01*
X354150Y-525846D01*
X353950Y-525046D01*
X353450Y-524379D01*
X352550Y-523979D01*
X351650Y-524112D01*
X350750Y-524646D01*
G01X358350Y-532246D02*
X361950Y-523979D01*
G01X368150D02*
X367350Y-524246D01*
X366750Y-524912D01*
X366350Y-525712D01*
X366050Y-526779D01*
X365950Y-527979D01*
X366050Y-529179D01*
X366350Y-530246D01*
X366750Y-531046D01*
X367350Y-531712D01*
X368150Y-531979D01*
X368950Y-531712D01*
X369550Y-531046D01*
X369950Y-530246D01*
X370250Y-529179D01*
X370350Y-527979D01*
X370250Y-526779D01*
X369950Y-525712D01*
X369550Y-524912D01*
X368950Y-524246D01*
X368150Y-523979D01*
G01X373950Y-530379D02*
X374550Y-531312D01*
X375350Y-531846D01*
X376250Y-531979D01*
X377050Y-531846D01*
X377850Y-531179D01*
X378350Y-530379D01*
X378450Y-529579D01*
X378250Y-528646D01*
X377550Y-527979D01*
X376850Y-527712D01*
X375950D01*
G01X376850D02*
X377450Y-527312D01*
X377950Y-526646D01*
X378150Y-525846D01*
X377950Y-525046D01*
X377450Y-524379D01*
X376550Y-523979D01*
X375650Y-524112D01*
X374750Y-524646D01*
G01X382350Y-532246D02*
X385950Y-523979D01*
G01X390250Y-525312D02*
X390850Y-524512D01*
X391550Y-524112D01*
X392350Y-523979D01*
X393350Y-524246D01*
X394050Y-524912D01*
X394250Y-525712D01*
X394150Y-526513D01*
X393750Y-527179D01*
X391750Y-528512D01*
X390850Y-529446D01*
X390250Y-530779D01*
X390050Y-531979D01*
X394250D01*
G01X401350D02*
Y-523979D01*
X397650Y-529712D01*
X402650D01*
G01X325950Y-506979D02*
Y-498979D01*
X327950D01*
X328750Y-499379D01*
X329350Y-499912D01*
X329850Y-500712D01*
X330250Y-501646D01*
X330350Y-502979D01*
X330250Y-504312D01*
X329850Y-505246D01*
X329350Y-506046D01*
X328750Y-506579D01*
X327950Y-506979D01*
X325950D01*
G01X333650D02*
X336150Y-498979D01*
X338650Y-506979D01*
G01X337750Y-504179D02*
X334550D01*
G01X344150Y-498979D02*
X343350Y-499246D01*
X342750Y-499912D01*
X342350Y-500712D01*
X342050Y-501779D01*
X341950Y-502979D01*
X342050Y-504179D01*
X342350Y-505246D01*
X342750Y-506046D01*
X343350Y-506712D01*
X344150Y-506979D01*
X344950Y-506712D01*
X345550Y-506046D01*
X345950Y-505246D01*
X346250Y-504179D01*
X346350Y-502979D01*
X346250Y-501779D01*
X345950Y-500712D01*
X345550Y-499912D01*
X344950Y-499246D01*
X344150Y-498979D01*
G01X350250Y-506979D02*
Y-498979D01*
X354050D01*
G01X352650Y-502846D02*
X350250D01*
G01X360150Y-498979D02*
X359350Y-499246D01*
X358750Y-499912D01*
X358350Y-500712D01*
X358050Y-501779D01*
X357950Y-502979D01*
X358050Y-504179D01*
X358350Y-505246D01*
X358750Y-506046D01*
X359350Y-506712D01*
X360150Y-506979D01*
X360950Y-506712D01*
X361550Y-506046D01*
X361950Y-505246D01*
X362250Y-504179D01*
X362350Y-502979D01*
X362250Y-501779D01*
X361950Y-500712D01*
X361550Y-499912D01*
X360950Y-499246D01*
X360150Y-498979D01*
G01X368150D02*
Y-506979D01*
G01X365850Y-498979D02*
X370450D01*
G01X373550Y-506979D02*
Y-498979D01*
X376150Y-505646D01*
X378750Y-498979D01*
Y-506979D01*
G01X384950Y-502712D02*
X385350Y-502312D01*
X385650Y-501646D01*
X385850Y-500712D01*
X385650Y-499912D01*
X385250Y-499379D01*
X384550Y-498979D01*
X381850D01*
Y-506979D01*
X385150D01*
X385850Y-506446D01*
X386250Y-505646D01*
X386450Y-504712D01*
X386250Y-503779D01*
X385650Y-502979D01*
X384950Y-502712D01*
X381850D01*
G01X390950Y-498979D02*
X393350D01*
G01X392150D02*
Y-506979D01*
G01X390950D02*
X393350D01*
G01X398150Y-505379D02*
X398650Y-506179D01*
X399250Y-506712D01*
X399950Y-506979D01*
X400750Y-506712D01*
X401350Y-506179D01*
X401950Y-505379D01*
X402150Y-504312D01*
Y-498979D01*
G01X408150D02*
X407350Y-499246D01*
X406750Y-499912D01*
X406350Y-500712D01*
X406050Y-501779D01*
X405950Y-502979D01*
X406050Y-504179D01*
X406350Y-505246D01*
X406750Y-506046D01*
X407350Y-506712D01*
X408150Y-506979D01*
X408950Y-506712D01*
X409550Y-506046D01*
X409950Y-505246D01*
X410250Y-504179D01*
X410350Y-502979D01*
X410250Y-501779D01*
X409950Y-500712D01*
X409550Y-499912D01*
X408950Y-499246D01*
X408150Y-498979D01*
G01X343750Y-481979D02*
Y-473979D01*
X347550D01*
G01X346150Y-477846D02*
X343750D01*
G01X353650Y-473979D02*
X352850Y-474246D01*
X352250Y-474912D01*
X351850Y-475712D01*
X351550Y-476779D01*
X351450Y-477979D01*
X351550Y-479179D01*
X351850Y-480246D01*
X352250Y-481046D01*
X352850Y-481712D01*
X353650Y-481979D01*
X354450Y-481712D01*
X355050Y-481046D01*
X355450Y-480246D01*
X355750Y-479179D01*
X355850Y-477979D01*
X355750Y-476779D01*
X355450Y-475712D01*
X355050Y-474912D01*
X354450Y-474246D01*
X353650Y-473979D01*
G01X361650D02*
Y-481979D01*
G01X359350Y-473979D02*
X363950D01*
G01X366650Y-484646D02*
X372650D01*
G01X375050Y-481979D02*
Y-473979D01*
X377650Y-480646D01*
X380250Y-473979D01*
Y-481979D01*
G01X386450Y-477712D02*
X386850Y-477312D01*
X387150Y-476646D01*
X387350Y-475712D01*
X387150Y-474912D01*
X386750Y-474379D01*
X386050Y-473979D01*
X383350D01*
Y-481979D01*
X386650D01*
X387350Y-481446D01*
X387750Y-480646D01*
X387950Y-479712D01*
X387750Y-478779D01*
X387150Y-477979D01*
X386450Y-477712D01*
X383350D01*
G01X390650Y-484646D02*
X396650D01*
G01X403650Y-481979D02*
X399650D01*
Y-473979D01*
X403650D01*
G01X402050Y-477846D02*
X399650D01*
G01X407050Y-481979D02*
Y-473979D01*
X409650Y-480646D01*
X412250Y-473979D01*
Y-481979D01*
G01X417650D02*
X418350Y-481846D01*
X419150Y-481446D01*
X419650Y-480779D01*
X419850Y-479846D01*
X419650Y-478913D01*
X419050Y-478112D01*
X418150Y-477712D01*
X417150D01*
X416550Y-477446D01*
X416050Y-476779D01*
X415850Y-475846D01*
X416150Y-474912D01*
X416850Y-474246D01*
X417650Y-473979D01*
X418450Y-474246D01*
X419150Y-474912D01*
X419450Y-475846D01*
X419250Y-476779D01*
X418750Y-477446D01*
X418150Y-477712D01*
X417150D01*
X416250Y-478112D01*
X415650Y-478913D01*
X415450Y-479846D01*
X415650Y-480779D01*
X416150Y-481446D01*
X416950Y-481846D01*
X417650Y-481979D01*
G01X423950Y-481046D02*
X424650Y-481712D01*
X425450Y-481979D01*
X426250Y-481712D01*
X426950Y-480913D01*
X427450Y-479712D01*
X427650Y-478512D01*
Y-477046D01*
X427450Y-475846D01*
X426950Y-474779D01*
X426350Y-474246D01*
X425650Y-473979D01*
X424850Y-474246D01*
X424250Y-474779D01*
X423850Y-475579D01*
X423650Y-476646D01*
X423850Y-477579D01*
X424350Y-478512D01*
X424950Y-479046D01*
X425650Y-479179D01*
X426450Y-478913D01*
X427050Y-478246D01*
X427650Y-477046D01*
G01X433650Y-473979D02*
X432850Y-474246D01*
X432250Y-474912D01*
X431850Y-475712D01*
X431550Y-476779D01*
X431450Y-477979D01*
X431550Y-479179D01*
X431850Y-480246D01*
X432250Y-481046D01*
X432850Y-481712D01*
X433650Y-481979D01*
X434450Y-481712D01*
X435050Y-481046D01*
X435450Y-480246D01*
X435750Y-479179D01*
X435850Y-477979D01*
X435750Y-476779D01*
X435450Y-475712D01*
X435050Y-474912D01*
X434450Y-474246D01*
X433650Y-473979D01*
G01X439450Y-481979D02*
Y-473979D01*
G01X443250D02*
X439450Y-478913D01*
G01X443850Y-481979D02*
X441150Y-476646D01*
G01X414650Y-534979D02*
Y-526979D01*
X413450Y-528579D01*
G01Y-534979D02*
X415850D01*
G01X420750Y-531646D02*
X421450Y-530712D01*
X422050Y-530179D01*
X422850Y-529912D01*
X423550Y-530179D01*
X424050Y-530712D01*
X424450Y-531512D01*
X424550Y-532446D01*
X424450Y-533246D01*
X424050Y-534046D01*
X423450Y-534712D01*
X422750Y-534979D01*
X421950Y-534712D01*
X421250Y-533913D01*
X420850Y-532712D01*
X420750Y-531379D01*
X420950Y-529646D01*
X421250Y-528712D01*
X421750Y-527779D01*
X422450Y-527112D01*
X423150Y-526979D01*
X423850Y-527246D01*
X424350Y-527912D01*
G01X430650Y-535246D02*
X430450Y-535112D01*
Y-534846D01*
X430650Y-534712D01*
X430850Y-534846D01*
Y-535112D01*
X430650Y-535246D01*
G01X436750Y-531646D02*
X437450Y-530712D01*
X438050Y-530179D01*
X438850Y-529912D01*
X439550Y-530179D01*
X440050Y-530712D01*
X440450Y-531512D01*
X440550Y-532446D01*
X440450Y-533246D01*
X440050Y-534046D01*
X439450Y-534712D01*
X438750Y-534979D01*
X437950Y-534712D01*
X437250Y-533913D01*
X436850Y-532712D01*
X436750Y-531379D01*
X436950Y-529646D01*
X437250Y-528712D01*
X437750Y-527779D01*
X438450Y-527112D01*
X439150Y-526979D01*
X439850Y-527246D01*
X440350Y-527912D01*
G01X459650Y-534979D02*
Y-526979D01*
X458450Y-528579D01*
G01Y-534979D02*
X460850D01*
G01X467450D02*
X467650Y-533246D01*
X467950Y-531779D01*
X468350Y-530446D01*
X468850Y-528979D01*
X469650Y-526979D01*
X465650D01*
G01X475650Y-535246D02*
X475450Y-535112D01*
Y-534846D01*
X475650Y-534712D01*
X475850Y-534846D01*
Y-535112D01*
X475650Y-535246D01*
G01X481750Y-528312D02*
X482350Y-527512D01*
X483050Y-527112D01*
X483850Y-526979D01*
X484850Y-527246D01*
X485550Y-527912D01*
X485750Y-528712D01*
X485650Y-529513D01*
X485250Y-530179D01*
X483250Y-531512D01*
X482350Y-532446D01*
X481750Y-533779D01*
X481550Y-534979D01*
X485750D01*
G01X479650Y-508379D02*
X480150Y-509179D01*
X480750Y-509712D01*
X481450Y-509979D01*
X482250Y-509712D01*
X482850Y-509179D01*
X483450Y-508379D01*
X483650Y-507312D01*
Y-501979D01*
G54D17*
X673093Y1320778D03*
X697466Y1320803D03*
X721866D03*
X1131100Y1357088D03*
X1155500D03*
X1179900D03*
X1634259Y1354374D03*
X1658632Y1354399D03*
X1683032D03*
G54D27*
G01X761716Y1661194D02*
Y1659977D01*
X754088Y1652349D01*
Y1636709D01*
X743748Y1626369D01*
X704529D01*
X697000Y1618840D01*
Y1577500D01*
X693133Y1573633D01*
X686793D01*
X684032Y1576394D01*
X667894D01*
X661800Y1570300D01*
X474500D01*
X467500Y1577300D01*
Y1587700D01*
X465300Y1589900D01*
X460200D01*
G54D18*
X828780Y1694890D03*
Y1684890D03*
X818780Y1694890D03*
Y1684890D03*
X828780Y1704890D03*
X818780D03*
X828780Y1714890D03*
X818780D03*
X853780Y1694890D03*
Y1684890D03*
Y1704890D03*
Y1714890D03*
X863780Y1694890D03*
Y1684890D03*
Y1704890D03*
Y1714890D03*
X888780Y1684890D03*
Y1694890D03*
Y1704890D03*
Y1714890D03*
X898780Y1684890D03*
Y1694890D03*
Y1704890D03*
Y1714890D03*
X928780Y1694890D03*
X938780D03*
X928780Y1704890D03*
X958780Y1694890D03*
Y1684890D03*
Y1704890D03*
Y1714890D03*
X968780Y1694890D03*
Y1684890D03*
Y1704890D03*
Y1714890D03*
X993780Y1684890D03*
Y1694890D03*
X1003780Y1684890D03*
Y1694890D03*
X993780Y1704890D03*
Y1714890D03*
X1003780Y1704890D03*
Y1714890D03*
X1028780Y1684890D03*
Y1694890D03*
X1038780Y1684890D03*
Y1694890D03*
X1028780Y1704890D03*
Y1714890D03*
X1038780Y1704890D03*
Y1714890D03*
G54D28*
G01X424729Y902649D02*
X424113Y901582D01*
X423762Y901488D01*
G03X421824Y901406I-884J-2043D01*
G01X421766Y901372D01*
G02X420292I-737J1277D01*
G03X418124Y901406I-1114J-1927D01*
G01X418066Y901372D01*
G02X416592I-737J1277D01*
G03X414424Y901406I-1114J-1927D01*
G01X414366Y901372D01*
G02X412892I-737J1277D01*
G03X410724Y901406I-1114J-1927D01*
G01X410666Y901372D01*
G02X409192I-737J1277D01*
G03X407024Y901406I-1114J-1927D01*
G01X406966Y901372D01*
G02X405492I-737J1277D01*
G03X402153Y899445I-1113J-1927D01*
G02X401450Y898188I-1475J0D01*
G01X401415Y898168D01*
G03X400304Y896327I1114J-1928D01*
G01Y896240D01*
G02X399601Y894983I-1475J0D01*
G01X399542Y894949D01*
G03X398453Y893036I1136J-1913D01*
G01Y893002D01*
G02X397716Y891759I-1474J34D01*
G03X396604Y889871I1113J-1927D01*
G01Y889832D01*
G02X395901Y888575I-1475J0D01*
G01X395866Y888555D01*
G03X394753Y886683I1112J-1928D01*
G01Y886627D01*
G02X394050Y885370I-1475J0D01*
G01X394015Y885350D01*
G03X392904Y883484I1114J-1927D01*
G01Y883362D01*
G03X394015Y881496I2225J61D01*
G01X394050Y881476D01*
G02Y878962I-772J-1257D01*
G01X394015Y878942D01*
G03X392904Y877101I1114J-1928D01*
G01Y877014D01*
G02X390692Y875737I-1475J0D01*
G03X388524Y875771I-1114J-1927D01*
G01X388466Y875737D01*
G02X386992I-737J1277D01*
G03X384824Y875771I-1114J-1927D01*
G01X384766Y875737D01*
X384626Y875654D01*
G03X383653Y873945I1014J-1709D01*
G01Y873810D01*
G02X382950Y872553I-1475J0D01*
G01X382915Y872533D01*
G03X381804Y870667I1114J-1927D01*
G01Y870606D01*
G02X381101Y869349I-1475J0D01*
G01X381066Y869329D01*
G03X379953Y867431I1113J-1928D01*
G01Y867401D01*
G02X379250Y866144I-1475J0D01*
G01X379215Y866124D01*
G02X377741I-737J1277D01*
G01X377700Y866148D01*
G03X375516Y866124I-1071J-1951D01*
G02X374042I-737J1277D01*
G01X374001Y866148D01*
G03X371815Y866124I-1072J-1951D01*
G02X370341I-737J1277D01*
G01X370300Y866148D01*
G03X368116Y866124I-1071J-1951D01*
G02X366642I-737J1277D01*
G01X366601Y866148D01*
G03X364415Y866124I-1072J-1951D01*
G02X362941I-737J1277D01*
G01X362900Y866148D01*
G03X360716Y866124I-1071J-1951D01*
G02X359242I-737J1277D01*
G01X359201Y866148D01*
G03X357015Y866124I-1072J-1951D01*
G02X355541I-737J1277D01*
G01X355500Y866148D01*
G03X353316Y866124I-1071J-1951D01*
G02X351842I-737J1277D01*
G03X349616I-1113J-1927D01*
G02X348142I-737J1277D01*
G03X347030Y866422I-1112J-1927D01*
G01X345007D01*
G03X344027Y866017I-1J-1385D01*
G01X337401Y859391D01*
Y857792D01*
X337404Y857789D01*
G02X336701Y856532I-1475J0D01*
G01X336659Y856508D01*
G03X335543Y854640I1099J-1924D01*
G01X335542Y854639D01*
Y852890D01*
X335227Y852575D01*
Y852413D01*
G01X422878Y899445D02*
X423494Y900512D01*
Y900736D01*
X423411Y900819D01*
G03X422141Y900722I-534J-1374D01*
G01X422083Y900688D01*
G02X419915Y900722I-1054J1961D01*
G03X418441I-737J-1277D01*
G01X418383Y900688D01*
G02X416215Y900722I-1054J1961D01*
G03X414741I-737J-1277D01*
G01X414683Y900688D01*
G02X412515Y900722I-1054J1961D01*
G03X411041I-737J-1277D01*
G01X410983Y900688D01*
G02X408815Y900722I-1054J1961D01*
G03X407341I-737J-1277D01*
G01X407283Y900688D01*
G02X405115Y900722I-1054J1961D01*
G03X402903Y899445I-737J-1277D01*
G01Y899358D01*
G02X401792Y897517I-2225J87D01*
G01X401757Y897497D01*
G03X401054Y896240I772J-1257D01*
G01Y896239D01*
G02X399967Y894327I-2223J-1D01*
G01X399941Y894313D01*
G03X399204Y893070I737J-1277D01*
G01Y892997D01*
G02X398092Y891109I-2225J39D01*
G01X398057Y891089D01*
G03X397354Y889832I772J-1257D01*
G01Y889776D01*
G02X396241Y887904I-2225J56D01*
G01X396206Y887884D01*
G03X395503Y886627I772J-1257D01*
G01Y886566D01*
G02X394392Y884700I-2225J61D01*
G01X394357Y884680D01*
G03Y882166I772J-1257D01*
G01X394392Y882146D01*
X394416Y882132D01*
G02X395504Y880219I-1138J-1913D01*
G01Y880163D01*
G02X394392Y878291I-2226J56D01*
G01X394357Y878271D01*
G03X393654Y877014I772J-1257D01*
G02X392565Y875101I-2225J0D01*
G01X392541Y875087D01*
X392483Y875053D01*
G02X390315Y875087I-1054J1961D01*
G03X388841I-737J-1277D01*
G01X388783Y875053D01*
G02X386615Y875087I-1054J1961D01*
G03X385141I-737J-1277D01*
G01X385116Y875072D01*
G03X384403Y873844I701J-1228D01*
G01Y873749D01*
G02X383292Y871883I-2225J61D01*
G01X383257Y871863D01*
G03X382554Y870606I772J-1257D01*
G01Y870533D01*
G02X381442Y868678I-2225J73D01*
G01X381407Y868658D01*
G03X380704Y867401I772J-1257D01*
G02X379616Y865488I-2226J0D01*
G01X379592Y865474D01*
G02X377424Y865440I-1114J1927D01*
G01X377366Y865474D01*
G03X375892I-737J-1277D01*
G02X373666I-1113J1927D01*
G03X372192I-737J-1277D01*
G02X370024Y865440I-1114J1927D01*
G01X369966Y865474D01*
G03X368492I-737J-1277D01*
G02X366266I-1113J1927D01*
G03X364792I-737J-1277D01*
G02X362624Y865440I-1114J1927D01*
G01X362566Y865474D01*
G03X361092I-737J-1277D01*
G02X358866I-1113J1927D01*
G03X357392I-737J-1277D01*
G02X355224Y865440I-1114J1927D01*
G01X355166Y865474D01*
G03X353692I-737J-1277D01*
G02X351466I-1113J1927D01*
G03X349992I-737J-1277D01*
G02X347766I-1113J1927D01*
G03X347029Y865672I-738J-1277D01*
G01X345007D01*
G03X344558Y865486I0J-635D01*
G01X338154Y859082D01*
Y857733D01*
G02X337041Y855861I-2225J56D01*
G03X336304Y854618I737J-1277D01*
G01X336302Y854616D01*
Y852900D01*
X336627Y852575D01*
Y852413D01*
G01X1405003Y1076587D02*
X1405619Y1077654D01*
X1405970Y1077748D01*
G03X1407966Y1077864I883J2041D01*
G03X1409078Y1079752I-1113J1927D01*
G01Y1079830D01*
G03X1407966Y1081718I-2225J-39D01*
G01X1407931Y1081738D01*
G02X1407228Y1082995I772J1257D01*
G02X1407229Y1083053I1475J4D01*
G02X1407931Y1084252I1474J-58D01*
G01X1407966Y1084272D01*
G03X1409078Y1086144I-1114J1928D01*
G01Y1086200D01*
G03X1407990Y1088113I-2226J0D01*
G01X1407966Y1088127D01*
X1407931Y1088147D01*
G02X1407229Y1089364I773J1257D01*
G02Y1089430I1475J33D01*
G02X1407931Y1090661I1475J-25D01*
G01X1407963Y1090679D01*
X1407966Y1090681D01*
G03X1409078Y1092569I-1113J1927D01*
G01Y1092681D01*
G03X1407966Y1094536I-2225J-73D01*
G01X1407931Y1094556D01*
G02X1407228Y1095813I772J1257D01*
G01Y1095852D01*
G03X1406116Y1097740I-2225J-39D01*
G01X1406081Y1097760D01*
G02Y1100274I772J1257D01*
G01X1406116Y1100294D01*
G03X1407228Y1102182I-1113J1927D01*
G01Y1102294D01*
G03X1406116Y1104149I-2225J-73D01*
G02X1405379Y1105392I737J1277D01*
G01Y1105460D01*
G02X1406116Y1106703I1474J-34D01*
G03X1407228Y1108591I-1113J1927D01*
G01Y1108669D01*
G03X1406116Y1110557I-2225J-39D01*
G02X1405379Y1111800I737J1277D01*
G01Y1111868D01*
G02X1406116Y1113111I1474J-34D01*
G03X1407228Y1114966I-1113J1928D01*
G01Y1115078D01*
G03X1406116Y1116966I-2225J-39D01*
G02X1405379Y1118209I737J1277D01*
G01Y1118243D01*
G03X1404290Y1120156I-2225J0D01*
G01X1404266Y1120170D01*
G02X1403529Y1121413I737J1277D01*
G01Y1121481D01*
G02X1404266Y1122724I1474J-34D01*
G01X1404290Y1122738D01*
G03X1405379Y1124651I-1136J1913D01*
G01Y1124707D01*
G03X1404266Y1126579I-2225J-56D01*
G02X1403529Y1127822I737J1277D01*
G01Y1127890D01*
G02X1404266Y1129133I1474J-34D01*
G01X1404290Y1129147D01*
G03Y1132973I-1137J1913D01*
G01X1404266Y1132987D01*
G02X1403529Y1134230I737J1277D01*
G01Y1134627D01*
G02X1404262Y1135589I1474J-363D01*
G03X1405402Y1137257I-1108J1981D01*
G01X1405378Y1137690D01*
X1405344Y1138312D01*
G03X1404258Y1139601I-2190J-743D01*
G02X1403528Y1140462I745J1372D01*
G01Y1150148D01*
X1403527Y1150149D01*
Y1152706D01*
X1403693Y1152872D01*
Y1152959D01*
G01X329901Y1140436D02*
X329962Y1140375D01*
X330194D01*
X331290Y1139279D01*
Y1124500D01*
X332840Y1120758D01*
X334078Y1119520D01*
X335248D01*
X335283Y1119500D01*
G02X335986Y1118243I-772J-1257D01*
G01Y1118204D01*
G03X337098Y1116316I2225J39D01*
G01X337133Y1116296D01*
G02X337836Y1115039I-772J-1257D01*
G01Y1114966D01*
G03X338948Y1113111I2225J73D01*
G01X338983Y1113091D01*
G02X339686Y1111834I-772J-1257D01*
G03X340774Y1109921I2226J0D01*
G01X340798Y1109907D01*
X340833Y1109887D01*
G02X341536Y1108630I-772J-1257D01*
G03X342624Y1106717I2226J0D01*
G01X342648Y1106703D01*
X342683Y1106683D01*
G02X343368Y1105652I-773J-1256D01*
G01X343142Y1105426D01*
X341911D01*
G01X1406853Y1079791D02*
X1406237Y1078724D01*
X1406320Y1078417D01*
G03X1407590Y1078514I534J1374D01*
G01X1407625Y1078534D01*
G03Y1081048I-772J1257D01*
G01X1407590Y1081068D01*
G02X1406478Y1082956I1113J1927D01*
G01Y1083082D01*
G02X1407589Y1084923I2225J-87D01*
G01X1407624Y1084943D01*
G03Y1087457I-771J1257D01*
G01X1407593Y1087475D01*
X1407589Y1087477D01*
G02X1406478Y1089343I1114J1927D01*
G01Y1089443D01*
G02X1407590Y1091331I2225J-39D01*
G01X1407625Y1091351D01*
G03X1408328Y1092582I-772J1257D01*
G03X1408327Y1092656I-1475J17D01*
G03X1407625Y1093865I-1474J-48D01*
G01X1407590Y1093885D01*
G02X1406478Y1095740I1113J1928D01*
G01Y1095813D01*
G03X1405775Y1097070I-1475J0D01*
G01X1405740Y1097090D01*
G02X1404628Y1098978I1113J1927D01*
G01Y1099056D01*
G02X1405740Y1100944I2225J-39D01*
G01X1405775Y1100964D01*
G03X1406478Y1102195I-772J1257D01*
G03X1406477Y1102269I-1475J17D01*
G03X1405775Y1103478I-1474J-48D01*
G01X1405740Y1103498D01*
G02X1404628Y1105353I1113J1928D01*
G01Y1105465D01*
G02X1405740Y1107353I2225J-39D01*
G01X1405775Y1107373D01*
G03Y1109887I-772J1257D01*
G01X1405740Y1109907D01*
G02X1404628Y1111795I1113J1927D01*
G01Y1111907D01*
G02X1405740Y1113762I2225J-73D01*
G01X1405775Y1113782D01*
G03X1406477Y1114991I-772J1257D01*
G03X1406478Y1115065I-1474J57D01*
G03X1405775Y1116296I-1475J-26D01*
G01X1405740Y1116316D01*
G02X1404628Y1118204I1113J1927D01*
G01Y1118277D01*
G03X1403891Y1119520I-1474J-34D01*
G01X1403867Y1119534D01*
G02Y1123360I1137J1913D01*
G01X1403891Y1123374D01*
G03X1404628Y1124617I-737J1277D01*
G01Y1124685D01*
G03X1403891Y1125928I-1474J-34D01*
G02X1402778Y1127800I1112J1928D01*
G01Y1127856D01*
G02X1403867Y1129769I2225J0D01*
G01X1403891Y1129783D01*
G03X1404628Y1131026I-737J1277D01*
G01Y1131094D01*
G03X1403891Y1132337I-1474J-34D01*
G01X1403867Y1132351D01*
G02X1402778Y1134264I1136J1913D01*
G01Y1134709D01*
G02X1403895Y1136244I2225J-445D01*
G03X1404647Y1137299I-742J1324D01*
G01X1404629Y1137648D01*
X1404602Y1138152D01*
G03X1403899Y1138941I-1448J-583D01*
G02X1402778Y1140342I1104J2032D01*
G01Y1142199D01*
X1402388Y1142589D01*
Y1143279D01*
X1402778Y1143669D01*
Y1144359D01*
X1402388Y1144749D01*
Y1145439D01*
X1402778Y1145829D01*
Y1146519D01*
X1402388Y1146909D01*
Y1147599D01*
X1402778Y1147989D01*
Y1148679D01*
X1402388Y1149069D01*
Y1149759D01*
X1402778Y1150149D01*
Y1152707D01*
X1402613Y1152872D01*
Y1152959D01*
G01X330665Y1141200D02*
X330726Y1141139D01*
Y1140903D01*
X332039Y1139590D01*
Y1124649D01*
X333476Y1121183D01*
X334389Y1120269D01*
X335447D01*
X335621Y1120172D01*
X335624Y1120170D01*
G02X336736Y1118282I-1113J-1927D01*
G01Y1118243D01*
G03X337439Y1116986I1475J0D01*
G01X337474Y1116966D01*
G02X338586Y1115078I-1113J-1927D01*
G01Y1115039D01*
G03X339289Y1113782I1475J0D01*
G01X339324Y1113762D01*
G02X340437Y1111864I-1113J-1928D01*
G01Y1111834D01*
G03X341140Y1110577I1475J0D01*
G01X341175Y1110557D01*
X341199Y1110543D01*
G02X342287Y1108630I-1138J-1913D01*
G03X342990Y1107373I1475J0D01*
G01X343021Y1107355D01*
X343025Y1107353D01*
G02X344111Y1105767I-1114J-1927D01*
G02X344122Y1105684I-2201J-334D01*
G01X344380Y1105426D01*
X345611D01*
G01X1395753D02*
X1394522D01*
X1394296Y1105200D01*
G03X1397227Y1105368I1457J227D01*
G03X1397228Y1105426I-1474J54D01*
G02X1398317Y1107339I2225J0D01*
G01X1398338Y1107351D01*
X1398341Y1107353D01*
X1398347Y1107356D01*
X1398376Y1107373D01*
G03X1399079Y1108630I-772J1257D01*
G01Y1108691D01*
G02X1400190Y1110557I2225J-61D01*
G01X1400194Y1110559D01*
X1400225Y1110577D01*
G03X1400928Y1111834I-772J1257D01*
G01Y1111864D01*
G02X1402041Y1113762I2226J-30D01*
G03X1402778Y1114991I-737J1277D01*
G03X1402779Y1115065I-1474J57D01*
G03X1402041Y1116316I-1474J-27D01*
G01X1401993Y1116344D01*
G02X1400928Y1118243I1161J1899D01*
G03X1400225Y1119500I-1475J0D01*
G01X1400166Y1119534D01*
G02X1399078Y1121447I1138J1913D01*
G03X1398375Y1122704I-1475J0D01*
G01X1398340Y1122724D01*
G02Y1126579I1113J1928D01*
G01X1398375Y1126599D01*
G03Y1129113I-772J1257D01*
G01X1398340Y1129133D01*
G02Y1132987I1112J1927D01*
G01X1398375Y1133007D01*
G03Y1135521I-772J1257D01*
G01X1398376D01*
X1398344Y1135539D01*
X1398341Y1135541D01*
G02X1397229Y1137396I1113J1928D01*
G01Y1138247D01*
G02X1398353Y1139553I2225J-778D01*
G03X1399078Y1140338I-750J1420D01*
G01Y1141911D01*
X1398688Y1142301D01*
Y1142991D01*
X1399078Y1143381D01*
Y1144753D01*
X1398591Y1145240D01*
X1398038D01*
X1397550Y1145728D01*
Y1146281D01*
X1397063Y1146768D01*
X1396510D01*
X1396022Y1147256D01*
Y1147809D01*
X1395535Y1148296D01*
X1394982D01*
X1394494Y1148784D01*
Y1149337D01*
X1393916Y1149915D01*
X1393363D01*
X1392875Y1150403D01*
Y1150956D01*
X1392488Y1151343D01*
Y1152133D01*
X1392098Y1152523D01*
Y1153213D01*
X1392488Y1153603D01*
Y1154524D01*
X1392098Y1154914D01*
Y1155604D01*
X1392488Y1155994D01*
Y1156684D01*
X1392098Y1157074D01*
Y1157764D01*
X1392488Y1158154D01*
Y1160337D01*
X1392323Y1160502D01*
Y1160589D01*
G01X332724Y1143749D02*
X332785Y1143688D01*
Y1143452D01*
X334834Y1141403D01*
Y1125940D01*
X337167Y1123607D01*
G03X337439Y1123394I1039J1047D01*
G01X337474Y1123374D01*
G03X338948I737J1277D01*
G02X341174I1113J-1927D01*
G02X342286Y1121486I-1113J-1927D01*
G01Y1121386D01*
G02X341175Y1119520I-2225J61D01*
G01X341171Y1119518D01*
X341140Y1119500D01*
G03Y1116986I772J-1257D01*
G01X341167Y1116970D01*
X341175Y1116966D01*
G02X342286Y1115100I-1114J-1927D01*
G01Y1115039D01*
G03X342989Y1113782I1475J0D01*
G01X343024Y1113762D01*
G02X344137Y1111890I-1112J-1928D01*
G01Y1111795D01*
G02X343306Y1110099I-2225J39D01*
G02X343241Y1110048I-1406J1725D01*
G01X343146Y1109697D01*
X343762Y1108630D01*
G01X1392053Y1105426D02*
X1393284D01*
X1393542Y1105168D01*
G03X1393553Y1105085I2212J251D01*
G03X1394641Y1103498I2199J341D01*
G01X1394699Y1103464D01*
G03X1396867Y1103498I1053J1962D01*
G03X1397978Y1105339I-1114J1928D01*
G01Y1105426D01*
G02X1398681Y1106683I1475J0D01*
G01X1398710Y1106700D01*
X1398716Y1106703D01*
X1398727Y1106709D01*
X1398740Y1106717D01*
G03X1399829Y1108630I-1136J1913D01*
G02X1400532Y1109887I1475J0D01*
G01X1400567Y1109907D01*
X1400591Y1109921D01*
G03X1401679Y1111834I-1138J1913D01*
G02X1402382Y1113091I1475J0D01*
G01X1402417Y1113111D01*
G03X1403529Y1114966I-1113J1928D01*
G01Y1115078D01*
G03X1402417Y1116966I-2225J-39D01*
G01X1402382Y1116986D01*
G02X1401679Y1118243I772J1257D01*
G03X1400591Y1120156I-2226J0D01*
G01X1400567Y1120170D01*
X1400532Y1120190D01*
G02X1399829Y1121447I772J1257D01*
G03X1398764Y1123346I-2226J0D01*
G01X1398716Y1123374D01*
G02X1397979Y1124617I737J1277D01*
G01Y1124685D01*
G02X1398716Y1125928I1474J-34D01*
G03X1399829Y1127826I-1113J1928D01*
G01Y1127856D01*
G03X1398764Y1129755I-2226J0D01*
G01X1398716Y1129783D01*
G02X1397979Y1131026I737J1277D01*
G01Y1131094D01*
G02X1398716Y1132337I1474J-34D01*
G01X1398721Y1132340D01*
X1398764Y1132365D01*
G03X1399829Y1134264I-1161J1899D01*
G01Y1134320D01*
G03X1398717Y1136192I-2226J-56D01*
G01X1398713Y1136194D01*
X1398682Y1136212D01*
G02X1397979Y1137469I772J1257D01*
G01Y1138104D01*
G02X1398704Y1138889I1475J-635D01*
G01X1398703Y1138890D01*
G03X1399827Y1140198I-1100J2082D01*
G01Y1145064D01*
X1393237Y1151654D01*
Y1160336D01*
X1393403Y1160502D01*
Y1160589D01*
G01X331960Y1142985D02*
X332021Y1142924D01*
X332253D01*
X334085Y1141092D01*
Y1125629D01*
X336637Y1123077D01*
G03X337098Y1122724I1572J1575D01*
G03X339324I1113J1927D01*
G02X340798I737J-1277D01*
G01X340833Y1122704D01*
G02X341536Y1121473I-772J-1257D01*
G02Y1121407I-1475J-33D01*
G02X340833Y1120190I-1475J40D01*
G01X340798Y1120170D01*
X340799Y1120169D01*
X340795Y1120167D01*
X340756Y1120145D01*
G03Y1116341I1156J-1902D01*
G01X340790Y1116322D01*
X340834Y1116295D01*
G02X341536Y1115088I-773J-1257D01*
G01Y1115039D01*
G03X342607Y1113135I2226J-1D01*
G01X342650Y1113111D01*
G02X343387Y1111879I-738J-1278D01*
G01Y1111803D01*
G02X342836Y1110684I-1475J31D01*
G01X342835Y1110685D01*
X342528Y1110767D01*
X341912Y1111834D01*
G01X1393904Y1108630D02*
X1394520Y1109697D01*
X1394870Y1109790D01*
G03X1394947Y1109758I892J2037D01*
G03X1396867Y1109907I805J2073D01*
G03X1397978Y1111773I-1114J1927D01*
G01Y1111834D01*
G02X1398681Y1113091I1475J0D01*
G01X1398716Y1113111D01*
G03X1399829Y1114983I-1112J1928D01*
G01Y1115039D01*
G03X1398740Y1116952I-2225J0D01*
G01X1398719Y1116964D01*
X1398716Y1116966D01*
G02X1397979Y1118209I737J1277D01*
G01Y1118243D01*
G03X1396890Y1120156I-2225J0D01*
G01X1396831Y1120191D01*
Y1120190D01*
G02X1396128Y1121447I772J1257D01*
G01Y1121508D01*
G03X1395017Y1123374I-2225J-61D01*
G01X1394982Y1123394D01*
G02X1394280Y1124611I773J1257D01*
G02X1394281Y1124709I1475J34D01*
G02X1394982Y1125908I1474J-57D01*
G01X1395017Y1125928D01*
G03X1396128Y1127769I-1114J1928D01*
G01Y1127917D01*
G03X1395017Y1129783I-2225J-61D01*
G01X1394982Y1129803D01*
G02X1394279Y1131060I772J1257D01*
G01Y1131099D01*
G03X1393167Y1132987I-2225J-39D01*
G01X1393132Y1133007D01*
G02X1392429Y1134264I772J1257D01*
G01Y1134337D01*
G03X1391317Y1136192I-2225J-73D01*
G01X1391282Y1136212D01*
G02X1390579Y1137469I772J1257D01*
G01Y1138104D01*
G02X1391304Y1138889I1475J-635D01*
G01Y1138891D01*
G03X1392427Y1140198I-1101J2082D01*
G01Y1146817D01*
X1389900Y1149344D01*
Y1161846D01*
X1390066Y1162012D01*
Y1162099D01*
G01X332911Y1146646D02*
X332972Y1146585D01*
X333204D01*
X336239Y1143550D01*
Y1135148D01*
X339686Y1131701D01*
Y1131060D01*
G02X338983Y1129803I-1475J0D01*
G01X338948Y1129783D01*
G03X337836Y1127895I1113J-1927D01*
G01Y1127783D01*
G03X341174Y1125928I2225J73D01*
G02X343386Y1124651I737J-1277D01*
G01Y1123871D01*
X343528D01*
G03X344496Y1122727I2083J781D01*
G01X344532Y1122706D01*
G02X344536Y1120190I-771J-1259D01*
G01X344503Y1120172D01*
G03X344499Y1116317I1107J-1929D01*
G02X345237Y1115070I-738J-1279D01*
G01Y1115038D01*
G03X346067Y1113306I2224J1D01*
G01X346065Y1113304D01*
G03X346132Y1113252I1398J1732D01*
G01X346227Y1112901D01*
X345611Y1111834D01*
G01X1395753D02*
X1395137Y1110767D01*
X1395220Y1110460D01*
G03X1396490Y1110557I534J1374D01*
G01X1396525Y1110577D01*
G03X1397228Y1111834I-772J1257D01*
G01Y1111890D01*
G02X1398341Y1113762I2225J-56D01*
G01X1398376Y1113782D01*
G03Y1116296I-771J1257D01*
G01X1398316Y1116331D01*
X1398317Y1116330D01*
G02X1397228Y1118243I1136J1913D01*
G01Y1118277D01*
G03X1396491Y1119520I-1474J-34D01*
G01X1396488Y1119522D01*
X1396467Y1119534D01*
G02X1395378Y1121447I1136J1913D01*
G03X1394675Y1122704I-1475J0D01*
G01X1394640Y1122724D01*
G02X1393529Y1124590I1114J1927D01*
G01Y1124738D01*
G02X1394640Y1126579I2225J-87D01*
G01X1394675Y1126599D01*
G03X1395377Y1127798I-772J1257D01*
G03X1395378Y1127896I-1474J64D01*
G03X1394675Y1129113I-1475J-40D01*
G01X1394640Y1129133D01*
G02X1393529Y1130999I1114J1927D01*
G01Y1131060D01*
G03X1392826Y1132317I-1475J0D01*
G01X1392791Y1132337D01*
G02X1391679Y1134225I1113J1927D01*
G01Y1134264D01*
G03X1390976Y1135521I-1475J0D01*
G01X1390944Y1135539D01*
X1390941Y1135541D01*
G02X1389829Y1137396I1113J1928D01*
G01Y1138247D01*
G02X1390953Y1139553I2225J-778D01*
G03X1391678Y1140338I-750J1420D01*
G01Y1141594D01*
X1391288Y1141984D01*
Y1142674D01*
X1391678Y1143064D01*
Y1143754D01*
X1391288Y1144144D01*
Y1144834D01*
X1391678Y1145224D01*
Y1146506D01*
X1390850Y1147334D01*
X1390297D01*
X1389809Y1147822D01*
Y1148375D01*
X1389151Y1149033D01*
Y1157264D01*
X1388761Y1157654D01*
Y1158344D01*
X1389151Y1158734D01*
Y1161847D01*
X1388986Y1162012D01*
Y1162099D01*
G01X333675Y1147410D02*
X333736Y1147349D01*
Y1147113D01*
X336988Y1143861D01*
Y1142617D01*
X337378Y1142227D01*
Y1141527D01*
X336988Y1141137D01*
Y1140437D01*
X337378Y1140047D01*
Y1139347D01*
X336988Y1138957D01*
Y1138257D01*
X337378Y1137867D01*
Y1137167D01*
X336988Y1136777D01*
Y1135459D01*
X337352Y1135095D01*
X337905D01*
X338400Y1134600D01*
Y1134047D01*
X338894Y1133553D01*
X339447D01*
X339942Y1133058D01*
Y1132505D01*
X340435Y1132012D01*
Y1131019D01*
X340436Y1131021D01*
G02X339324Y1129133I-2225J39D01*
G01X339321Y1129131D01*
X339289Y1129113D01*
G03X338586Y1127856I772J-1257D01*
G01X338585D01*
Y1127797D01*
G03X340800Y1126577I1476J59D01*
G02X344135Y1124652I1111J-1926D01*
G01Y1124620D01*
X344136D01*
G03X344230Y1124134I1475J33D01*
G03X344872Y1123375I1381J517D01*
G01X344915Y1123350D01*
G02Y1119543I-1153J-1903D01*
G01X344874Y1119520D01*
G03Y1116966I737J-1277D01*
G02X345986Y1115078I-1113J-1927D01*
G01Y1115039D01*
G03X346537Y1113890I1475J1D01*
G01X346845Y1113972D01*
X347461Y1115039D01*
G01X1390204Y1102221D02*
X1389588Y1103288D01*
X1389683Y1103639D01*
G03X1390578Y1105369I-1332J1786D01*
G01X1390579Y1105425D01*
G02X1391282Y1106682I1475J0D01*
G01X1391317Y1106702D01*
G03X1392429Y1108557I-1113J1928D01*
G01Y1108630D01*
G02X1393132Y1109887I1475J0D01*
G01X1393167Y1109907D01*
X1393191Y1109921D01*
G03X1394279Y1111833I-1138J1913D01*
G01Y1111861D01*
G02X1395017Y1113111I1475J-28D01*
G03X1396129Y1114983I-1114J1928D01*
G01Y1115039D01*
G03X1395041Y1116952I-2226J0D01*
G01X1395017Y1116966D01*
X1394982Y1116986D01*
G02X1394279Y1118243I772J1257D01*
G03X1393214Y1120142I-2226J0D01*
G01X1393166Y1120170D01*
X1393131Y1120190D01*
G02X1392428Y1121447I772J1257D01*
G01Y1121508D01*
G03X1391317Y1123374I-2225J-61D01*
G01X1391313Y1123376D01*
X1391282Y1123394D01*
G02Y1125908I772J1257D01*
G01X1391317Y1125928D01*
G03X1392429Y1127783I-1113J1928D01*
G01Y1127895D01*
G03X1391317Y1129783I-2225J-39D01*
G01X1391282Y1129803D01*
G02X1390579Y1131060I772J1257D01*
G01Y1131099D01*
G03X1389467Y1132987I-2225J-39D01*
G01X1389432Y1133007D01*
G02X1388729Y1134264I772J1257D01*
G01Y1134337D01*
G03X1387617Y1136192I-2225J-73D01*
G01X1387582Y1136212D01*
G02X1386879Y1137469I772J1257D01*
G01Y1138104D01*
G02X1387604Y1138889I1475J-635D01*
G03X1388728Y1140195I-1101J2084D01*
G01Y1143384D01*
X1388727Y1143385D01*
Y1146088D01*
X1382190Y1152625D01*
Y1155556D01*
X1382356Y1155722D01*
Y1155809D01*
G01X340226Y1138809D02*
Y1138722D01*
X340391Y1138557D01*
Y1136272D01*
X341537Y1135126D01*
Y1134223D01*
X341536Y1134225D01*
G03X342648Y1132337I2225J39D01*
G01X342651Y1132335D01*
X342683Y1132317D01*
G02X343386Y1131060I-772J-1257D01*
G01Y1131021D01*
G03X344498Y1129133I2225J39D01*
G03X346724I1113J1927D01*
G02X348198I737J-1277D01*
G01X348233Y1129113D01*
G02Y1126599I-772J-1257D01*
G01X348201Y1126581D01*
X348198Y1126579D01*
G03X347086Y1124724I1113J-1928D01*
G01Y1124612D01*
G03X348198Y1122724I2225J39D01*
G01X348233Y1122704D01*
G02X348936Y1121447I-772J-1257D01*
G03X350025Y1119534I2225J0D01*
G01X350046Y1119522D01*
X350049Y1119520D01*
G02X350786Y1118277I-737J-1277D01*
G01Y1118209D01*
G02X350049Y1116966I-1474J34D01*
G01X350046Y1116964D01*
X350025Y1116952D01*
G03X348936Y1115039I1136J-1913D01*
G02X348935Y1114981I-1475J-4D01*
G02X348233Y1113782I-1474J58D01*
G01X348198Y1113762D01*
G03X347086Y1111890I1114J-1928D01*
G01Y1111834D01*
G03X348174Y1109921I2226J0D01*
G01X348198Y1109907D01*
X348233Y1109887D01*
G02X348936Y1108630I-772J-1257D01*
G03X350024Y1106717I2226J0D01*
G01X350048Y1106703D01*
X350083Y1106683D01*
G02X350786Y1105426I-772J-1257D01*
G01Y1105353D01*
G03X351898Y1103498I2225J73D01*
G01X351901Y1103496D01*
X351933Y1103478D01*
G02X352618Y1102447I-773J-1256D01*
G01X352392Y1102221D01*
X351161D01*
G01X1388353Y1105426D02*
X1388969Y1104359D01*
X1389277Y1104277D01*
G03X1389828Y1105426I-924J1150D01*
G01X1389829Y1105456D01*
G02X1390941Y1107353I2226J-30D01*
G01X1390976Y1107373D01*
G03X1391679Y1108630I-772J1257D01*
G01Y1108691D01*
G02X1392790Y1110557I2225J-61D01*
G01X1392794Y1110559D01*
X1392825Y1110577D01*
G03X1393528Y1111834I-772J1257D01*
G01X1393529Y1111890D01*
G02X1394640Y1113761I2226J-56D01*
G03X1395378Y1115011I-737J1278D01*
G01Y1115039D01*
G03X1394675Y1116296I-1475J0D01*
G01X1394640Y1116316D01*
X1394616Y1116330D01*
G02X1393528Y1118243I1138J1913D01*
G03X1392825Y1119500I-1475J0D01*
G01X1392793Y1119518D01*
X1392790Y1119520D01*
G02X1391678Y1121408I1113J1927D01*
G01Y1121447D01*
G03X1390975Y1122704I-1475J0D01*
G01X1390940Y1122724D01*
X1390916Y1122738D01*
G02X1389828Y1124651I1138J1913D01*
G01Y1124681D01*
G02X1390941Y1126579I2226J-30D01*
G03X1391678Y1127822I-737J1277D01*
G01Y1127890D01*
G03X1390941Y1129133I-1474J-34D01*
G02X1389829Y1131021I1113J1927D01*
G01Y1131060D01*
G03X1389126Y1132317I-1475J0D01*
G01X1389091Y1132337D01*
G02X1387979Y1134225I1113J1927D01*
G01Y1134264D01*
G03X1387276Y1135521I-1475J0D01*
G01X1387241Y1135541D01*
G02X1386129Y1137396I1113J1928D01*
G01Y1138247D01*
G02X1387253Y1139553I2225J-778D01*
G01Y1139552D01*
G03X1387978Y1140335I-750J1421D01*
G01Y1141915D01*
X1387588Y1142305D01*
Y1142995D01*
X1387978Y1143385D01*
Y1145777D01*
X1387491Y1146264D01*
X1386938D01*
X1386450Y1146752D01*
Y1147305D01*
X1385669Y1148086D01*
X1385116D01*
X1384628Y1148574D01*
Y1149127D01*
X1381441Y1152314D01*
Y1155557D01*
X1381276Y1155722D01*
Y1155809D01*
G01X341306Y1138809D02*
Y1138722D01*
X341140Y1138556D01*
Y1136583D01*
X342286Y1135437D01*
Y1134264D01*
G03X342989Y1133007I1475J0D01*
G01X343024Y1132987D01*
G02X344136Y1131099I-1113J-1927D01*
G01Y1131060D01*
G03X344839Y1129803I1475J0D01*
G01X344874Y1129783D01*
G03X346348I737J1277D01*
G02X348574I1113J-1927D01*
G01X348622Y1129755D01*
G02X349687Y1127856I-1161J-1899D01*
G01Y1127826D01*
G02X348574Y1125928I-2226J30D01*
G01X348539Y1125908D01*
G03X347837Y1124699I772J-1257D01*
G03X347836Y1124625I1474J-57D01*
G03X348539Y1123394I1475J26D01*
G01X348574Y1123374D01*
G02X349686Y1121486I-1113J-1927D01*
G01Y1121447D01*
G03X350389Y1120190I1475J0D01*
G01X350448Y1120155D01*
Y1120156D01*
G02Y1116330I-1137J-1913D01*
G01X350389Y1116295D01*
Y1116296D01*
G03X349686Y1115039I772J-1257D01*
G01Y1114952D01*
G02X348575Y1113111I-2225J87D01*
G01X348540Y1113091D01*
G03Y1110577I771J-1257D01*
G01X348575Y1110557D01*
X348599Y1110543D01*
G02X349687Y1108630I-1138J-1913D01*
G03X350390Y1107373I1475J0D01*
G01X350421Y1107355D01*
X350425Y1107353D01*
G02X351536Y1105487I-1114J-1927D01*
G01Y1105426D01*
G03X352239Y1104169I1475J0D01*
G01X352274Y1104149D01*
G02X353362Y1102563I-1112J-1929D01*
G02X353373Y1102478I-2202J-328D01*
G01X353630Y1102221D01*
X354861D01*
G01X1392053Y1111834D02*
X1391437Y1112901D01*
X1391532Y1113252D01*
G03X1391599Y1113303I-1314J1796D01*
G03X1392429Y1114983I-1395J1734D01*
G01Y1115039D01*
G03X1391340Y1116952I-2225J0D01*
G01X1391327Y1116960D01*
X1391316Y1116966D01*
X1391310Y1116969D01*
X1391281Y1116986D01*
G02X1390578Y1118243I772J1257D01*
G01Y1118282D01*
G03X1389466Y1120170I-2225J-39D01*
G02X1388729Y1121413I737J1277D01*
G01Y1121447D01*
G03X1387640Y1123360I-2225J0D01*
G01X1387581Y1123394D01*
G02Y1125908I772J1257D01*
G01X1387613Y1125926D01*
X1387616Y1125928D01*
G03X1388729Y1127826I-1113J1928D01*
G01Y1127856D01*
G03X1387641Y1129769I-2226J0D01*
G01X1387617Y1129783D01*
X1387582Y1129803D01*
G02X1386879Y1131060I772J1257D01*
G03X1385791Y1132973I-2226J0D01*
G01X1385767Y1132987D01*
X1385732Y1133007D01*
G02X1385029Y1134264I772J1257D01*
G01Y1134337D01*
G03X1383917Y1136192I-2225J-73D01*
G01X1383882Y1136212D01*
G02X1383179Y1137469I772J1257D01*
G01Y1138104D01*
G02X1383904Y1138889I1475J-635D01*
G03X1385028Y1140195I-1101J2084D01*
G01Y1144637D01*
X1378541Y1151124D01*
Y1153367D01*
X1378706Y1153532D01*
Y1153619D01*
G01X341817Y1146971D02*
X341878Y1146910D01*
X342110D01*
X343386Y1145634D01*
Y1136546D01*
X344037Y1135895D01*
G03X344533Y1135521I1575J1573D01*
G02X345236Y1134264I-772J-1257D01*
G01Y1134225D01*
G03X346348Y1132337I2225J39D01*
G03X348574I1113J1927D01*
G02X350786Y1131060I737J-1277D01*
G03X351875Y1129147I2225J0D01*
G01X351896Y1129135D01*
X351899Y1129133D01*
G02Y1126579I-737J-1277D01*
G03X351898Y1122724I1112J-1928D01*
G01X351933Y1122704D01*
G02X352636Y1121447I-772J-1257D01*
G01Y1121408D01*
G03X353748Y1119520I2225J39D01*
G01X353783Y1119500D01*
G02Y1116986I-772J-1257D01*
G01X353748Y1116966D01*
G03X352636Y1115078I1113J-1927D01*
G01Y1115039D01*
G02X351933Y1113782I-1475J0D01*
G01X351898Y1113762D01*
G03X350811Y1112174I1113J-1928D01*
G03X350799Y1112089I2198J-354D01*
G01X350543Y1111833D01*
X349313D01*
X349312Y1111834D01*
G01X1390204Y1115039D02*
X1390820Y1113972D01*
X1391127Y1113890D01*
G03X1391678Y1115005I-923J1150D01*
G01Y1115073D01*
G03X1390941Y1116316I-1474J-34D01*
G01X1390938Y1116318D01*
X1390917Y1116330D01*
G02X1389828Y1118243I1136J1913D01*
G03X1389125Y1119500I-1475J0D01*
G01X1389090Y1119520D01*
G02X1387978Y1121408I1113J1927D01*
G01Y1121481D01*
G03X1387241Y1122724I-1474J-34D01*
G01X1387238Y1122726D01*
X1387217Y1122738D01*
G02X1386128Y1124651I1136J1913D01*
G01Y1124724D01*
G02X1387240Y1126579I2225J-73D01*
G01X1387275Y1126599D01*
G03Y1129113I-772J1257D01*
G01X1387240Y1129133D01*
X1387216Y1129147D01*
G02X1386128Y1131060I1138J1913D01*
G03X1385425Y1132317I-1475J0D01*
G01X1385394Y1132335D01*
X1385390Y1132337D01*
G02X1384279Y1134203I1114J1927D01*
G01Y1134264D01*
G03X1383576Y1135521I-1475J0D01*
G01X1383541Y1135541D01*
G02X1382429Y1137396I1113J1928D01*
G01Y1138247D01*
G02X1383553Y1139553I2225J-778D01*
G03X1384278Y1140338I-750J1420D01*
G01X1384279Y1140340D01*
Y1141627D01*
X1383889Y1142017D01*
Y1142707D01*
X1384279Y1143097D01*
Y1144326D01*
X1382264Y1146341D01*
X1381711D01*
X1381223Y1146829D01*
Y1147382D01*
X1380736Y1147869D01*
X1380183D01*
X1379695Y1148357D01*
Y1148910D01*
X1377791Y1150814D01*
Y1153367D01*
X1377626Y1153532D01*
Y1153619D01*
G01X342581Y1147735D02*
X342642Y1147674D01*
Y1147438D01*
X344135Y1145945D01*
Y1141929D01*
X344525Y1141539D01*
Y1140839D01*
X344135Y1140449D01*
Y1139749D01*
X344525Y1139359D01*
Y1138659D01*
X344135Y1138269D01*
Y1136857D01*
X344567Y1136425D01*
G03X344874Y1136192I1038J1049D01*
G02X345986Y1134337I-1113J-1928D01*
G01Y1134264D01*
G03X346689Y1133007I1475J0D01*
G01X346724Y1132987D01*
G03X348198I737J1277D01*
G02X351536Y1131099I1113J-1927D01*
G01Y1131060D01*
G03X352239Y1129803I1475J0D01*
G01X352268Y1129786D01*
X352298Y1129769D01*
G02X352274Y1125928I-1136J-1913D01*
G01X352239Y1125908D01*
G03Y1123394I772J-1257D01*
G01X352274Y1123374D01*
G02X353386Y1121486I-1113J-1927D01*
G01Y1121447D01*
G03X354089Y1120190I1475J0D01*
G01X354124Y1120170D01*
G02Y1116316I-1113J-1927D01*
G01X354089Y1116296D01*
G03X353386Y1115039I772J-1257D01*
G01Y1114966D01*
G02X352274Y1113111I-2225J73D01*
G03X351555Y1112059I738J-1276D01*
G01X351780Y1111834D01*
X353012D01*
G01X1388353D02*
X1387122D01*
X1386896Y1111608D01*
G03X1387610Y1110560I1458J226D01*
G01X1387616Y1110557D01*
G03X1389827Y1111794I737J1277D01*
G03X1389826Y1111892I-1474J34D01*
G03X1389125Y1113091I-1473J-57D01*
G01X1389094Y1113109D01*
X1389090Y1113111D01*
G02X1387978Y1114983I1114J1928D01*
G01Y1115039D01*
G03X1387275Y1116296I-1475J0D01*
G01X1387243Y1116314D01*
X1387240Y1116316D01*
G02X1386128Y1118204I1113J1927D01*
G01Y1118243D01*
G03X1385425Y1119500I-1475J0D01*
G01X1385390Y1119520D01*
G02X1384279Y1121386I1114J1927D01*
G01Y1121447D01*
G03X1383576Y1122704I-1475J0D01*
G01X1383540Y1122724D01*
G02X1382428Y1124612I1113J1927D01*
G01Y1124707D01*
G02X1383541Y1126579I2225J-56D01*
G03X1384278Y1127822I-737J1277D01*
G01Y1127890D01*
G03X1383541Y1129133I-1474J-34D01*
G01X1383538Y1129135D01*
X1383517Y1129147D01*
G02X1382428Y1131060I1136J1913D01*
G03X1381725Y1132317I-1475J0D01*
G01X1381690Y1132337D01*
G02X1380579Y1134203I1114J1927D01*
G01Y1134264D01*
G03X1379876Y1135521I-1475J0D01*
G01X1379841Y1135541D01*
G02X1378729Y1137396I1113J1928D01*
G01Y1138247D01*
G02X1379853Y1139553I2225J-778D01*
G01X1379854D01*
G03X1380578Y1140338I-751J1419D01*
G01Y1142842D01*
X1379998Y1143422D01*
X1379473D01*
X1378985Y1143910D01*
Y1144463D01*
X1371381Y1152067D01*
Y1154667D01*
X1370991Y1155057D01*
Y1155747D01*
X1371381Y1156137D01*
Y1156827D01*
X1370991Y1157217D01*
Y1157907D01*
X1371381Y1158297D01*
Y1158987D01*
X1370991Y1159377D01*
Y1160067D01*
X1371381Y1160457D01*
Y1161147D01*
X1370991Y1161537D01*
Y1162227D01*
X1371381Y1162617D01*
Y1163307D01*
X1370991Y1163697D01*
Y1164387D01*
X1371381Y1164777D01*
Y1165747D01*
X1370991Y1166137D01*
Y1166827D01*
X1371381Y1167217D01*
Y1172047D01*
X1371216Y1172212D01*
Y1172299D01*
G01X344947Y1150002D02*
X345008Y1149941D01*
Y1149705D01*
X347423Y1147290D01*
Y1142719D01*
X349252Y1140890D01*
Y1140891D01*
X351537Y1138606D01*
Y1137435D01*
G03X352274Y1136192I1474J34D01*
G02X353386Y1134337I-1113J-1928D01*
G01Y1134264D01*
G03X354089Y1133007I1475J0D01*
G01X354172Y1132959D01*
G02X355237Y1131060I-1161J-1899D01*
G03X355940Y1129803I1475J0D01*
G01X355956Y1129794D01*
X355971Y1129785D01*
X355975Y1129783D01*
G02X357086Y1127917I-1114J-1927D01*
G01Y1127769D01*
G02X355975Y1125928I-2225J87D01*
G01X355940Y1125908D01*
G03Y1123394I771J-1257D01*
G01X355956Y1123385D01*
X355971Y1123376D01*
X355975Y1123374D01*
G02X357086Y1121508I-1114J-1927D01*
G01Y1121447D01*
G03X357789Y1120190I1475J0D01*
G01X357824Y1120170D01*
G02Y1116316I-1113J-1927D01*
G01X357789Y1116296D01*
G03X357086Y1115039I772J-1257D01*
G01Y1114952D01*
G02X355975Y1113111I-2225J87D01*
G01X355940Y1113091D01*
G03X355238Y1111892I772J-1257D01*
G03X355237Y1111834I1474J-54D01*
G02X354148Y1109921I-2225J0D01*
G01X354127Y1109909D01*
X354124Y1109907D01*
G03X353387Y1108664I737J-1277D01*
G01Y1108630D01*
G02X352490Y1106844I-2223J-2D01*
G01X352395Y1106493D01*
X353011Y1105426D01*
G01X1384653Y1111834D02*
X1385884D01*
X1386143Y1111575D01*
G03X1386154Y1111493I2210J255D01*
G03X1387217Y1109921I2199J341D01*
G01X1387238Y1109909D01*
X1387241Y1109907D01*
X1387299Y1109873D01*
G03X1390578Y1111773I1054J1961D01*
G01Y1111921D01*
G03X1389467Y1113762I-2225J-87D01*
G01X1389432Y1113782D01*
G02X1388729Y1115039I772J1257D01*
G03X1387664Y1116938I-2226J0D01*
G01X1387616Y1116966D01*
X1387581Y1116986D01*
G02X1386878Y1118243I772J1257D01*
G01Y1118304D01*
G03X1385767Y1120170I-2225J-61D01*
G01X1385732Y1120190D01*
G02X1385029Y1121447I772J1257D01*
G03X1383940Y1123360I-2225J0D01*
G01X1383927Y1123368D01*
X1383921Y1123371D01*
X1383916Y1123374D01*
X1383881Y1123394D01*
G02X1383178Y1124625I772J1257D01*
G02Y1124688I1475J32D01*
G02X1383881Y1125908I1475J-37D01*
G01X1383916Y1125928D01*
G03X1385029Y1127800I-1112J1928D01*
G01Y1127856D01*
G03X1383940Y1129769I-2225J0D01*
G01X1383927Y1129777D01*
X1383916Y1129783D01*
X1383910Y1129786D01*
X1383881Y1129803D01*
G02X1383178Y1131060I772J1257D01*
G01Y1131121D01*
G03X1382067Y1132987I-2225J-61D01*
G01X1382032Y1133007D01*
G02X1381329Y1134264I772J1257D01*
G01Y1134337D01*
G03X1380217Y1136192I-2225J-73D01*
G01X1380182Y1136212D01*
G02X1379479Y1137469I772J1257D01*
G01Y1138104D01*
G02X1380204Y1138889I1475J-635D01*
G01X1380203Y1138890D01*
X1380205Y1138891D01*
G03X1381327Y1140199I-1103J2081D01*
G01Y1143153D01*
X1380528Y1143952D01*
Y1143980D01*
X1372130Y1152378D01*
Y1172046D01*
X1372296Y1172212D01*
Y1172299D01*
G01X344183Y1149238D02*
X344244Y1149177D01*
X344476D01*
X346674Y1146979D01*
Y1145168D01*
X346294Y1144788D01*
Y1143788D01*
X346674Y1143408D01*
Y1142408D01*
X348503Y1140579D01*
Y1140041D01*
X349211Y1139333D01*
X349749D01*
X350786Y1138296D01*
Y1137396D01*
G03X351898Y1135541I2225J73D01*
G01X351934Y1135522D01*
X351933Y1135521D01*
G02X352636Y1134264I-772J-1257D01*
G01Y1134225D01*
G03X353748Y1132337I2225J39D01*
G01X353751Y1132335D01*
X353761Y1132329D01*
X353783Y1132317D01*
G02X354486Y1131060I-772J-1257D01*
G03X355574Y1129147I2226J0D01*
G01X355579Y1129144D01*
X355582Y1129142D01*
X355633Y1129113D01*
G02X356335Y1127896I-774J-1257D01*
G02X356334Y1127798I-1476J-34D01*
G02X355633Y1126599I-1475J58D01*
G01X355602Y1126581D01*
X355598Y1126579D01*
G03X355574Y1122738I1113J-1928D01*
G01X355579Y1122735D01*
X355582Y1122733D01*
X355633Y1122704D01*
G02X356336Y1121447I-772J-1257D01*
G01Y1121408D01*
G03X357448Y1119520I2225J39D01*
G01X357483Y1119500D01*
G02Y1116986I-772J-1257D01*
G01X357448Y1116966D01*
G03X356336Y1115078I1113J-1927D01*
G01Y1115039D01*
G02X356335Y1114981I-1475J-4D01*
G02X355633Y1113782I-1474J58D01*
G01X355598Y1113762D01*
G03X354487Y1111921I1114J-1928D01*
G01Y1111834D01*
G02X353784Y1110577I-1475J0D01*
G01X353755Y1110560D01*
X353725Y1110543D01*
G03X352636Y1108630I1136J-1913D01*
G01Y1108596D01*
G02X352085Y1107481I-1474J35D01*
G01X351778Y1107563D01*
X351162Y1108630D01*
G01X1384653Y1105426D02*
X1385270Y1106492D01*
X1385175Y1106843D01*
G02X1385108Y1106895I1331J1784D01*
G02X1384278Y1108600I1396J1734D01*
G01Y1108630D01*
G03X1383575Y1109887I-1475J0D01*
G01X1383543Y1109905D01*
X1383540Y1109907D01*
G02X1382428Y1111795I1113J1927D01*
G01Y1111907D01*
G02X1383540Y1113762I2225J-73D01*
G01X1383575Y1113782D01*
G03X1384277Y1114991I-772J1257D01*
G03X1384278Y1115065I-1474J57D01*
G03X1383575Y1116296I-1475J-26D01*
G01X1383543Y1116314D01*
X1383540Y1116316D01*
G02X1382428Y1118204I1113J1927D01*
G01Y1118243D01*
G03X1381725Y1119500I-1475J0D01*
G01X1381690Y1119520D01*
G02X1380579Y1121386I1114J1927D01*
G01Y1121447D01*
G03X1379876Y1122704I-1475J0D01*
G01X1379816Y1122739D01*
X1379817Y1122738D01*
G02X1378728Y1124651I1136J1913D01*
G01Y1124724D01*
G02X1379840Y1126579I2225J-73D01*
G01X1379875Y1126599D01*
G03Y1129113I-772J1257D01*
G01X1379843Y1129131D01*
X1379840Y1129133D01*
G02X1378728Y1131021I1113J1927D01*
G01Y1131060D01*
G03X1378025Y1132317I-1475J0D01*
G01X1377990Y1132337D01*
G02X1376879Y1134203I1114J1927D01*
G01Y1134264D01*
G03X1376176Y1135521I-1475J0D01*
G01X1376144Y1135539D01*
X1376141Y1135541D01*
G02X1375029Y1137396I1113J1928D01*
G01Y1138247D01*
G02X1375090Y1138404I2226J-775D01*
G02X1376153Y1139553I2164J-935D01*
G01X1376879Y1140279D01*
Y1142635D01*
X1368012Y1151502D01*
Y1158187D01*
X1367847Y1158352D01*
Y1158439D01*
G01X350625Y1144870D02*
Y1144783D01*
X350459Y1144617D01*
Y1144083D01*
X355235Y1139307D01*
Y1137471D01*
X355237Y1137469D01*
G03X355940Y1136212I1475J0D01*
G01X355975Y1136192D01*
G02X357086Y1134351I-1114J-1928D01*
G01Y1134264D01*
G03X357789Y1133007I1475J0D01*
G01X357824Y1132987D01*
X357848Y1132973D01*
G02X358937Y1131060I-1136J-1913D01*
G03X359640Y1129803I1475J0D01*
G01X359675Y1129783D01*
X359699Y1129769D01*
G02X360787Y1127856I-1138J-1913D01*
G01Y1127800D01*
G02X359675Y1125928I-2226J56D01*
G01X359640Y1125908D01*
G03X358938Y1124709I772J-1257D01*
G03X358937Y1124651I1474J-54D01*
G03X359640Y1123394I1475J0D01*
G01X359675Y1123374D01*
G02X360786Y1121508I-1114J-1927D01*
G01Y1121447D01*
G03X361489Y1120190I1475J0D01*
G01X361524Y1120170D01*
G02X362636Y1118282I-1113J-1927D01*
G01Y1118243D01*
G03X363339Y1116986I1475J0D01*
G01X363374Y1116966D01*
G02X364486Y1115078I-1113J-1927D01*
G01Y1115039D01*
G03X365189Y1113782I1475J0D01*
G01X365224Y1113762D01*
G03X366698I737J1277D01*
G02X368866Y1113796I1115J-1928D01*
G01X368924Y1113762D01*
G02X370037Y1111890I-1112J-1928D01*
G01Y1111834D01*
G03X370740Y1110577I1475J0D01*
G01X370775Y1110557D01*
G02X371886Y1108691I-1114J-1927D01*
G01Y1108630D01*
G03X372589Y1107373I1475J0D01*
G01X372649Y1107338D01*
X372648Y1107339D01*
G02X373737Y1105426I-1136J-1913D01*
G01Y1105392D01*
G03X374474Y1104149I1474J34D01*
G03X375948I737J1277D01*
G01X375983Y1104169D01*
G03X376668Y1105200I-773J1256D01*
G01X376442Y1105426D01*
X375211D01*
G01X1379104Y1108630D02*
X1378489Y1109696D01*
X1378584Y1110048D01*
G03X1379480Y1111795I-1329J1785D01*
G01X1379479Y1111834D01*
Y1111868D01*
G02X1380216Y1113111I1474J-34D01*
G03X1381329Y1114983I-1112J1928D01*
G01Y1115039D01*
G03X1380240Y1116952I-2225J0D01*
G01X1380221Y1116963D01*
X1380212Y1116969D01*
X1380181Y1116987D01*
Y1116986D01*
G02X1379478Y1118243I772J1257D01*
G01Y1118304D01*
G03X1378367Y1120170I-2225J-61D01*
G01X1378332Y1120190D01*
G02X1377629Y1121447I772J1257D01*
G03X1376540Y1123360I-2225J0D01*
G01X1376519Y1123372D01*
X1376516Y1123374D01*
X1376489Y1123389D01*
X1376481Y1123394D01*
G02Y1125908I772J1257D01*
G01X1376516Y1125928D01*
G03X1377629Y1127800I-1112J1928D01*
G01Y1127856D01*
G03X1376540Y1129769I-2225J0D01*
G01X1376521Y1129780D01*
X1376512Y1129786D01*
X1376481Y1129804D01*
Y1129803D01*
G02X1375778Y1131060I772J1257D01*
G01Y1131121D01*
G03X1374667Y1132987I-2225J-61D01*
G01X1374632Y1133007D01*
G02X1373929Y1134264I772J1257D01*
G01Y1134337D01*
G03X1372817Y1136192I-2225J-73D01*
G01X1372782Y1136212D01*
G02X1372079Y1137469I772J1257D01*
G01Y1138104D01*
G02X1372804Y1138889I1475J-635D01*
G03X1373928Y1140195I-1101J2084D01*
G01Y1142708D01*
X1365468Y1151168D01*
Y1159126D01*
X1365634Y1159292D01*
Y1159379D01*
G01X355199Y1144091D02*
X355260Y1144030D01*
X355492D01*
X356040Y1143482D01*
Y1140265D01*
X357362Y1138943D01*
X357462Y1138890D01*
G02X358188Y1138106I-749J-1422D01*
G01Y1137380D01*
X358187Y1137382D01*
G03X359298Y1135541I2225J87D01*
G01X359302Y1135539D01*
X359333Y1135521D01*
G02X360036Y1134264I-772J-1257D01*
G03X361101Y1132365I2226J0D01*
G01X361134Y1132346D01*
X361149Y1132337D01*
X361184Y1132317D01*
G02X361887Y1131060I-772J-1257D01*
G01Y1131021D01*
G03X362999Y1129133I2225J39D01*
G01X363002Y1129131D01*
X363034Y1129113D01*
G02X363737Y1127856I-772J-1257D01*
G01Y1127769D01*
G03X364848Y1125928I2225J87D01*
G01X364852Y1125926D01*
X364883Y1125908D01*
G02X365585Y1124709I-772J-1257D01*
G02X365586Y1124651I-1474J-54D01*
G03X366675Y1122738I2225J0D01*
G01X366734Y1122704D01*
G02X367437Y1121447I-772J-1257D01*
G01Y1121386D01*
G03X368548Y1119520I2225J61D01*
G01X368583Y1119500D01*
G02X369286Y1118243I-772J-1257D01*
G01Y1118204D01*
G03X370398Y1116316I2225J39D01*
G01X370433Y1116296D01*
G02X371136Y1115039I-772J-1257D01*
G01Y1114983D01*
G03X372249Y1113111I2225J56D01*
G02X372986Y1111868I-737J-1277D01*
G01Y1111795D01*
G03X374098Y1109907I2225J39D01*
G01X374139Y1109883D01*
G03X376016Y1109759I1071J1951D01*
G03X376095Y1109791I-796J2078D01*
G01X376446Y1109697D01*
X377062Y1108630D01*
G01X1386504D02*
X1385888Y1107563D01*
X1385580Y1107481D01*
G02X1385029Y1108630I924J1150D01*
G03X1383964Y1110529I-2226J0D01*
G01X1383916Y1110557D01*
X1383881Y1110577D01*
G02X1383178Y1111808I772J1257D01*
G02X1383179Y1111882I1475J17D01*
G02X1383881Y1113091I1474J-48D01*
G01X1383916Y1113111D01*
G03X1385028Y1114966I-1113J1928D01*
G01Y1115078D01*
G03X1383916Y1116966I-2225J-39D01*
G01X1383881Y1116986D01*
G02X1383178Y1118243I772J1257D01*
G01Y1118304D01*
G03X1382067Y1120170I-2225J-61D01*
G01X1382032Y1120190D01*
G02X1381329Y1121447I772J1257D01*
G03X1380240Y1123360I-2225J0D01*
G01X1380219Y1123372D01*
X1380216Y1123374D01*
X1380189Y1123389D01*
X1380181Y1123394D01*
G02Y1125908I772J1257D01*
G01X1380213Y1125926D01*
X1380216Y1125928D01*
G03X1381329Y1127826I-1113J1928D01*
G01Y1127856D01*
G03X1380264Y1129755I-2226J0D01*
G01X1380216Y1129783D01*
X1380181Y1129803D01*
G02X1379478Y1131060I772J1257D01*
G01Y1131121D01*
G03X1378367Y1132987I-2225J-61D01*
G01X1378332Y1133007D01*
G02X1377629Y1134264I772J1257D01*
G01Y1134337D01*
G03X1376517Y1136192I-2225J-73D01*
G01X1376482Y1136212D01*
G02X1375779Y1137469I772J1257D01*
G01Y1138108D01*
X1375778Y1138107D01*
G02X1376503Y1138890I1475J-639D01*
G01X1376603Y1138943D01*
X1377628Y1139968D01*
Y1142946D01*
X1368761Y1151813D01*
Y1153284D01*
X1369151Y1153674D01*
Y1154364D01*
X1368761Y1154754D01*
Y1158186D01*
X1368927Y1158352D01*
Y1158439D01*
G01X349545Y1144870D02*
Y1144783D01*
X349710Y1144618D01*
Y1143772D01*
X354486Y1138996D01*
Y1137413D01*
G03X355598Y1135541I2226J56D01*
G01X355633Y1135521D01*
G02X356335Y1134322I-772J-1257D01*
G02X356336Y1134264I-1474J-54D01*
G03X357425Y1132351I2225J0D01*
G01X357449Y1132337D01*
X357484Y1132317D01*
G02X358187Y1131060I-772J-1257D01*
G01Y1130999D01*
G03X359298Y1129133I2225J61D01*
G01X359302Y1129131D01*
X359333Y1129113D01*
G02Y1126599I-772J-1257D01*
G01X359302Y1126581D01*
X359298Y1126579D01*
G03X358187Y1124738I1114J-1928D01*
G01Y1124590D01*
G03X359298Y1122724I2225J61D01*
G01X359333Y1122704D01*
G02X360036Y1121447I-772J-1257D01*
G01Y1121408D01*
G03X361148Y1119520I2225J39D01*
G01X361183Y1119500D01*
G02X361886Y1118243I-772J-1257D01*
G01Y1118204D01*
G03X362998Y1116316I2225J39D01*
G01X363033Y1116296D01*
G02X363736Y1115039I-772J-1257D01*
G01Y1114983D01*
G03X364849Y1113111I2225J56D01*
G01X364907Y1113077D01*
G03X367075Y1113111I1053J1962D01*
G02X368549I737J-1277D01*
G01X368584Y1113091D01*
G02X369287Y1111834I-772J-1257D01*
G01Y1111773D01*
G03X370398Y1109907I2225J61D01*
G01X370433Y1109887D01*
G02X371136Y1108630I-772J-1257D01*
G03X372225Y1106717I2225J0D01*
G01X372246Y1106705D01*
X372249Y1106703D01*
G02X372986Y1105460I-737J-1277D01*
G01Y1105353D01*
G03X374098Y1103498I2225J73D01*
G01X374139Y1103474D01*
G03X376325Y1103498I1072J1952D01*
G03X377412Y1105085I-1113J1928D01*
G03X377423Y1105168I-2202J334D01*
G01X377681Y1105426D01*
X378912D01*
G01X1377253Y1111834D02*
X1377869Y1110767D01*
X1378177Y1110685D01*
G03X1378728Y1111833I-923J1149D01*
G01X1378727Y1111889D01*
G02X1379841Y1113762I2225J-56D01*
G03X1380578Y1115005I-737J1277D01*
G01Y1115073D01*
G03X1379841Y1116316I-1474J-34D01*
G01X1379838Y1116318D01*
X1379827Y1116324D01*
X1379817Y1116330D01*
G02X1378728Y1118243I1136J1913D01*
G03X1378025Y1119500I-1475J0D01*
G01X1377990Y1119520D01*
G02X1376879Y1121386I1114J1927D01*
G01Y1121447D01*
G03X1376176Y1122704I-1475J0D01*
G01X1376116Y1122739D01*
X1376117Y1122738D01*
G02X1375028Y1124651I1136J1913D01*
G01Y1124707D01*
G02X1376141Y1126579I2225J-56D01*
G03X1376878Y1127822I-737J1277D01*
G01Y1127890D01*
G03X1376141Y1129133I-1474J-34D01*
G01X1376138Y1129135D01*
X1376127Y1129141D01*
X1376117Y1129147D01*
G02X1375028Y1131060I1136J1913D01*
G03X1374325Y1132317I-1475J0D01*
G01X1374290Y1132337D01*
G02X1373179Y1134203I1114J1927D01*
G01Y1134264D01*
G03X1372476Y1135521I-1475J0D01*
G01X1372441Y1135541D01*
G02X1371329Y1137396I1113J1928D01*
G01Y1138243D01*
X1371330Y1138244D01*
G02X1371391Y1138400I2222J-779D01*
G02X1372454Y1139552I2164J-930D01*
G03X1373179Y1140335I-750J1422D01*
G01Y1142397D01*
X1372692Y1142884D01*
X1372139D01*
X1371651Y1143372D01*
Y1143925D01*
X1364719Y1150857D01*
Y1151547D01*
X1364329Y1151937D01*
Y1152627D01*
X1364719Y1153017D01*
Y1153737D01*
X1364329Y1154127D01*
Y1154817D01*
X1364719Y1155207D01*
Y1159127D01*
X1364554Y1159292D01*
Y1159379D01*
G01X355963Y1144855D02*
X356024Y1144794D01*
Y1144558D01*
X356789Y1143793D01*
Y1140577D01*
X357813Y1139553D01*
X357812D01*
G02X358937Y1138246I-1100J-2084D01*
G01Y1137469D01*
G03X358938Y1137411I1475J-4D01*
G03X359640Y1136212I1474J58D01*
G01X359675Y1136192D01*
G02X360787Y1134320I-1114J-1928D01*
G01Y1134264D01*
G03X361490Y1133007I1475J0D01*
G01X361512Y1132995D01*
X361522Y1132989D01*
X361525Y1132987D01*
G02X362637Y1131099I-1113J-1927D01*
G01Y1131060D01*
G03X363340Y1129803I1475J0D01*
G01X363375Y1129783D01*
G02X364487Y1127895I-1113J-1927D01*
G01Y1127856D01*
G03X364488Y1127798I1475J-4D01*
G03X365190Y1126599I1474J58D01*
G01X365225Y1126579D01*
G02X366336Y1124738I-1114J-1928D01*
G01Y1124651D01*
G03X367039Y1123394I1475J0D01*
G01X367068Y1123377D01*
X367074Y1123374D01*
X367085Y1123368D01*
X367098Y1123360D01*
G02X368187Y1121447I-1136J-1913D01*
G03X368890Y1120190I1475J0D01*
G01X368925Y1120170D01*
G02X370036Y1118304I-1114J-1927D01*
G01Y1118243D01*
G03X370739Y1116986I1475J0D01*
G01X370774Y1116966D01*
G02X371886Y1115078I-1113J-1927D01*
G01Y1115039D01*
G03X372589Y1113782I1475J0D01*
G01X372624Y1113762D01*
G02X373737Y1111890I-1112J-1928D01*
G01Y1111800D01*
G03X374474Y1110557I1474J34D01*
G03X375744Y1110460I736J1277D01*
G01X375827Y1110767D01*
X375211Y1111834D01*
G01X1379104Y1115039D02*
X1377873D01*
X1377614Y1115298D01*
G03X1377603Y1115380I-2210J-255D01*
G03X1376540Y1116952I-2199J-341D01*
G01X1376527Y1116960D01*
X1376516Y1116966D01*
X1376513Y1116968D01*
X1376480Y1116988D01*
X1376481Y1116986D01*
G02X1375778Y1118243I772J1257D01*
G01Y1118304D01*
G03X1374667Y1120170I-2225J-61D01*
G01X1374632Y1120190D01*
G02X1373929Y1121447I772J1257D01*
G03X1372840Y1123360I-2225J0D01*
G01X1372819Y1123372D01*
X1372816Y1123374D01*
X1372789Y1123389D01*
X1372781Y1123394D01*
G02Y1125908I772J1257D01*
G01X1372813Y1125926D01*
X1372816Y1125928D01*
G03X1373929Y1127826I-1113J1928D01*
G01Y1127856D01*
G03X1372864Y1129755I-2226J0D01*
G01X1372816Y1129783D01*
X1372781Y1129803D01*
G02X1372078Y1131060I772J1257D01*
G01Y1131121D01*
G03X1370967Y1132987I-2225J-61D01*
G01X1370932Y1133007D01*
G02X1370229Y1134264I772J1257D01*
G01Y1134337D01*
G03X1369117Y1136192I-2225J-73D01*
G01X1369082Y1136212D01*
G02X1368379Y1137469I772J1257D01*
G01Y1138104D01*
G02X1369104Y1138889I1475J-635D01*
G01X1369103Y1138890D01*
G03X1370227Y1140198I-1100J2082D01*
G01Y1142587D01*
X1362194Y1150620D01*
Y1159126D01*
X1362360Y1159292D01*
Y1159379D01*
G01X362358Y1142992D02*
X362419Y1142931D01*
X362651D01*
X363736Y1141846D01*
Y1140338D01*
G02X363011Y1139553I-1475J635D01*
G03X361887Y1138247I1101J-2084D01*
G01Y1137396D01*
G03X362999Y1135541I2225J73D01*
G01X363034Y1135521D01*
G02X363737Y1134264I-772J-1257D01*
G01Y1134225D01*
G03X364849Y1132337I2225J39D01*
G02X365586Y1131094I-737J-1277D01*
G01Y1131060D01*
G03X366675Y1129147I2225J0D01*
G01X366699Y1129133D01*
X366757Y1129099D01*
G03X368925Y1129133I1054J1961D01*
G02X370399I737J-1277D01*
G02X371136Y1127890I-737J-1277D01*
G01Y1127822D01*
G02X370399Y1126579I-1474J34D01*
G03X369286Y1124707I1112J-1928D01*
G01Y1124651D01*
G03X370375Y1122738I2225J0D01*
G01X370399Y1122724D01*
X370434Y1122704D01*
G02X371137Y1121447I-772J-1257D01*
G01Y1121386D01*
G03X372248Y1119520I2225J61D01*
G01X372283Y1119500D01*
G02X372986Y1118243I-772J-1257D01*
G01Y1118204D01*
G03X374098Y1116316I2225J39D01*
G01X374133Y1116296D01*
G02X374836Y1115039I-772J-1257D01*
G01Y1114966D01*
G03X375948Y1113111I2225J73D01*
G01X375983Y1113091D01*
G02X376686Y1111834I-772J-1257D01*
G03X377775Y1109921I2225J0D01*
G01X377799Y1109907D01*
X377834Y1109887D01*
G02X378537Y1108630I-772J-1257D01*
G01Y1108591D01*
G03X379649Y1106703I2225J39D01*
G02X380386Y1105460I-737J-1277D01*
G01Y1105392D01*
G02X379649Y1104149I-1474J34D01*
G03X378537Y1102294I1113J-1928D01*
G01Y1102160D01*
G03X379648Y1100294I2225J61D01*
G03X381816Y1100260I1114J1927D01*
G01X381874Y1100294D01*
X381877Y1100296D01*
X381898Y1100308D01*
G03X382987Y1102221I-1136J1913D01*
G01Y1102277D01*
G03X382157Y1103956I-2225J-55D01*
G03X382090Y1104008I-1398J-1732D01*
G01X381995Y1104359D01*
X382611Y1105426D01*
G01X1375404Y1115039D02*
X1376635D01*
X1376861Y1115265D01*
G03X1376176Y1116296I-1458J-225D01*
G01X1376148Y1116312D01*
X1376136Y1116319D01*
X1376130Y1116323D01*
X1376117Y1116330D01*
G02X1375028Y1118243I1136J1913D01*
G03X1374325Y1119500I-1475J0D01*
G01X1374290Y1119520D01*
G02X1373179Y1121386I1114J1927D01*
G01Y1121447D01*
G03X1372476Y1122704I-1475J0D01*
G01X1372447Y1122721D01*
X1372441Y1122724D01*
X1372428Y1122732D01*
X1372417Y1122738D01*
G02X1372440Y1126579I1135J1914D01*
G01X1372475Y1126599D01*
G03Y1129113I-772J1257D01*
G01X1372443Y1129131D01*
X1372440Y1129133D01*
G02X1371328Y1131021I1113J1927D01*
G01Y1131060D01*
G03X1370625Y1132317I-1475J0D01*
G01X1370590Y1132337D01*
G02X1369479Y1134203I1114J1927D01*
G01Y1134264D01*
G03X1368776Y1135521I-1475J0D01*
G01X1368741Y1135541D01*
G02X1367629Y1137396I1113J1928D01*
G01Y1138247D01*
G02X1368753Y1139553I2225J-778D01*
G03X1369478Y1140338I-750J1420D01*
G01Y1142276D01*
X1361445Y1150309D01*
Y1159127D01*
X1361280Y1159292D01*
Y1159379D01*
G01X363122Y1143756D02*
X363183Y1143695D01*
Y1143459D01*
X364485Y1142157D01*
Y1140198D01*
X364486Y1140197D01*
Y1140195D01*
G02X363362Y1138889I-2225J778D01*
G03X362637Y1138104I750J-1420D01*
G01Y1137469D01*
G03X363340Y1136212I1475J0D01*
G01X363375Y1136192D01*
G02X364487Y1134337I-1113J-1928D01*
G01Y1134264D01*
G03X365190Y1133007I1475J0D01*
G01X365225Y1132987D01*
G02X366337Y1131099I-1113J-1927D01*
G01Y1131026D01*
G03X368548Y1129783I1474J33D01*
G02X370716Y1129817I1114J-1927D01*
G01X370798Y1129769D01*
G02X371887Y1127856I-1136J-1913D01*
G01Y1127800D01*
G02X370774Y1125928I-2225J56D01*
G01X370739Y1125908D01*
G03Y1123394I771J-1257D01*
G01X370798Y1123360D01*
G02X371887Y1121447I-1136J-1913D01*
G03X372590Y1120190I1475J0D01*
G01X372625Y1120170D01*
G02X373736Y1118304I-1114J-1927D01*
G01Y1118243D01*
G03X374439Y1116986I1475J0D01*
G01X374474Y1116966D01*
G02X375586Y1115078I-1113J-1927D01*
G01Y1115039D01*
G03X376289Y1113782I1475J0D01*
G01X376324Y1113762D01*
G02X377436Y1111907I-1113J-1928D01*
G01Y1111834D01*
G03X378139Y1110577I1475J0D01*
G01X378198Y1110543D01*
G02X379287Y1108630I-1136J-1913D01*
G03X379990Y1107373I1475J0D01*
G01X380025Y1107353D01*
G02Y1103498I-1113J-1928D01*
G01X379990Y1103478D01*
G03X379287Y1102269I771J-1257D01*
G03Y1102181I1474J-44D01*
G03X381499Y1100944I1474J40D01*
G01X381505Y1100947D01*
G03X381686Y1103370I-742J1274D01*
G01X381378Y1103288D01*
X380762Y1102221D01*
G01X1373553Y1105426D02*
X1374169Y1106493D01*
X1374520Y1106587D01*
G03X1374599Y1106555I875J2047D01*
G03X1376458Y1106669I806J2075D01*
G01X1376540Y1106717D01*
G03Y1110543I-1136J1913D01*
G01X1376533Y1110547D01*
X1376525Y1110552D01*
X1376516Y1110557D01*
X1376458Y1110591D01*
G03X1374290Y1110557I-1054J-1961D01*
G02X1372816I-737J1277D01*
G01X1372810Y1110560D01*
X1372781Y1110577D01*
G02Y1113091I772J1257D01*
G01X1372813Y1113109D01*
X1372816Y1113111D01*
G03X1373929Y1115009I-1113J1928D01*
G01Y1115039D01*
G03X1372864Y1116938I-2226J0D01*
G01X1372816Y1116966D01*
X1372781Y1116986D01*
G02X1372078Y1118243I772J1257D01*
G01Y1118304D01*
G03X1370967Y1120170I-2225J-61D01*
G01X1370932Y1120190D01*
G02X1370229Y1121447I772J1257D01*
G03X1369140Y1123360I-2225J0D01*
G01X1369119Y1123372D01*
X1369116Y1123374D01*
X1369089Y1123389D01*
X1369081Y1123394D01*
G02Y1125908I772J1257D01*
G01X1369116Y1125928D01*
G03X1370229Y1127800I-1112J1928D01*
G01Y1127856D01*
G03X1369140Y1129769I-2225J0D01*
G01X1369121Y1129780D01*
X1369112Y1129786D01*
X1369104Y1129791D01*
X1369094Y1129796D01*
X1369081Y1129804D01*
Y1129803D01*
G02X1368378Y1131060I772J1257D01*
G01Y1131121D01*
G03X1367267Y1132987I-2225J-61D01*
G01X1367232Y1133007D01*
G02X1366529Y1134264I772J1257D01*
G01Y1134337D01*
G03X1365417Y1136192I-2225J-73D01*
G01X1365382Y1136212D01*
G02X1364679Y1137469I772J1257D01*
G01Y1138104D01*
G02X1365404Y1138889I1475J-635D01*
G01X1365403Y1138890D01*
G03X1366527Y1140198I-1100J2082D01*
G01Y1142451D01*
X1358922Y1150056D01*
Y1159646D01*
X1359088Y1159812D01*
Y1159899D01*
G01X366764Y1143386D02*
X366825Y1143325D01*
X367057D01*
X367436Y1142946D01*
Y1140339D01*
G02X366711Y1139553I-1476J634D01*
G03X365587Y1138247I1101J-2084D01*
G01Y1137396D01*
G03X366699Y1135541I2225J73D01*
G01X366702Y1135539D01*
X366734Y1135521D01*
G02X367437Y1134264I-772J-1257D01*
G01Y1134203D01*
G03X370716Y1132303I2225J61D01*
G01X370774Y1132337D01*
G02X372986Y1131060I737J-1277D01*
G01Y1131021D01*
G03X374098Y1129133I2225J39D01*
G01X374101Y1129131D01*
X374111Y1129125D01*
X374133Y1129113D01*
G02Y1126599I-772J-1257D01*
G01X374098Y1126579D01*
G03X374075Y1122738I1112J-1927D01*
G01X374134Y1122704D01*
G02X374837Y1121447I-772J-1257D01*
G01Y1121386D01*
G03X375948Y1119520I2225J61D01*
G01X375983Y1119500D01*
G02X376686Y1118243I-772J-1257D01*
G01Y1118204D01*
G03X377798Y1116316I2225J39D01*
G01X377801Y1116314D01*
X377811Y1116308D01*
X377833Y1116296D01*
G02X378536Y1115039I-772J-1257D01*
G01Y1114983D01*
G03X379366Y1113303I2226J55D01*
G03X379432Y1113252I1394J1736D01*
G01X379527Y1112901D01*
X378911Y1111834D01*
G01X1375404Y1108630D02*
X1374788Y1107563D01*
X1374871Y1107256D01*
G03X1376141Y1107353I534J1374D01*
G01X1376147Y1107356D01*
X1376176Y1107373D01*
G03Y1109887I-772J1257D01*
G01X1376147Y1109904D01*
X1376141Y1109907D01*
G03X1374667I-737J-1277D01*
G02X1372499Y1109873I-1114J1927D01*
G01X1372417Y1109921D01*
G02X1371328Y1111834I1136J1913D01*
G01Y1111907D01*
G02X1372440Y1113762I2225J-73D01*
G01X1372475Y1113782D01*
G03Y1116296I-772J1257D01*
G01X1372472Y1116298D01*
X1372453Y1116308D01*
X1372450Y1116310D01*
X1372443Y1116314D01*
X1372440Y1116316D01*
G02X1371328Y1118204I1113J1927D01*
G01Y1118243D01*
G03X1370625Y1119500I-1475J0D01*
G01X1370590Y1119520D01*
G02X1369479Y1121386I1114J1927D01*
G01Y1121447D01*
G03X1368776Y1122704I-1475J0D01*
G01X1368716Y1122739D01*
X1368717Y1122738D01*
G02X1367628Y1124651I1136J1913D01*
G01Y1124707D01*
G02X1368741Y1126579I2225J-56D01*
G03X1369478Y1127822I-737J1277D01*
G01Y1127890D01*
G03X1368741Y1129133I-1474J-34D01*
G01X1368738Y1129135D01*
X1368727Y1129141D01*
X1368717Y1129147D01*
G02X1367628Y1131060I1136J1913D01*
G03X1366925Y1132317I-1475J0D01*
G01X1366894Y1132335D01*
X1366890Y1132337D01*
G02X1365779Y1134203I1114J1927D01*
G01Y1134264D01*
G03X1365076Y1135521I-1475J0D01*
G01X1365041Y1135541D01*
G02X1363929Y1137396I1113J1928D01*
G01Y1138247D01*
G02X1365053Y1139553I2225J-778D01*
G03X1365778Y1140338I-750J1420D01*
G01Y1142140D01*
X1365291Y1142627D01*
X1364738D01*
X1364250Y1143115D01*
Y1143668D01*
X1358173Y1149745D01*
Y1150235D01*
X1357783Y1150625D01*
Y1151315D01*
X1358173Y1151705D01*
Y1152395D01*
X1357783Y1152785D01*
Y1153475D01*
X1358173Y1153865D01*
Y1154555D01*
X1357783Y1154945D01*
Y1155635D01*
X1358173Y1156025D01*
Y1156715D01*
X1357783Y1157105D01*
Y1157795D01*
X1358173Y1158185D01*
Y1159647D01*
X1358008Y1159812D01*
Y1159899D01*
G01X367528Y1144150D02*
X367589Y1144089D01*
Y1143853D01*
X368185Y1143257D01*
Y1140198D01*
G02X367061Y1138890I-2224J774D01*
G01X367062Y1138889D01*
G03X366337Y1138104I750J-1420D01*
G01Y1137469D01*
G03X367040Y1136212I1475J0D01*
G01X367075Y1136192D01*
G02X368187Y1134337I-1113J-1928D01*
G01Y1134264D01*
G03X370399Y1132987I1475J0D01*
G01X370457Y1133021D01*
G02X373736Y1131121I1054J-1961D01*
G01Y1131060D01*
G03X374439Y1129803I1475J0D01*
G01X374522Y1129755D01*
G02X374474Y1125928I-1161J-1899D01*
G01X374471Y1125926D01*
X374439Y1125908D01*
G03Y1123394I773J-1257D01*
G01X374468Y1123377D01*
X374474Y1123374D01*
X374477Y1123372D01*
X374498Y1123360D01*
G02X375587Y1121447I-1136J-1913D01*
G03X376290Y1120190I1475J0D01*
G01X376325Y1120170D01*
G02X377436Y1118304I-1114J-1927D01*
G01Y1118243D01*
G03X378139Y1116986I1475J0D01*
G01X378222Y1116938D01*
G02X379287Y1115039I-1161J-1899D01*
G03X379838Y1113890I1475J1D01*
G01X380146Y1113972D01*
X380762Y1115039D01*
G01X1369853Y1111834D02*
X1369237Y1112901D01*
X1369332Y1113252D01*
G03X1369399Y1113303I-1314J1796D01*
G03X1370229Y1114983I-1395J1734D01*
G01Y1115039D01*
G03X1369140Y1116952I-2225J0D01*
G01X1369121Y1116963D01*
X1369112Y1116969D01*
X1369104Y1116974D01*
X1369094Y1116979D01*
X1369081Y1116987D01*
Y1116986D01*
G02X1368378Y1118243I772J1257D01*
G01Y1118304D01*
G03X1367267Y1120170I-2225J-61D01*
G01X1367232Y1120190D01*
G02X1366529Y1121447I772J1257D01*
G03X1365440Y1123360I-2225J0D01*
G01X1365419Y1123372D01*
X1365416Y1123374D01*
X1365389Y1123389D01*
X1365381Y1123394D01*
G02Y1125908I772J1257D01*
G01X1365413Y1125926D01*
X1365416Y1125928D01*
G03X1366529Y1127826I-1113J1928D01*
G01Y1127856D01*
G03X1365464Y1129755I-2226J0D01*
G01X1365416Y1129783D01*
X1365381Y1129803D01*
G02X1364678Y1131060I772J1257D01*
G01Y1131121D01*
G03X1363567Y1132987I-2225J-61D01*
G01X1363532Y1133007D01*
G02X1362829Y1134264I772J1257D01*
G01Y1134337D01*
G03X1361717Y1136192I-2225J-73D01*
G01X1361682Y1136212D01*
G02X1360979Y1137469I772J1257D01*
G01Y1138104D01*
G02X1361560Y1138803I1475J-635D01*
G01X1361619D01*
X1361706Y1138890D01*
G03X1362828Y1140195I-1103J2083D01*
G01Y1142316D01*
X1355612Y1149532D01*
Y1159646D01*
X1355778Y1159812D01*
Y1159899D01*
G01X368838Y1146512D02*
X368899Y1146451D01*
X369131D01*
X371136Y1144446D01*
Y1140196D01*
G03X371195Y1140043I2227J771D01*
G03X372261Y1138889I2165J931D01*
G02X372987Y1138102I-749J-1420D01*
G01Y1137396D01*
G03X374099Y1135541I2225J73D01*
G01X374102Y1135539D01*
X374134Y1135521D01*
G02X374837Y1134264I-772J-1257D01*
G01Y1134203D01*
G03X375948Y1132337I2225J61D01*
G01X375983Y1132317D01*
G02X376686Y1131060I-772J-1257D01*
G03X377775Y1129147I2225J0D01*
G01X377796Y1129135D01*
X377799Y1129133D01*
G02X378536Y1127890I-737J-1277D01*
G01Y1127822D01*
G02X377799Y1126579I-1474J34D01*
G03X376686Y1124707I1112J-1928D01*
G01Y1124651D01*
G03X377775Y1122738I2225J0D01*
G01X377796Y1122726D01*
X377799Y1122724D01*
X377805Y1122721D01*
X377834Y1122704D01*
G02X378537Y1121447I-772J-1257D01*
G01Y1121386D01*
G03X379648Y1119520I2225J61D01*
G01X379683Y1119500D01*
G02X380386Y1118243I-772J-1257D01*
G03X381475Y1116330I2225J0D01*
G01X381496Y1116318D01*
X381499Y1116316D01*
G02X382236Y1115073I-737J-1277D01*
G01Y1115005D01*
G02X381499Y1113762I-1474J34D01*
G03X380386Y1111890I1112J-1928D01*
G01Y1111834D01*
G03X381475Y1109921I2225J0D01*
G01X381496Y1109909D01*
X381499Y1109907D01*
X381505Y1109904D01*
X381534Y1109887D01*
G02X382237Y1108630I-772J-1257D01*
G01Y1108569D01*
G03X383348Y1106703I2225J61D01*
G03X385268Y1106554I1115J1926D01*
G03X385345Y1106586I-816J2071D01*
G01X385695Y1106493D01*
X386311Y1105426D01*
G01X1368004Y1115039D02*
X1368620Y1113972D01*
X1368927Y1113890D01*
G03X1369478Y1115005I-923J1150D01*
G01Y1115073D01*
G03X1368741Y1116316I-1474J-34D01*
G01X1368738Y1116318D01*
X1368727Y1116324D01*
X1368717Y1116330D01*
G02X1367628Y1118243I1136J1913D01*
G03X1366925Y1119500I-1475J0D01*
G01X1366890Y1119520D01*
G02X1365779Y1121386I1114J1927D01*
G01Y1121447D01*
G03X1365076Y1122704I-1475J0D01*
G01X1365016Y1122739D01*
X1365017Y1122738D01*
G02X1363928Y1124651I1136J1913D01*
G01Y1124724D01*
G02X1365040Y1126579I2225J-73D01*
G01X1365075Y1126599D01*
G03Y1129113I-772J1257D01*
G01X1365043Y1129131D01*
X1365040Y1129133D01*
G02X1363928Y1131021I1113J1927D01*
G01Y1131060D01*
G03X1363225Y1132317I-1475J0D01*
G01X1363190Y1132337D01*
G02X1362079Y1134203I1114J1927D01*
G01Y1134264D01*
G03X1361376Y1135521I-1475J0D01*
G01X1361341Y1135541D01*
G02X1360229Y1137396I1113J1928D01*
G01Y1138243D01*
X1360230Y1138244D01*
G02X1360290Y1138400I2227J-767D01*
G02X1361142Y1139426I2164J-930D01*
G02X1361250Y1139494I1309J-1959D01*
G01X1361932Y1140176D01*
X1362079Y1140335D01*
Y1142005D01*
X1361223Y1142861D01*
X1360670D01*
X1360182Y1143349D01*
Y1143902D01*
X1354863Y1149221D01*
Y1150640D01*
X1354473Y1151030D01*
Y1151720D01*
X1354863Y1152110D01*
Y1152800D01*
X1354473Y1153190D01*
Y1153880D01*
X1354863Y1154270D01*
Y1159647D01*
X1354698Y1159812D01*
Y1159899D01*
G01X369602Y1147276D02*
X369663Y1147215D01*
Y1146979D01*
X371885Y1144757D01*
Y1140342D01*
X371886Y1140340D01*
G03X372612Y1139553I1475J633D01*
G02X373737Y1138246I-1100J-2084D01*
G01Y1137469D01*
G03X374440Y1136212I1475J0D01*
G01X374475Y1136192D01*
G02X375587Y1134337I-1113J-1928D01*
G01Y1134264D01*
G03X376290Y1133007I1475J0D01*
G01X376325Y1132987D01*
G02X377436Y1131121I-1114J-1927D01*
G01Y1131060D01*
G03X378139Y1129803I1475J0D01*
G01X378199Y1129768D01*
X378198Y1129769D01*
G02X379287Y1127856I-1136J-1913D01*
G01Y1127800D01*
G02X378174Y1125928I-2225J56D01*
G01X378139Y1125908D01*
G03Y1123394I771J-1257D01*
G01X378168Y1123377D01*
X378174Y1123374D01*
X378177Y1123372D01*
X378198Y1123360D01*
G02X379287Y1121447I-1136J-1913D01*
G03X379990Y1120190I1475J0D01*
G01X380025Y1120170D01*
G02X381136Y1118304I-1114J-1927D01*
G01Y1118243D01*
G03X381839Y1116986I1475J0D01*
G01X381899Y1116951D01*
X381898Y1116952D01*
G02X382987Y1115039I-1136J-1913D01*
G01Y1114983D01*
G02X381874Y1113111I-2225J56D01*
G01X381839Y1113091D01*
G03Y1110577I771J-1257D01*
G01X381868Y1110560D01*
X381874Y1110557D01*
X381877Y1110555D01*
X381898Y1110543D01*
G02X382987Y1108630I-1136J-1913D01*
G03X383690Y1107373I1475J0D01*
G01X383725Y1107353D01*
G03X384995Y1107256I736J1277D01*
G01X385078Y1107563D01*
X384462Y1108630D01*
G01X1368004D02*
X1369235D01*
X1369461Y1108404D01*
G02X1368776Y1107373I-1458J225D01*
G01X1368747Y1107356D01*
X1368741Y1107353D01*
G02X1367267I-737J1277D01*
G01X1367232Y1107373D01*
G02Y1109887I773J1257D01*
G01X1367263Y1109905D01*
X1367267Y1109907D01*
G03X1368378Y1111773I-1114J1927D01*
G01Y1111837D01*
G03X1367267Y1113762I-2223J0D01*
G01X1367232Y1113782D01*
G02X1366529Y1115039I772J1257D01*
G03X1365464Y1116938I-2226J0D01*
G01X1365416Y1116966D01*
X1365381Y1116986D01*
G02X1364678Y1118243I772J1257D01*
G01Y1118304D01*
G03X1363567Y1120170I-2225J-61D01*
G01X1363532Y1120190D01*
G02X1362829Y1121447I772J1257D01*
G03X1361740Y1123360I-2225J0D01*
G01X1361719Y1123372D01*
X1361716Y1123374D01*
X1361710Y1123377D01*
X1361681Y1123394D01*
G02Y1125908I772J1257D01*
G01X1361716Y1125928D01*
G03X1362829Y1127800I-1112J1928D01*
G01Y1127856D01*
G03X1361740Y1129769I-2225J0D01*
G01X1361721Y1129780D01*
X1361712Y1129786D01*
X1361704Y1129791D01*
X1361694Y1129796D01*
X1361681Y1129804D01*
Y1129803D01*
G02X1360978Y1131060I772J1257D01*
G01Y1131121D01*
G03X1359867Y1132987I-2225J-61D01*
G01X1359832Y1133007D01*
G02X1359129Y1134264I772J1257D01*
G01Y1134337D01*
G03X1358017Y1136192I-2225J-73D01*
G01X1357982Y1136212D01*
G02X1357279Y1137469I772J1257D01*
G01Y1138104D01*
G02X1358004Y1138889I1475J-635D01*
G01X1358006Y1138890D01*
G03X1358024Y1138900I-1135J2065D01*
G03X1359128Y1140195I-1121J2073D01*
G01Y1141904D01*
X1358641Y1142391D01*
Y1142944D01*
X1358153Y1143432D01*
X1357600D01*
X1352341Y1148691D01*
Y1156847D01*
X1352721Y1157227D01*
Y1158227D01*
X1352341Y1158607D01*
Y1162316D01*
X1352507Y1162482D01*
Y1162569D01*
G01X370863Y1151189D02*
Y1151102D01*
X371028Y1150937D01*
Y1149154D01*
X378536Y1141646D01*
Y1140338D01*
G02X377811Y1139553I-1475J635D01*
G03X376687Y1138247I1101J-2084D01*
G01Y1137396D01*
G03X377799Y1135541I2225J73D01*
G01X377802Y1135539D01*
X377834Y1135521D01*
G02X378537Y1134264I-772J-1257D01*
G01Y1134203D01*
G03X379648Y1132337I2225J61D01*
G01X379683Y1132317D01*
G02X380386Y1131060I-772J-1257D01*
G01Y1131021D01*
G03X381498Y1129133I2225J39D01*
G01X381501Y1129131D01*
X381511Y1129125D01*
X381533Y1129113D01*
G02Y1126599I-772J-1257D01*
G01X381498Y1126579D01*
G03X380386Y1124724I1113J-1928D01*
G01Y1124651D01*
G03X381475Y1122738I2225J0D01*
G01X381496Y1122726D01*
X381499Y1122724D01*
X381505Y1122721D01*
X381534Y1122704D01*
G02X382237Y1121447I-772J-1257D01*
G01Y1121386D01*
G03X383348Y1119520I2225J61D01*
G01X383383Y1119500D01*
G02X384086Y1118243I-772J-1257D01*
G01Y1118204D01*
G03X385198Y1116316I2225J39D01*
G01X385233Y1116296D01*
G02X385936Y1115065I-772J-1257D01*
G02X385935Y1114991I-1475J-17D01*
G02X385233Y1113782I-1475J48D01*
G01X385198Y1113762D01*
G03X384110Y1112176I1112J-1929D01*
G03X384099Y1112091I2202J-328D01*
G01X383842Y1111834D01*
X382611D01*
G01X1377253Y1099017D02*
X1377869Y1100084D01*
X1378220Y1100178D01*
G03X1378299Y1100146I875J2047D01*
G03X1380158Y1100260I806J2075D01*
G01X1380216Y1100294D01*
X1380240Y1100308D01*
G03X1381329Y1102221I-1136J1913D01*
G01Y1102294D01*
G03X1380217Y1104149I-2225J-73D01*
G01X1380176Y1104173D01*
G03X1377990Y1104149I-1072J-1952D01*
G02X1376516I-737J1277D01*
G01X1376458Y1104183D01*
G03X1374290Y1104149I-1053J-1962D01*
G02X1372816I-737J1277D01*
G01X1372758Y1104183D01*
G03X1370590Y1104149I-1053J-1962D01*
G02X1369116I-737J1277D01*
G01X1369058Y1104183D01*
G03X1366890Y1104149I-1053J-1962D01*
G02X1365416I-737J1277D01*
G01X1365381Y1104169D01*
G02X1364678Y1105426I772J1257D01*
G01Y1105487D01*
G03X1363567Y1107353I-2225J-61D01*
G01X1363532Y1107373D01*
G02Y1109887I773J1257D01*
G01X1363563Y1109905D01*
X1363567Y1109907D01*
G03X1364678Y1111773I-1114J1927D01*
G01Y1111907D01*
G03X1363566Y1113762I-2225J-73D01*
G01X1363531Y1113782D01*
G02X1362828Y1115039I772J1257D01*
G01Y1115078D01*
G03X1361716Y1116966I-2225J-39D01*
G01X1361681Y1116986D01*
G02X1360978Y1118243I772J1257D01*
G01Y1118304D01*
G03X1359867Y1120170I-2225J-61D01*
G01X1359832Y1120190D01*
G02X1359129Y1121447I772J1257D01*
G03X1358040Y1123360I-2225J0D01*
G01X1358016Y1123374D01*
X1357981Y1123394D01*
G02Y1125908I772J1257D01*
G01X1358013Y1125926D01*
X1358016Y1125928D01*
G03X1359129Y1127826I-1113J1928D01*
G01Y1127856D01*
G03X1358064Y1129755I-2226J0D01*
G01X1358016Y1129783D01*
X1357981Y1129803D01*
G02X1357278Y1131060I772J1257D01*
G01Y1131121D01*
G03X1356167Y1132987I-2225J-61D01*
G01X1356132Y1133007D01*
G02X1355429Y1134264I772J1257D01*
G01Y1134337D01*
G03X1354317Y1136192I-2225J-73D01*
G01X1354282Y1136212D01*
G02X1353579Y1137469I772J1257D01*
G01Y1138104D01*
G02X1354304Y1138889I1475J-635D01*
G03X1355428Y1140195I-1101J2084D01*
G01Y1141012D01*
G03X1354316Y1142900I-2225J-39D01*
G02X1354010Y1143133I733J1281D01*
G01X1349052Y1148091D01*
Y1159146D01*
X1349218Y1159312D01*
Y1159399D01*
G01X381308Y1142991D02*
X381369Y1142930D01*
X381601D01*
X382240Y1142291D01*
Y1141396D01*
X382234Y1140687D01*
X382233D01*
G02X381792Y1139739I-1263J11D01*
G02X381513Y1139552I-1024J1226D01*
G03X380388Y1138244I1099J-2083D01*
G01Y1137394D01*
X380387Y1137396D01*
G03X381499Y1135541I2225J73D01*
G01X381534Y1135521D01*
G02X382237Y1134264I-772J-1257D01*
G01Y1134203D01*
G03X383348Y1132337I2225J61D01*
G01X383383Y1132317D01*
G02X384086Y1131060I-772J-1257D01*
G03X385175Y1129147I2225J0D01*
G01X385196Y1129135D01*
X385199Y1129133D01*
G02X385936Y1127890I-737J-1277D01*
G01Y1127822D01*
G02X385199Y1126579I-1474J34D01*
G03X384086Y1124707I1112J-1928D01*
G01Y1124651D01*
G03X385175Y1122738I2225J0D01*
G01X385199Y1122724D01*
X385234Y1122704D01*
G02X385937Y1121447I-772J-1257D01*
G01Y1121386D01*
G03X387048Y1119520I2225J61D01*
G01X387083Y1119500D01*
G02X387786Y1118243I-772J-1257D01*
G01Y1118204D01*
G03X388898Y1116316I2225J39D01*
G01X388901Y1116314D01*
X388911Y1116308D01*
X388933Y1116296D01*
G02Y1113782I-772J-1257D01*
G01X388898Y1113762D01*
G03X387786Y1111907I1113J-1928D01*
G01Y1111834D01*
G02X387083Y1110577I-1475J0D01*
G01X387048Y1110557D01*
G03X385937Y1108691I1114J-1927D01*
G01Y1108569D01*
G03X387048Y1106703I2225J61D01*
G01X387083Y1106683D01*
G02X387786Y1105426I-772J-1257D01*
G01Y1105370D01*
G03X388899Y1103498I2225J56D01*
G01X388934Y1103478D01*
G02X389637Y1102221I-772J-1257D01*
G01Y1102160D01*
G03X390748Y1100294I2225J61D01*
G01X390783Y1100274D01*
G02X391486Y1099017I-772J-1257D01*
G03X392575Y1097104I2225J0D01*
G01X392596Y1097092D01*
X392599Y1097090D01*
X392605Y1097087D01*
X392634Y1097070D01*
G02Y1094556I-772J-1257D01*
G01X392599Y1094536D01*
G03X391486Y1092664I1112J-1928D01*
G01Y1092608D01*
G03X392575Y1090695I2225J0D01*
G01X392659Y1090647D01*
X392657D01*
G03X394825Y1090681I1054J1961D01*
G02X396299I737J-1277D01*
G01X396305Y1090678D01*
X396334Y1090661D01*
G02X397037Y1089404I-772J-1257D01*
G01Y1089365D01*
G03X398149Y1087477I2225J39D01*
G02X398886Y1086234I-737J-1277D01*
G01Y1086144D01*
G03X399999Y1084272I2225J56D01*
G01X400034Y1084252D01*
G02X400737Y1082995I-772J-1257D01*
G01Y1082934D01*
G03X401848Y1081068I2225J61D01*
G03X404016Y1081034I1114J1927D01*
G01X404020Y1081037D01*
X404074Y1081068D01*
G02X405548I737J-1277D01*
G03X407768Y1081067I1111J1921D01*
G01X408031Y1081218D01*
G02X408763Y1081274I425J-738D01*
G01X409044Y1081165D01*
X409127Y1080858D01*
X408511Y1079791D01*
G01X1371704Y1108630D02*
X1370473D01*
X1370214Y1108371D01*
G02X1370203Y1108289I-2210J255D01*
G02X1369140Y1106717I-2199J341D01*
G01X1369056Y1106669D01*
X1369058D01*
G02X1366890Y1106703I-1054J1961D01*
G02X1365779Y1108569I1114J1927D01*
G01Y1108691D01*
G02X1366890Y1110557I2225J-61D01*
G01X1366925Y1110577D01*
G03Y1113091I-773J1257D01*
G01X1366890Y1113111D01*
G02X1365778Y1114983I1114J1928D01*
G01Y1115039D01*
G03X1365075Y1116296I-1475J0D01*
G01X1365043Y1116314D01*
X1365040Y1116316D01*
G02X1363928Y1118204I1113J1927D01*
G01Y1118243D01*
G03X1363225Y1119500I-1475J0D01*
G01X1363190Y1119520D01*
G02X1362079Y1121386I1114J1927D01*
G01Y1121447D01*
G03X1361376Y1122704I-1475J0D01*
G01X1361347Y1122721D01*
X1361341Y1122724D01*
X1361338Y1122726D01*
X1361317Y1122738D01*
G02X1360228Y1124651I1136J1913D01*
G01Y1124707D01*
G02X1361341Y1126579I2225J-56D01*
G03X1362078Y1127822I-737J1277D01*
G01Y1127890D01*
G03X1361341Y1129133I-1474J-34D01*
G01X1361338Y1129135D01*
X1361327Y1129141D01*
X1361317Y1129147D01*
G02X1360228Y1131060I1136J1913D01*
G03X1359525Y1132317I-1475J0D01*
G01X1359490Y1132337D01*
G02X1358379Y1134203I1114J1927D01*
G01Y1134264D01*
G03X1357676Y1135521I-1475J0D01*
G01X1357641Y1135541D01*
G02X1356529Y1137396I1113J1928D01*
G01Y1138243D01*
X1356530Y1138244D01*
G02X1356591Y1138400I2222J-779D01*
G02X1357654Y1139552I2164J-930D01*
G01X1357655D01*
G03X1357668Y1139559I-756J1419D01*
G03X1358379Y1140335I-765J1414D01*
G01Y1141593D01*
X1351592Y1148380D01*
Y1162317D01*
X1351427Y1162482D01*
Y1162569D01*
G01X371943Y1151189D02*
Y1151102D01*
X371777Y1150936D01*
Y1149465D01*
X379285Y1141957D01*
Y1140198D01*
X379286Y1140197D01*
Y1140195D01*
G02X378162Y1138889I-2225J778D01*
G03X377437Y1138104I750J-1420D01*
G01Y1137469D01*
G03X378140Y1136212I1475J0D01*
G01X378175Y1136192D01*
G02X379287Y1134337I-1113J-1928D01*
G01Y1134264D01*
G03X379990Y1133007I1475J0D01*
G01X380025Y1132987D01*
G02X381136Y1131121I-1114J-1927D01*
G01Y1131060D01*
G03X381839Y1129803I1475J0D01*
G01X381874Y1129783D01*
X381889Y1129774D01*
X381922Y1129755D01*
G02X382987Y1127856I-1161J-1899D01*
G01Y1127826D01*
G02X381874Y1125928I-2226J30D01*
G01X381871Y1125926D01*
X381839Y1125908D01*
G03Y1123394I773J-1257D01*
G01X381868Y1123377D01*
X381874Y1123374D01*
X381885Y1123368D01*
X381898Y1123360D01*
G02X382987Y1121447I-1136J-1913D01*
G03X383690Y1120190I1475J0D01*
G01X383725Y1120170D01*
G02X384836Y1118304I-1114J-1927D01*
G01Y1118243D01*
G03X385539Y1116986I1475J0D01*
G01X385574Y1116966D01*
G02X386686Y1115078I-1113J-1927D01*
G01Y1114966D01*
G02X385574Y1113111I-2225J73D01*
G01X385571Y1113109D01*
X385539Y1113091D01*
G03X384854Y1112060I773J-1256D01*
G01X385080Y1111834D01*
X386311D01*
G01X1379104Y1102221D02*
X1378488Y1101154D01*
X1378571Y1100847D01*
G03X1379841Y1100944I534J1374D01*
G03X1380578Y1102187I-737J1277D01*
G01Y1102255D01*
G03X1379841Y1103498I-1474J-34D01*
G03X1378367I-737J-1277D01*
G02X1376199Y1103464I-1115J1928D01*
G01X1376141Y1103498D01*
G03X1374667I-737J-1277D01*
G02X1372499Y1103464I-1115J1928D01*
G01X1372441Y1103498D01*
G03X1370967I-737J-1277D01*
G02X1368799Y1103464I-1115J1928D01*
G01X1368741Y1103498D01*
G03X1367267I-737J-1277D01*
G02X1365099Y1103464I-1115J1928D01*
G01X1365041Y1103498D01*
G02X1363928Y1105370I1112J1928D01*
G01Y1105426D01*
G03X1363225Y1106683I-1475J0D01*
G01X1363190Y1106703D01*
G02X1362079Y1108569I1114J1927D01*
G01Y1108691D01*
G02X1363190Y1110557I2225J-61D01*
G01X1363225Y1110577D01*
G03X1363927Y1111794I-773J1257D01*
G03Y1111882I-1475J44D01*
G03X1363225Y1113091I-1474J-48D01*
G01X1363190Y1113111D01*
G02X1362078Y1114966I1113J1928D01*
G01Y1115039D01*
G03X1361375Y1116296I-1475J0D01*
G01X1361340Y1116316D01*
G02X1360228Y1118204I1113J1927D01*
G01Y1118243D01*
G03X1359525Y1119500I-1475J0D01*
G01X1359490Y1119520D01*
G02X1358379Y1121386I1114J1927D01*
G01Y1121447D01*
G03X1357676Y1122704I-1475J0D01*
G01X1357641Y1122724D01*
X1357617Y1122738D01*
G02X1356528Y1124651I1136J1913D01*
G01Y1124724D01*
G02X1357640Y1126579I2225J-73D01*
G01X1357675Y1126599D01*
G03Y1129113I-772J1257D01*
G01X1357643Y1129131D01*
X1357640Y1129133D01*
G02X1356528Y1131021I1113J1927D01*
G01Y1131060D01*
G03X1355825Y1132317I-1475J0D01*
G01X1355790Y1132337D01*
G02X1354679Y1134203I1114J1927D01*
G01Y1134264D01*
G03X1353976Y1135521I-1475J0D01*
G01X1353941Y1135541D01*
G02X1352829Y1137396I1113J1928D01*
G01Y1138247D01*
G02X1353953Y1139553I2225J-778D01*
G03X1354678Y1140338I-750J1420D01*
G01Y1140973D01*
G03X1353975Y1142230I-1475J0D01*
G01X1353943Y1142250D01*
G02X1353481Y1142602I1106J1931D01*
G01X1350384Y1145699D01*
X1349831D01*
X1349343Y1146187D01*
Y1146740D01*
X1348303Y1147780D01*
Y1149152D01*
X1347913Y1149542D01*
Y1150232D01*
X1348303Y1150622D01*
Y1151312D01*
X1347913Y1151702D01*
Y1152392D01*
X1348303Y1152782D01*
Y1153472D01*
X1347913Y1153862D01*
Y1154552D01*
X1348303Y1154942D01*
Y1155632D01*
X1347913Y1156022D01*
Y1156712D01*
X1348303Y1157102D01*
Y1159147D01*
X1348138Y1159312D01*
Y1159399D01*
G01X382072Y1143755D02*
X382133Y1143694D01*
Y1143458D01*
X382989Y1142602D01*
Y1141392D01*
X382983Y1140681D01*
G02X382276Y1139166I-2013J17D01*
G02X381862Y1138889I-1505J1801D01*
G03X381137Y1138104I750J-1420D01*
G01Y1137469D01*
G03X381840Y1136212I1475J0D01*
G01X381875Y1136192D01*
G02X382987Y1134337I-1113J-1928D01*
G01Y1134264D01*
G03X383690Y1133007I1475J0D01*
G01X383725Y1132987D01*
G02X384836Y1131121I-1114J-1927D01*
G01Y1131060D01*
G03X385539Y1129803I1475J0D01*
G01X385599Y1129768D01*
X385598Y1129769D01*
G02X386687Y1127856I-1136J-1913D01*
G01Y1127800D01*
G02X385574Y1125928I-2225J56D01*
G01X385539Y1125908D01*
G03Y1123394I771J-1257D01*
G01X385574Y1123374D01*
X385598Y1123360D01*
G02X386687Y1121447I-1136J-1913D01*
G03X387390Y1120190I1475J0D01*
G01X387425Y1120170D01*
G02X388536Y1118304I-1114J-1927D01*
G01Y1118243D01*
G03X389239Y1116986I1475J0D01*
G01X389274Y1116966D01*
X389289Y1116957D01*
X389322Y1116938D01*
G02X390387Y1115039I-1161J-1899D01*
G01Y1115009D01*
G02X389274Y1113111I-2226J30D01*
G01X389271Y1113109D01*
X389239Y1113091D01*
G03X388536Y1111834I772J-1257D01*
G01Y1111773D01*
G02X387425Y1109907I-2225J61D01*
G01X387390Y1109887D01*
G03Y1107373I773J-1257D01*
G01X387425Y1107353D01*
G02X388536Y1105487I-1114J-1927D01*
G01Y1105426D01*
G03X389239Y1104169I1475J0D01*
G01X389274Y1104149D01*
G02X390387Y1102277I-1112J-1928D01*
G01Y1102221D01*
G03X391090Y1100964I1475J0D01*
G01X391125Y1100944D01*
G02X392236Y1099078I-1114J-1927D01*
G01Y1099017D01*
G03X392939Y1097760I1475J0D01*
G01X392968Y1097743D01*
X392974Y1097740D01*
X392985Y1097734D01*
X392998Y1097726D01*
G02X394087Y1095813I-1136J-1913D01*
G01Y1095757D01*
G02X392974Y1093885I-2225J56D01*
G01X392939Y1093865D01*
G03Y1091351I771J-1257D01*
G01X392968Y1091334D01*
X392974Y1091331D01*
G03X394448I737J1277D01*
G02X396616Y1091365I1114J-1927D01*
G01X396674Y1091331D01*
X396683Y1091326D01*
X396691Y1091321D01*
X396698Y1091317D01*
G02X397787Y1089404I-1136J-1913D01*
G01X397786D01*
Y1089373D01*
G03X398524Y1088126I1476J32D01*
G02X399635Y1086242I-1112J-1925D01*
G01Y1086155D01*
G03X400373Y1084922I1476J46D01*
G01X400415Y1084897D01*
G02X401486Y1082995I-1153J-1902D01*
G01Y1082946D01*
G03X403637Y1081682I1476J50D01*
G01X403649Y1081688D01*
X403704Y1081720D01*
G02X405923Y1081717I1107J-1929D01*
G03X407394Y1081716I736J1272D01*
G01X407657Y1081868D01*
G02X409035Y1081972I798J-1388D01*
G01X409395Y1081834D01*
X409746Y1081928D01*
X410362Y1082995D01*
G01X1380953Y1099017D02*
X1382184D01*
X1382410Y1098791D01*
G02X1381725Y1097760I-1458J225D01*
G01X1381690Y1097740D01*
G02X1380216I-737J1277D01*
G01X1380158Y1097774D01*
G03X1377990Y1097740I-1054J-1961D01*
G02X1376516I-737J1277D01*
G03X1374332Y1097764I-1113J-1927D01*
G01X1374291Y1097740D01*
G02X1372817I-737J1277D01*
G01X1372776Y1097764D01*
G03X1370590Y1097740I-1072J-1951D01*
G02X1369116I-737J1277D01*
G01X1369058Y1097774D01*
G03X1366890Y1097740I-1054J-1961D01*
G02X1365416I-737J1277D01*
G02X1364679Y1098983I737J1277D01*
G01Y1099056D01*
G03X1363567Y1100944I-2225J-39D01*
G01X1363532Y1100964D01*
G02X1362829Y1102221I772J1257D01*
G01Y1102277D01*
G03X1361716Y1104149I-2225J-56D01*
G01X1361681Y1104169D01*
G02X1360978Y1105426I772J1257D01*
G01Y1105487D01*
G03X1359867Y1107353I-2225J-61D01*
G01X1359832Y1107373D01*
G02X1359129Y1108630I772J1257D01*
G03X1358040Y1110543I-2225J0D01*
G01X1358016Y1110557D01*
X1357981Y1110577D01*
G02Y1113091I772J1257D01*
G01X1358016Y1113111D01*
G03X1359129Y1114983I-1112J1928D01*
G01Y1115039D01*
G03X1358040Y1116952I-2225J0D01*
G01X1357981Y1116987D01*
Y1116986D01*
G02X1357278Y1118243I772J1257D01*
G01Y1118304D01*
G03X1356167Y1120170I-2225J-61D01*
G01X1356132Y1120190D01*
G02X1355429Y1121447I772J1257D01*
G03X1354340Y1123360I-2225J0D01*
G01X1354316Y1123374D01*
X1354281Y1123394D01*
G02Y1125908I772J1257D01*
G01X1354316Y1125928D01*
G03X1355429Y1127800I-1112J1928D01*
G01Y1127856D01*
G03X1354340Y1129769I-2225J0D01*
G01X1354281Y1129804D01*
Y1129803D01*
G02X1353578Y1131060I772J1257D01*
G01Y1131121D01*
G03X1352467Y1132987I-2225J-61D01*
G01X1352432Y1133007D01*
G02X1351729Y1134264I772J1257D01*
G01Y1134337D01*
G03X1350617Y1136192I-2225J-73D01*
G01X1350582Y1136212D01*
G02X1349879Y1137469I772J1257D01*
G01Y1138246D01*
G03X1348754Y1139553I-2225J-777D01*
G02X1348028Y1140340I749J1420D01*
G01Y1142834D01*
X1345172Y1145690D01*
Y1150577D01*
X1345562Y1150967D01*
Y1151657D01*
X1345172Y1152047D01*
Y1152737D01*
X1345562Y1153127D01*
Y1153817D01*
X1345172Y1154207D01*
Y1154897D01*
X1345562Y1155287D01*
Y1155977D01*
X1345172Y1156367D01*
Y1157057D01*
X1345562Y1157447D01*
Y1158137D01*
X1345172Y1158527D01*
Y1161506D01*
X1345338Y1161672D01*
Y1161759D01*
G01X382118Y1146832D02*
X382179Y1146771D01*
X382411D01*
X385936Y1143246D01*
Y1140338D01*
G02X385211Y1139553I-1475J635D01*
G03X384087Y1138247I1101J-2084D01*
G01Y1137396D01*
G03X385199Y1135541I2225J73D01*
G01X385234Y1135521D01*
G02X385937Y1134264I-772J-1257D01*
G01Y1134203D01*
G03X387048Y1132337I2225J61D01*
G01X387083Y1132317D01*
G02X387786Y1131060I-772J-1257D01*
G01Y1131021D01*
G03X388898Y1129133I2225J39D01*
G01X388901Y1129131D01*
X388911Y1129125D01*
X388933Y1129113D01*
G02Y1126599I-772J-1257D01*
G01X388901Y1126581D01*
X388898Y1126579D01*
G03X387786Y1124724I1113J-1928D01*
G01Y1124651D01*
G03X388875Y1122738I2225J0D01*
G01X388899Y1122724D01*
X388934Y1122704D01*
G02X389637Y1121447I-772J-1257D01*
G01Y1121386D01*
G03X390748Y1119520I2225J61D01*
G01X390783Y1119500D01*
G02X391486Y1118243I-772J-1257D01*
G03X392575Y1116330I2225J0D01*
G01X392596Y1116318D01*
X392599Y1116316D01*
G02X393336Y1115073I-737J-1277D01*
G01Y1114966D01*
G03X394448Y1113111I2225J73D01*
G01X394483Y1113091D01*
G02X395185Y1111882I-773J-1257D01*
G02Y1111794I-1475J-44D01*
G02X394483Y1110577I-1475J40D01*
G01X394448Y1110557D01*
G02X392974I-737J1277D01*
G01X392916Y1110591D01*
G03X390748Y1110557I-1054J-1961D01*
G03X389637Y1108691I1114J-1927D01*
G01Y1108569D01*
G03X390748Y1106703I2225J61D01*
G01X390783Y1106683D01*
G02X391486Y1105426I-772J-1257D01*
G01Y1105370D01*
G03X392599Y1103498I2225J56D01*
G01X392634Y1103478D01*
G02X393337Y1102221I-772J-1257D01*
G01Y1102160D01*
G03X394448Y1100294I2225J61D01*
G01X394452Y1100292D01*
X394483Y1100274D01*
G02X395186Y1099017I-772J-1257D01*
G03X396251Y1097118I2226J0D01*
G01X396299Y1097090D01*
G02X397036Y1095847I-737J-1277D01*
G01Y1095740D01*
G03X398148Y1093885I2225J73D01*
G01X398183Y1093865D01*
G02X398886Y1092608I-772J-1257D01*
G03X399951Y1090709I2226J0D01*
G01X399999Y1090681D01*
G02X400736Y1089438I-737J-1277D01*
G01Y1089365D01*
G03X401848Y1087477I2225J39D01*
G01X401883Y1087457D01*
G02X402586Y1086200I-772J-1257D01*
G01Y1086144D01*
G03X403699Y1084272I2225J56D01*
G01X403734Y1084252D01*
G02X404419Y1083221I-773J-1256D01*
G01X404193Y1082995D01*
X402962D01*
G01X1345803Y1108630D02*
X1345187Y1109697D01*
X1345270Y1110004D01*
G02X1346540Y1109907I534J-1374D01*
G03X1348708Y1109873I1114J1927D01*
G01X1348766Y1109907D01*
X1348790Y1109921D01*
G03X1349879Y1111834I-1136J1913D01*
G01Y1111868D01*
G02X1350616Y1113111I1474J-34D01*
G03X1351728Y1114966I-1113J1928D01*
G01Y1115078D01*
G03X1350616Y1116966I-2225J-39D01*
G01X1350581Y1116986D01*
G02X1349878Y1118243I772J1257D01*
G01Y1118304D01*
G03X1348767Y1120170I-2225J-61D01*
G01X1348732Y1120190D01*
G02X1348029Y1121447I772J1257D01*
G03X1346940Y1123360I-2225J0D01*
G01X1346916Y1123374D01*
X1346881Y1123394D01*
G02Y1125908I772J1257D01*
G01X1346916Y1125928D01*
G03X1348029Y1127800I-1112J1928D01*
G01Y1127856D01*
G03X1346940Y1129769I-2225J0D01*
G01X1346881Y1129804D01*
Y1129803D01*
G02X1346178Y1131060I772J1257D01*
G01Y1131121D01*
G03X1345067Y1132987I-2225J-61D01*
G01X1345032Y1133007D01*
G02X1344330Y1134224I773J1257D01*
G01X1344329Y1134261D01*
Y1134337D01*
G03X1343217Y1136192I-2225J-73D01*
G01X1343182Y1136212D01*
G02X1342479Y1137469I772J1257D01*
G01Y1138104D01*
G02X1343204Y1138889I1475J-635D01*
G03X1344328Y1140195I-1101J2084D01*
G01Y1141924D01*
X1341969Y1144283D01*
Y1145985D01*
X1335879Y1152075D01*
Y1152311D01*
X1335818Y1152372D01*
G01X389471Y1142843D02*
Y1142756D01*
X389636Y1142591D01*
Y1140338D01*
G02X388911Y1139553I-1475J635D01*
G03X387787Y1138247I1101J-2084D01*
G01Y1137396D01*
G03X388899Y1135541I2225J73D01*
G01X388934Y1135521D01*
G02X389637Y1134264I-772J-1257D01*
G01Y1134203D01*
G03X390748Y1132337I2225J61D01*
G01X390783Y1132317D01*
G02X391486Y1131060I-772J-1257D01*
G03X392575Y1129147I2225J0D01*
G01X392596Y1129135D01*
X392599Y1129133D01*
G02X393336Y1127890I-737J-1277D01*
G01Y1127822D01*
G02X392599Y1126579I-1474J34D01*
G03X391486Y1124707I1112J-1928D01*
G01Y1124651D01*
G03X392575Y1122738I2225J0D01*
G01X392596Y1122726D01*
X392599Y1122724D01*
X392605Y1122721D01*
X392634Y1122704D01*
G02X393337Y1121447I-772J-1257D01*
G01Y1121386D01*
G03X394448Y1119520I2225J61D01*
G01X394483Y1119500D01*
G02X395186Y1118243I-772J-1257D01*
G01Y1118204D01*
G03X396298Y1116316I2225J39D01*
G01X396301Y1116314D01*
X396308Y1116310D01*
X396311Y1116308D01*
X396333Y1116296D01*
G02X397036Y1115039I-772J-1257D01*
G01Y1114983D01*
G03X398148Y1113111I2226J56D01*
G01X398183Y1113091D01*
G02X398885Y1111892I-772J-1257D01*
G02X398886Y1111794I-1474J-64D01*
G02X398183Y1110577I-1475J40D01*
G01X398148Y1110557D01*
G03X397037Y1108691I1114J-1927D01*
G01Y1108630D01*
G02X396334Y1107373I-1475J0D01*
G01X396326Y1107368D01*
X396313Y1107361D01*
X396305Y1107356D01*
X396299Y1107353D01*
X396293Y1107349D01*
X396288Y1107346D01*
X396275Y1107339D01*
G03X395186Y1105426I1136J-1913D01*
G01Y1105370D01*
G03X396299Y1103498I2225J56D01*
G01X396334Y1103478D01*
G02X397037Y1102221I-772J-1257D01*
G01Y1102182D01*
G03X398149Y1100294I2225J39D01*
G02X398886Y1099051I-737J-1277D01*
G01Y1098978D01*
G03X399998Y1097090I2225J39D01*
G01X400033Y1097070D01*
G02X400736Y1095813I-772J-1257D01*
G01Y1095783D01*
G03X401849Y1093885I2226J30D01*
G02X402586Y1092642I-737J-1277D01*
G01Y1092535D01*
G03X403698Y1090680I2225J73D01*
G03X405890Y1090660I1114J1928D01*
G01X405925Y1090681D01*
G02X407195Y1090778I736J-1277D01*
G01X407278Y1090471D01*
X406662Y1089404D01*
G01X1384653Y1099017D02*
X1383422D01*
X1383164Y1098759D01*
G02X1383153Y1098676I-2212J251D01*
G02X1382067Y1097090I-2200J341D01*
G02X1379899Y1097056I-1114J1927D01*
G01X1379841Y1097090D01*
G03X1378367I-737J-1277D01*
G02X1376181Y1097066I-1114J1927D01*
G01X1376140Y1097090D01*
G03X1374666I-737J-1277D01*
G01X1374625Y1097066D01*
G02X1372441Y1097090I-1071J1951D01*
G03X1370967I-737J-1277D01*
G02X1368799Y1097056I-1114J1927D01*
G01X1368741Y1097090D01*
G03X1367267I-737J-1277D01*
G02X1365099Y1097056I-1114J1927D01*
G01X1365041Y1097090D01*
X1365017Y1097104D01*
G02X1363928Y1099017I1136J1913D01*
G01Y1099051D01*
G03X1363191Y1100294I-1474J-34D01*
G02X1362079Y1102182I1113J1927D01*
G01Y1102221D01*
G03X1361376Y1103478I-1475J0D01*
G01X1361341Y1103498D01*
G02X1360228Y1105370I1112J1928D01*
G01Y1105426D01*
G03X1359525Y1106683I-1475J0D01*
G01X1359490Y1106703D01*
G02X1358379Y1108569I1114J1927D01*
G01Y1108630D01*
G03X1357676Y1109887I-1475J0D01*
G01X1357641Y1109907D01*
X1357617Y1109921D01*
G02X1356528Y1111834I1136J1913D01*
G01Y1111890D01*
G02X1357641Y1113762I2225J-56D01*
G03X1358378Y1115005I-737J1277D01*
G01Y1115073D01*
G03X1357641Y1116316I-1474J-34D01*
G01X1357638Y1116318D01*
X1357617Y1116330D01*
G02X1356528Y1118243I1136J1913D01*
G03X1355825Y1119500I-1475J0D01*
G01X1355790Y1119520D01*
G02X1354679Y1121386I1114J1927D01*
G01Y1121447D01*
G03X1353976Y1122704I-1475J0D01*
G01X1353941Y1122724D01*
X1353917Y1122738D01*
G02X1352828Y1124651I1136J1913D01*
G01Y1124707D01*
G02X1353941Y1126579I2225J-56D01*
G03X1354678Y1127822I-737J1277D01*
G01Y1127890D01*
G03X1353941Y1129133I-1474J-34D01*
G01X1353938Y1129135D01*
X1353917Y1129147D01*
G02X1352828Y1131060I1136J1913D01*
G03X1352125Y1132317I-1475J0D01*
G01X1352090Y1132337D01*
G02X1350979Y1134203I1114J1927D01*
G01Y1134264D01*
G03X1350276Y1135521I-1475J0D01*
G01X1350241Y1135541D01*
G02X1349129Y1137396I1113J1928D01*
G01Y1138102D01*
G03X1348403Y1138889I-1475J-633D01*
G01X1348404Y1138890D01*
G02X1347279Y1140201I1100J2082D01*
G01Y1142523D01*
X1344423Y1145379D01*
Y1161507D01*
X1344258Y1161672D01*
Y1161759D01*
G01X382882Y1147596D02*
X382943Y1147535D01*
Y1147299D01*
X386685Y1143557D01*
Y1140198D01*
X386686Y1140197D01*
Y1140195D01*
G02X385562Y1138889I-2225J778D01*
G03X384837Y1138104I750J-1420D01*
G01Y1137469D01*
G03X385540Y1136212I1475J0D01*
G01X385575Y1136192D01*
G02X386687Y1134337I-1113J-1928D01*
G01Y1134264D01*
G03X387390Y1133007I1475J0D01*
G01X387425Y1132987D01*
G02X388536Y1131121I-1114J-1927D01*
G01Y1131060D01*
G03X389239Y1129803I1475J0D01*
G01X389274Y1129783D01*
X389289Y1129774D01*
X389322Y1129755D01*
G02X390387Y1127856I-1161J-1899D01*
G01Y1127826D01*
G02X389274Y1125928I-2226J30D01*
G01X389239Y1125908D01*
G03Y1123394I773J-1257D01*
G01X389274Y1123374D01*
X389298Y1123360D01*
G02X390387Y1121447I-1136J-1913D01*
G03X391090Y1120190I1475J0D01*
G01X391125Y1120170D01*
G02X392236Y1118304I-1114J-1927D01*
G01Y1118243D01*
G03X392939Y1116986I1475J0D01*
G01X392999Y1116951D01*
X392998Y1116952D01*
G02X394087Y1115039I-1136J-1913D01*
G01Y1115005D01*
G03X394824Y1113762I1474J34D01*
G02X395936Y1111907I-1113J-1928D01*
G01Y1111773D01*
G02X394825Y1109907I-2225J61D01*
G02X392657Y1109873I-1114J1927D01*
G01X392599Y1109907D01*
G03X391125I-737J-1277D01*
G01X391090Y1109887D01*
G03Y1107373I773J-1257D01*
G01X391125Y1107353D01*
G02X392236Y1105487I-1114J-1927D01*
G01Y1105426D01*
G03X392939Y1104169I1475J0D01*
G01X392974Y1104149D01*
G02X394087Y1102277I-1112J-1928D01*
G01Y1102221D01*
G03X394790Y1100964I1475J0D01*
G01X394825Y1100944D01*
X394849Y1100930D01*
G02X395937Y1099017I-1138J-1913D01*
G03X396640Y1097760I1475J0D01*
G01X396675Y1097740D01*
G02X397787Y1095852I-1113J-1927D01*
G01Y1095779D01*
G03X398524Y1094536I1474J34D01*
G02X399637Y1092638I-1113J-1928D01*
G01Y1092608D01*
G03X400340Y1091351I1475J0D01*
G01X400375Y1091331D01*
G02X401487Y1089443I-1113J-1927D01*
G01Y1089370D01*
G03X402224Y1088127I1474J34D01*
G02X403336Y1086239I-1113J-1927D01*
G01Y1086200D01*
G03X404039Y1084943I1475J0D01*
G01X404074Y1084923D01*
G02X405162Y1083336I-1111J-1928D01*
G02X405173Y1083253I-2201J-334D01*
G01X405431Y1082995D01*
X406662D01*
G01X1343954Y1111834D02*
X1344570Y1110767D01*
X1344920Y1110674D01*
G02X1344998Y1110706I884J-2043D01*
G02X1346917Y1110557I804J-2076D01*
G03X1348391I737J1277D01*
G03X1349128Y1111800I-737J1277D01*
G01Y1111907D01*
G02X1350240Y1113762I2225J-73D01*
G01X1350275Y1113782D01*
G03X1350977Y1114991I-772J1257D01*
G03X1350978Y1115065I-1474J57D01*
G03X1350275Y1116296I-1475J-26D01*
G01X1350240Y1116316D01*
G02X1349128Y1118204I1113J1927D01*
G01Y1118243D01*
G03X1348425Y1119500I-1475J0D01*
G01X1348390Y1119520D01*
G02X1347279Y1121386I1114J1927D01*
G01Y1121447D01*
G03X1346576Y1122704I-1475J0D01*
G01X1346541Y1122724D01*
X1346517Y1122738D01*
G02X1345428Y1124651I1136J1913D01*
G01Y1124707D01*
G02X1346541Y1126579I2225J-56D01*
G03X1347278Y1127822I-737J1277D01*
G01Y1127890D01*
G03X1346541Y1129133I-1474J-34D01*
G01X1346538Y1129135D01*
X1346517Y1129147D01*
G02X1345428Y1131060I1136J1913D01*
G03X1344725Y1132317I-1475J0D01*
G01X1344690Y1132337D01*
G02X1343579Y1134203I1114J1927D01*
G01Y1134264D01*
G03X1342876Y1135521I-1475J0D01*
G01X1342841Y1135541D01*
G02X1341729Y1137396I1113J1928D01*
G01Y1138247D01*
G02X1342853Y1139553I2225J-778D01*
G03X1343578Y1140338I-750J1420D01*
G01X1343579Y1140340D01*
Y1141613D01*
X1341220Y1143972D01*
Y1145674D01*
X1335347Y1151547D01*
X1335115D01*
X1335054Y1151608D01*
G01X390551Y1142843D02*
Y1142756D01*
X390385Y1142590D01*
Y1140198D01*
X390386Y1140197D01*
Y1140195D01*
G02X389262Y1138889I-2225J778D01*
G03X388537Y1138104I750J-1420D01*
G01Y1137469D01*
G03X389240Y1136212I1475J0D01*
G01X389275Y1136192D01*
G02X390387Y1134337I-1113J-1928D01*
G01Y1134264D01*
G03X391090Y1133007I1475J0D01*
G01X391125Y1132987D01*
G02X392236Y1131121I-1114J-1927D01*
G01Y1131060D01*
G03X392939Y1129803I1475J0D01*
G01X392999Y1129768D01*
X392998Y1129769D01*
G02X394087Y1127856I-1136J-1913D01*
G01Y1127800D01*
G02X392974Y1125928I-2225J56D01*
G01X392939Y1125908D01*
G03Y1123394I771J-1257D01*
G01X392968Y1123377D01*
X392974Y1123374D01*
X392985Y1123368D01*
X392998Y1123360D01*
G02X394087Y1121447I-1136J-1913D01*
G03X394790Y1120190I1475J0D01*
G01X394825Y1120170D01*
G02X395936Y1118304I-1114J-1927D01*
G01Y1118243D01*
G03X396639Y1116986I1475J0D01*
G01X396674Y1116966D01*
X396722Y1116938D01*
G02X397787Y1115039I-1161J-1899D01*
G03X398490Y1113782I1475J0D01*
G01X398525Y1113762D01*
G02X399636Y1111921I-1114J-1928D01*
G01Y1111773D01*
G02X398525Y1109907I-2225J61D01*
G01X398490Y1109887D01*
G03X397787Y1108630I772J-1257D01*
G02X396698Y1106717I-2225J0D01*
G01X396677Y1106705D01*
X396671Y1106701D01*
X396639Y1106682D01*
Y1106683D01*
G03Y1104169I772J-1257D01*
G01X396674Y1104149D01*
G02X397787Y1102277I-1112J-1928D01*
G01Y1102221D01*
G03X398490Y1100964I1475J0D01*
G01X398525Y1100944D01*
G02X399637Y1099056I-1113J-1927D01*
G01Y1098983D01*
G03X400374Y1097740I1474J34D01*
G01X400422Y1097712D01*
G02X401487Y1095813I-1161J-1899D01*
G03X402190Y1094556I1475J0D01*
G01X402225Y1094536D01*
G02X403337Y1092681I-1113J-1928D01*
G01Y1092574D01*
G03X404074Y1091331I1474J34D01*
G03X405548I737J1277D01*
G02X407467Y1091480I1115J-1927D01*
G02X407545Y1091448I-806J-2075D01*
G01X407895Y1091541D01*
X408511Y1092608D01*
G01X1342103Y1115039D02*
X1343334D01*
X1343592Y1114781D01*
G03X1343603Y1114698I2212J251D01*
G03X1344691Y1113111I2199J341D01*
G01X1344749Y1113077D01*
G03X1346917Y1113111I1053J1962D01*
G03X1348028Y1114952I-1114J1928D01*
G01Y1115078D01*
G03X1346916Y1116966I-2225J-39D01*
G01X1346881Y1116986D01*
G02X1346178Y1118243I772J1257D01*
G01Y1118304D01*
G03X1345067Y1120170I-2225J-61D01*
G01X1345032Y1120190D01*
G02X1344329Y1121447I772J1257D01*
G03X1343240Y1123360I-2225J0D01*
G01X1343219Y1123372D01*
X1343216Y1123374D01*
X1343189Y1123389D01*
X1343181Y1123394D01*
G02Y1125908I772J1257D01*
G01X1343216Y1125928D01*
G03X1344329Y1127800I-1112J1928D01*
G01Y1127856D01*
G03X1343240Y1129769I-2225J0D01*
G01X1343219Y1129781D01*
X1343216Y1129783D01*
G02X1342479Y1131026I737J1277D01*
G01Y1131099D01*
G03X1341367Y1132987I-2225J-39D01*
G01X1341332Y1133007D01*
G02X1340629Y1134264I772J1257D01*
G01Y1134337D01*
G03X1339517Y1136192I-2225J-73D01*
G01X1339482Y1136212D01*
G02X1338779Y1137469I772J1257D01*
G01Y1138104D01*
G02X1339504Y1138889I1475J-635D01*
G01X1339503Y1138890D01*
G03X1340627Y1140198I-1100J2082D01*
G01Y1142367D01*
X1335365Y1147629D01*
Y1147865D01*
X1335304Y1147926D01*
G01X393171Y1143423D02*
Y1143336D01*
X393336Y1143171D01*
Y1140196D01*
G03X393395Y1140043I2227J771D01*
G03X394461Y1138889I2165J931D01*
G02X395187Y1138102I-749J-1420D01*
G01Y1137396D01*
G03X396299Y1135541I2225J73D01*
G01X396302Y1135539D01*
X396334Y1135521D01*
G02X397037Y1134264I-772J-1257D01*
G01Y1134203D01*
G03X398148Y1132337I2225J61D01*
G01X398183Y1132317D01*
G02X398886Y1131060I-772J-1257D01*
G03X399975Y1129147I2225J0D01*
G01X399996Y1129135D01*
X399999Y1129133D01*
G02X400736Y1127890I-737J-1277D01*
G01Y1127822D01*
G02X399999Y1126579I-1474J34D01*
G03X398886Y1124707I1112J-1928D01*
G01Y1124651D01*
G03X399975Y1122738I2225J0D01*
G01X399996Y1122726D01*
X399999Y1122724D01*
X400005Y1122721D01*
X400034Y1122704D01*
G02X400737Y1121447I-772J-1257D01*
G01Y1121386D01*
G03X401848Y1119520I2225J61D01*
G01X401883Y1119500D01*
G02X402586Y1118243I-772J-1257D01*
G03X403675Y1116330I2225J0D01*
G01X403696Y1116318D01*
X403699Y1116316D01*
G02X404436Y1115073I-737J-1277D01*
G01Y1115005D01*
G02X403699Y1113762I-1474J34D01*
G03X402586Y1111864I1113J-1928D01*
G01Y1111834D01*
G03X403651Y1109935I2226J0D01*
G01X403699Y1109907D01*
G02X404436Y1108664I-737J-1277D01*
G01Y1108596D01*
G02X403699Y1107353I-1474J34D01*
G01X403651Y1107325D01*
G03X402586Y1105426I1161J-1899D01*
G01Y1105396D01*
G03X403699Y1103498I2226J30D01*
G02X404436Y1102255I-737J-1277D01*
G01Y1102187D01*
G02X403699Y1100944I-1474J34D01*
G01X403696Y1100942D01*
X403675Y1100930D01*
G03Y1097104I1136J-1913D01*
G01X403696Y1097092D01*
X403699Y1097090D01*
X403705Y1097087D01*
X403734Y1097070D01*
G02X404437Y1095813I-772J-1257D01*
G01Y1095726D01*
G03X405548Y1093885I2225J87D01*
G03X407716Y1093851I1115J1928D01*
G01X407774Y1093885D01*
G02X409248I737J-1277D01*
G01X409283Y1093865D01*
G02X409985Y1092666I-772J-1257D01*
G02X409986Y1092608I-1474J-54D01*
G03X411075Y1090695I2225J0D01*
G01X411096Y1090683D01*
X411099Y1090681D01*
X411105Y1090678D01*
X411134Y1090661D01*
G02X411819Y1089630I-773J-1256D01*
G01X411593Y1089404D01*
X410362D01*
G01X1345803Y1115039D02*
X1344572D01*
X1344346Y1114813D01*
G03X1345031Y1113782I1458J225D01*
G01X1345066Y1113762D01*
G03X1346540I737J1277D01*
G01X1346575Y1113782D01*
G03X1347277Y1114981I-772J1257D01*
G03X1347278Y1115039I-1474J54D01*
G03X1346575Y1116296I-1475J0D01*
G01X1346543Y1116314D01*
X1346540Y1116316D01*
G02X1345428Y1118204I1113J1927D01*
G01Y1118243D01*
G03X1344725Y1119500I-1475J0D01*
G01X1344690Y1119520D01*
G02X1343579Y1121386I1114J1927D01*
G01Y1121447D01*
G03X1342876Y1122704I-1475J0D01*
G01X1342816Y1122739D01*
X1342817Y1122738D01*
G02X1341728Y1124651I1136J1913D01*
G01Y1124707D01*
G02X1342841Y1126579I2225J-56D01*
G01X1342876Y1126599D01*
G03Y1129113I-771J1257D01*
G01X1342816Y1129148D01*
X1342817Y1129147D01*
G02X1341728Y1131060I1136J1913D01*
G01Y1131094D01*
G03X1340991Y1132337I-1474J-34D01*
G02X1339879Y1134225I1113J1927D01*
G01Y1134264D01*
G03X1339176Y1135521I-1475J0D01*
G01X1339144Y1135539D01*
X1339141Y1135541D01*
G02X1338029Y1137396I1113J1928D01*
G01Y1138247D01*
G02X1339153Y1139553I2225J-778D01*
G01X1339154D01*
G03X1339878Y1140338I-751J1419D01*
G01Y1142056D01*
X1339391Y1142543D01*
X1338838D01*
X1338350Y1143031D01*
Y1143584D01*
X1337863Y1144071D01*
X1337310D01*
X1336822Y1144559D01*
Y1145112D01*
X1334833Y1147101D01*
X1334601D01*
X1334540Y1147162D01*
G01X394251Y1143423D02*
Y1143336D01*
X394085Y1143170D01*
Y1140342D01*
X394086Y1140340D01*
G03X394812Y1139553I1475J633D01*
G02X395937Y1138246I-1100J-2084D01*
G01Y1137469D01*
G03X396640Y1136212I1475J0D01*
G01X396675Y1136192D01*
G02X397787Y1134337I-1113J-1928D01*
G01Y1134264D01*
G03X398490Y1133007I1475J0D01*
G01X398525Y1132987D01*
G02X399636Y1131121I-1114J-1927D01*
G01Y1131060D01*
G03X400339Y1129803I1475J0D01*
G01X400399Y1129768D01*
X400398Y1129769D01*
G02X401487Y1127856I-1136J-1913D01*
G01Y1127800D01*
G02X400374Y1125928I-2225J56D01*
G01X400339Y1125908D01*
G03Y1123394I771J-1257D01*
G01X400368Y1123377D01*
X400374Y1123374D01*
X400385Y1123368D01*
X400398Y1123360D01*
G02X401487Y1121447I-1136J-1913D01*
G03X402190Y1120190I1475J0D01*
G01X402225Y1120170D01*
G02X403336Y1118304I-1114J-1927D01*
G01Y1118243D01*
G03X404039Y1116986I1475J0D01*
G01X404099Y1116951D01*
X404098Y1116952D01*
G02X405187Y1115039I-1136J-1913D01*
G01Y1114966D01*
G02X404075Y1113111I-2225J73D01*
G01X404040Y1113091D01*
G03Y1110577I772J-1257D01*
G01X404075Y1110557D01*
G02X405187Y1108669I-1113J-1927D01*
G01Y1108591D01*
G02X404075Y1106703I-2225J39D01*
G01X404040Y1106683D01*
G03Y1104169I772J-1257D01*
G01X404075Y1104149D01*
G02X405187Y1102294I-1113J-1928D01*
G01Y1102221D01*
G02X404098Y1100308I-2225J0D01*
G01X404039Y1100274D01*
G03Y1097760I772J-1257D01*
G01X404068Y1097743D01*
X404074Y1097740D01*
X404077Y1097738D01*
X404098Y1097726D01*
G02X405187Y1095813I-1136J-1913D01*
G03X405188Y1095755I1475J-4D01*
G03X405890Y1094556I1474J58D01*
G01X405925Y1094536D01*
G03X407399I737J1277D01*
G01X407457Y1094570D01*
G02X409625Y1094536I1053J-1962D01*
G02X410736Y1092695I-1114J-1928D01*
G01Y1092608D01*
G03X411439Y1091351I1475J0D01*
G01X411468Y1091334D01*
X411474Y1091331D01*
X411477Y1091329D01*
X411498Y1091317D01*
G02X412561Y1089745I-1136J-1913D01*
G02X412572Y1089663I-2199J-337D01*
G01X412831Y1089404D01*
X414062D01*
G01X1340254Y1105426D02*
X1340870Y1106493D01*
X1340775Y1106844D01*
G02X1340708Y1106896I1330J1783D01*
G02X1339878Y1108630I1395J1733D01*
G03X1339175Y1109887I-1475J0D01*
G01X1339140Y1109907D01*
G02X1338029Y1111773I1114J1927D01*
G01Y1111921D01*
G02X1339140Y1113762I2225J-87D01*
G01X1339175Y1113782D01*
G03X1339877Y1114981I-772J1257D01*
G03X1339878Y1115039I-1474J54D01*
G01Y1115078D01*
G02X1340990Y1116966I2225J-39D01*
G01X1341025Y1116986D01*
G03X1341728Y1118217I-772J1257D01*
G03Y1118283I-1475J33D01*
G03X1341025Y1119500I-1475J-40D01*
G01X1340990Y1119520D01*
X1340966Y1119534D01*
G02X1339878Y1121447I1138J1913D01*
G03X1339175Y1122704I-1475J0D01*
G01X1339140Y1122724D01*
G02X1338028Y1124612I1113J1927D01*
G01Y1124707D01*
G02X1339141Y1126579I2225J-56D01*
G01X1339176Y1126599D01*
G03X1339879Y1127819I-772J1257D01*
G03Y1127882I-1475J31D01*
G03X1339176Y1129113I-1475J-26D01*
G01X1339141Y1129133D01*
G02X1338029Y1131021I1113J1927D01*
G01Y1131060D01*
G03X1337326Y1132317I-1475J0D01*
G01X1337291Y1132337D01*
X1337276Y1132346D01*
X1337243Y1132365D01*
G02X1336178Y1134264I1161J1899D01*
G03X1335475Y1135521I-1475J0D01*
G01X1335440Y1135541D01*
G02X1334329Y1137382I1114J1928D01*
G01Y1138102D01*
G03X1333603Y1138889I-1475J-633D01*
G02X1332397Y1140489I1100J2084D01*
G02X1332381Y1140571I2304J492D01*
G01Y1144301D01*
X1332003Y1144679D01*
X1331771D01*
X1331710Y1144740D01*
G01X392339Y1154369D02*
Y1154282D01*
X392173Y1154116D01*
Y1151787D01*
X401486Y1142474D01*
Y1140194D01*
G02X401425Y1140037I-2226J775D01*
G02X400362Y1138889I-2163J937D01*
G03X399637Y1138104I750J-1420D01*
G01Y1137469D01*
G03X400340Y1136212I1475J0D01*
G01X400372Y1136194D01*
X400375Y1136192D01*
G02X401487Y1134337I-1113J-1928D01*
G01Y1134264D01*
G03X402190Y1133007I1475J0D01*
G01X402225Y1132987D01*
G02X403336Y1131121I-1114J-1927D01*
G01Y1131060D01*
G03X404039Y1129803I1475J0D01*
G01X404122Y1129755D01*
G02X405187Y1127856I-1161J-1899D01*
G02X404074Y1125928I-2226J0D01*
G01X404039Y1125908D01*
G03Y1123394I773J-1257D01*
G01X404068Y1123377D01*
X404074Y1123374D01*
X404098Y1123360D01*
G02X405187Y1121447I-1136J-1913D01*
G01Y1121413D01*
G03X405924Y1120170I1474J34D01*
G02X407036Y1118282I-1113J-1927D01*
G01Y1118243D01*
G03X407739Y1116986I1475J0D01*
G01X407774Y1116966D01*
G02X408886Y1115078I-1113J-1927D01*
G01Y1114966D01*
G02X407774Y1113111I-2225J73D01*
G03X407037Y1111868I737J-1277D01*
G01Y1111800D01*
G03X407774Y1110557I1474J34D01*
G01X407822Y1110529D01*
G02Y1106731I-1161J-1899D01*
G01X407774Y1106703D01*
G03X407037Y1105460I737J-1277D01*
G01Y1105392D01*
G03X407774Y1104149I1474J34D01*
G02X408887Y1102251I-1113J-1928D01*
G01Y1102221D01*
G03X409590Y1100964I1475J0D01*
G01X409621Y1100946D01*
X409625Y1100944D01*
G02X410736Y1099078I-1114J-1927D01*
G01Y1099017D01*
G03X411439Y1097760I1475J0D01*
G01X411468Y1097743D01*
X411474Y1097740D01*
X411485Y1097734D01*
X411498Y1097726D01*
G02X412587Y1095813I-1136J-1913D01*
G01Y1095779D01*
G03X413324Y1094536I1474J34D01*
G02X414436Y1092681I-1113J-1928D01*
G01Y1092608D01*
G03X415139Y1091351I1475J0D01*
G01X415168Y1091334D01*
X415174Y1091331D01*
X415185Y1091325D01*
X415198Y1091317D01*
G02X416287Y1089404I-1136J-1913D01*
G01Y1089365D01*
G02X415175Y1087477I-2225J39D01*
G01X415134Y1087453D01*
G02X412948Y1087477I-1072J1951D01*
G03X411474I-737J-1277D01*
G01X411416Y1087443D01*
G02X409248Y1087477I-1054J1961D01*
G03X407774I-737J-1277D01*
G01X407716Y1087443D01*
G02X405548Y1087477I-1054J1961D01*
G03X404279Y1087575I-737J-1277D01*
G01X404196Y1087266D01*
X404811Y1086200D01*
G01X1336554Y1111834D02*
X1335938Y1112901D01*
X1336033Y1113252D01*
G03X1336099Y1113303I-1328J1787D01*
G03X1336928Y1114952I-1396J1735D01*
G01Y1115039D01*
G02X1337631Y1116296I1475J0D01*
G01X1337663Y1116314D01*
X1337666Y1116316D01*
G03X1338778Y1118204I-1113J1927D01*
G01Y1118282D01*
G03X1337666Y1120170I-2225J-39D01*
G01X1337631Y1120190D01*
G02X1336928Y1121447I772J1257D01*
G01Y1121508D01*
G03X1335817Y1123374I-2225J-61D01*
G01X1335782Y1123394D01*
G02X1335080Y1124611I773J1257D01*
G02X1335081Y1124709I1475J34D01*
G02X1335782Y1125908I1474J-57D01*
G01X1335817Y1125928D01*
G03X1336929Y1127800I-1114J1928D01*
G01Y1127856D01*
G03X1335841Y1129769I-2226J0D01*
G01X1335817Y1129783D01*
X1335782Y1129803D01*
G02X1335079Y1131060I772J1257D01*
G03X1333990Y1132973I-2225J0D01*
G01X1333969Y1132985D01*
X1333966Y1132987D01*
X1333939Y1133002D01*
X1333931Y1133007D01*
G02X1333228Y1134264I772J1257D01*
G01Y1134351D01*
G03X1332117Y1136192I-2225J-87D01*
G01X1332058Y1136226D01*
G02X1331378Y1137469I796J1243D01*
G01Y1139064D01*
X1330210Y1140232D01*
Y1142617D01*
X1329368Y1143459D01*
Y1143695D01*
X1329307Y1143756D01*
G01X394704Y1162689D02*
Y1162602D01*
X394869Y1162437D01*
Y1152013D01*
X404436Y1142446D01*
Y1140338D01*
G02X403711Y1139553I-1475J635D01*
G03X402587Y1138247I1101J-2084D01*
G01Y1137396D01*
G03X403699Y1135541I2225J73D01*
G01X403734Y1135521D01*
G02X404437Y1134264I-772J-1257D01*
G01Y1134203D01*
G03X405548Y1132337I2225J61D01*
G01X405583Y1132317D01*
G02X406286Y1131060I-772J-1257D01*
G03X407375Y1129147I2225J0D01*
G01X407396Y1129135D01*
X407399Y1129133D01*
G02X408136Y1127890I-737J-1277D01*
G01Y1127822D01*
G02X407399Y1126579I-1474J34D01*
G03X406286Y1124707I1112J-1928D01*
G01Y1124612D01*
G03X407398Y1122724I2225J39D01*
G01X407401Y1122722D01*
X407408Y1122718D01*
X407411Y1122716D01*
X407433Y1122704D01*
G02X408136Y1121447I-772J-1257D01*
G01Y1121446D01*
G03X409224Y1119534I2226J1D01*
G01X409239Y1119525D01*
X409246Y1119521D01*
X409283Y1119500D01*
G02X409986Y1118243I-772J-1257D01*
G01Y1118204D01*
G03X411098Y1116316I2225J39D01*
G01X411101Y1116314D01*
X411111Y1116308D01*
X411133Y1116296D01*
G02X411836Y1115039I-772J-1257D01*
G01Y1114983D01*
G03X412948Y1113111I2226J56D01*
G01X412983Y1113091D01*
G02X413685Y1111892I-772J-1257D01*
G02X413686Y1111794I-1474J-64D01*
G02X412983Y1110577I-1474J40D01*
G01X412948Y1110557D01*
G03X411837Y1108691I1114J-1927D01*
G01Y1108630D01*
G02X411134Y1107373I-1475J0D01*
G01X411126Y1107368D01*
X411113Y1107361D01*
X411105Y1107356D01*
X411099Y1107353D01*
X411093Y1107349D01*
X411075Y1107339D01*
G03X411099Y1103498I1136J-1913D01*
G01X411134Y1103478D01*
G02X411837Y1102221I-772J-1257D01*
G01Y1102160D01*
G03X412948Y1100294I2225J61D01*
G01X412952Y1100292D01*
X412983Y1100274D01*
G02X413686Y1099017I-772J-1257D01*
G01Y1098961D01*
G03X414798Y1097089I2226J56D01*
G01X414833Y1097069D01*
G02X415536Y1095812I-772J-1257D01*
G01X415537Y1095756D01*
G03X416648Y1093885I2226J56D01*
G01X416683Y1093865D01*
G02X417385Y1092666I-772J-1257D01*
G02X417386Y1092608I-1474J-54D01*
G01Y1092569D01*
G03X418498Y1090681I2225J39D01*
G01X418539Y1090657D01*
G03X420416Y1090533I1071J1951D01*
G03X420495Y1090565I-796J2079D01*
G01X420846Y1090471D01*
X421462Y1089404D01*
G01X1342103Y1108630D02*
X1341487Y1107563D01*
X1341179Y1107481D01*
G02X1340628Y1108630I924J1150D01*
G01Y1108691D01*
G03X1339517Y1110557I-2225J-61D01*
G01X1339482Y1110577D01*
G02X1338780Y1111794I773J1257D01*
G02X1338781Y1111892I1475J34D01*
G02X1339482Y1113091I1474J-57D01*
G01X1339513Y1113109D01*
X1339517Y1113111D01*
G03X1340628Y1114952I-1114J1928D01*
G01Y1115039D01*
G02X1341331Y1116296I1475J0D01*
G01X1341366Y1116316D01*
G03X1342478Y1118204I-1113J1927D01*
G01Y1118304D01*
G03X1341367Y1120170I-2225J-61D01*
G01X1341363Y1120172D01*
X1341332Y1120190D01*
G02X1340629Y1121447I772J1257D01*
G03X1339564Y1123346I-2226J0D01*
G01X1339516Y1123374D01*
G02X1338779Y1124617I737J1277D01*
G01Y1124685D01*
G02X1339516Y1125928I1474J-34D01*
G03X1340629Y1127800I-1112J1928D01*
G01Y1127895D01*
G03X1339517Y1129783I-2225J-39D01*
G01X1339482Y1129803D01*
G02X1338779Y1131060I772J1257D01*
G01Y1131099D01*
G03X1337667Y1132987I-2225J-39D01*
G01X1337664Y1132989D01*
X1337654Y1132995D01*
X1337632Y1133007D01*
G02X1336929Y1134264I772J1257D01*
G01Y1134320D01*
G03X1335817Y1136192I-2226J-56D01*
G01X1335782Y1136212D01*
G02X1335079Y1137469I772J1257D01*
G01Y1138246D01*
G03X1333954Y1139553I-2225J-777D01*
G02X1333132Y1140643I749J1420D01*
G01X1333131Y1140648D01*
Y1144611D01*
X1332506Y1145236D01*
Y1145472D01*
X1332474Y1145504D01*
G01X391259Y1154369D02*
Y1154282D01*
X391424Y1154117D01*
Y1151476D01*
X400737Y1142163D01*
Y1140337D01*
X400736Y1140335D01*
G02X400011Y1139553I-1474J639D01*
G03X398887Y1138247I1101J-2084D01*
G01Y1137396D01*
G03X399999Y1135541I2225J73D01*
G01X400002Y1135539D01*
X400034Y1135521D01*
G02X400737Y1134264I-772J-1257D01*
G01Y1134203D01*
G03X401848Y1132337I2225J61D01*
G01X401883Y1132317D01*
G02X402586Y1131060I-772J-1257D01*
G01Y1131021D01*
G03X403698Y1129133I2225J39D01*
G01X403701Y1129131D01*
X403711Y1129125D01*
X403733Y1129113D01*
G02Y1126599I-772J-1257D01*
G01X403701Y1126581D01*
X403698Y1126579D01*
G03X402586Y1124724I1113J-1928D01*
G01Y1124651D01*
G03X403675Y1122738I2225J0D01*
G01X403684Y1122733D01*
X403688Y1122731D01*
X403699Y1122724D01*
G02X404436Y1121481I-737J-1277D01*
G01Y1121408D01*
G03X405548Y1119520I2225J39D01*
G01X405583Y1119500D01*
G02X406286Y1118243I-772J-1257D01*
G01Y1118204D01*
G03X407398Y1116316I2225J39D01*
G01X407401Y1116314D01*
X407433Y1116296D01*
G02X408136Y1115065I-772J-1257D01*
G02X408135Y1114991I-1475J-17D01*
G02X407433Y1113782I-1475J48D01*
G01X407398Y1113762D01*
G03X406286Y1111907I1113J-1928D01*
G01Y1111795D01*
G03X407398Y1109907I2225J39D01*
G01X407433Y1109887D01*
G02Y1107373I-772J-1257D01*
G01X407398Y1107353D01*
G03X406286Y1105465I1113J-1927D01*
G01Y1105353D01*
G03X407398Y1103498I2225J73D01*
G01X407433Y1103478D01*
G02X408136Y1102221I-772J-1257D01*
G03X409224Y1100308I2226J0D01*
G01X409248Y1100294D01*
X409283Y1100274D01*
G02X409986Y1099017I-772J-1257D01*
G03X411075Y1097104I2225J0D01*
G01X411096Y1097092D01*
X411099Y1097090D01*
G02X411836Y1095847I-737J-1277D01*
G01Y1095740D01*
G03X412948Y1093885I2225J73D01*
G01X412983Y1093865D01*
G02X413686Y1092608I-772J-1257D01*
G03X414775Y1090695I2225J0D01*
G01X414796Y1090683D01*
X414799Y1090681D01*
G02X415536Y1089438I-737J-1277D01*
G01Y1089370D01*
G02X414799Y1088127I-1474J34D01*
G02X413325I-737J1277D01*
G03X411157Y1088161I-1114J-1927D01*
G01X411099Y1088127D01*
G02X409625I-737J1277D01*
G03X407457Y1088161I-1114J-1927D01*
G01X407399Y1088127D01*
G02X405925I-737J1277D01*
G03X404008Y1088276I-1114J-1927D01*
G03X403927Y1088243I799J-2077D01*
G01X403576Y1088337D01*
X402961Y1089403D01*
Y1089404D01*
G01X1334703Y1108630D02*
X1335934D01*
X1336160Y1108856D01*
G03X1335475Y1109887I-1458J-225D01*
G01X1335440Y1109907D01*
G02X1334329Y1111773I1114J1927D01*
G01Y1111834D01*
G03X1333626Y1113091I-1475J0D01*
G01X1333591Y1113111D01*
G02X1332478Y1114983I1112J1928D01*
G01Y1115039D01*
G03X1331775Y1116296I-1475J0D01*
G01X1331740Y1116316D01*
G02X1330628Y1118204I1113J1927D01*
G01Y1118243D01*
G03X1329925Y1119500I-1475J0D01*
G01X1329890Y1119520D01*
G02X1328778Y1121408I1113J1927D01*
G01Y1121447D01*
G03X1328075Y1122704I-1475J0D01*
G01X1328040Y1122724D01*
G02X1326928Y1124612I1113J1927D01*
G01Y1124707D01*
G02X1328041Y1126579I2225J-56D01*
G03X1328778Y1127822I-737J1277D01*
G01Y1127895D01*
G02X1329890Y1129783I2225J-39D01*
G01X1329925Y1129803D01*
G03Y1132317I-772J1257D01*
G01X1329922Y1132319D01*
X1329903Y1132329D01*
X1329900Y1132331D01*
X1329893Y1132335D01*
X1329890Y1132337D01*
G02X1328778Y1134225I1113J1927D01*
G01Y1134264D01*
G03X1328075Y1135521I-1475J0D01*
G01X1328040Y1135541D01*
G02X1326927Y1137413I1112J1928D01*
G01Y1138178D01*
X1325052Y1140053D01*
Y1141752D01*
X1323873Y1142931D01*
X1323641D01*
X1323580Y1142992D01*
G01X402734Y1155549D02*
Y1155462D01*
X402568Y1155296D01*
Y1151998D01*
X402948Y1151618D01*
Y1150618D01*
X402568Y1150238D01*
Y1149238D01*
X404981Y1146825D01*
X405518D01*
X406226Y1146117D01*
Y1145580D01*
X406933Y1144873D01*
X407470D01*
X408178Y1144165D01*
Y1143628D01*
X408885Y1142921D01*
Y1140198D01*
G02X407761Y1138890I-2224J774D01*
G01X407762Y1138889D01*
G03X407037Y1138104I750J-1420D01*
G01Y1137469D01*
G03X407740Y1136212I1475J0D01*
G01X407775Y1136192D01*
G02X408887Y1134337I-1113J-1928D01*
G01Y1134264D01*
G03X409590Y1133007I1475J0D01*
G01X409625Y1132987D01*
X409649Y1132973D01*
G02X410737Y1131060I-1138J-1913D01*
G03X411440Y1129803I1475J0D01*
G01X411475Y1129783D01*
X411499Y1129769D01*
G02X412587Y1127856I-1138J-1913D01*
G01Y1127826D01*
G02X411474Y1125928I-2226J30D01*
G01X411471Y1125926D01*
X411439Y1125908D01*
G03Y1123394I773J-1257D01*
G01X411468Y1123377D01*
X411474Y1123374D01*
X411485Y1123368D01*
X411498Y1123360D01*
G02X412587Y1121447I-1136J-1913D01*
G01Y1121413D01*
G03X413324Y1120170I1474J34D01*
G02X414436Y1118282I-1113J-1927D01*
G01Y1118243D01*
G03X415139Y1116986I1475J0D01*
G01X415199Y1116951D01*
X415198Y1116952D01*
G02X416287Y1115039I-1136J-1913D01*
G01Y1115005D01*
G03X417024Y1113762I1474J34D01*
G02X418136Y1111907I-1113J-1928D01*
G01Y1111773D01*
G02X417025Y1109907I-2225J61D01*
G01X416990Y1109887D01*
G03X416287Y1108630I772J-1257D01*
G02X415198Y1106717I-2225J0D01*
G01X415174Y1106703D01*
X415139Y1106683D01*
G03Y1104169I772J-1257D01*
G01X415174Y1104149D01*
G02X416287Y1102277I-1112J-1928D01*
G01Y1102221D01*
G03X416990Y1100964I1475J0D01*
G01X417025Y1100944D01*
G02X418137Y1099056I-1113J-1927D01*
G01Y1099017D01*
G03X418840Y1097760I1475J0D01*
G01X418875Y1097740D01*
G02X419987Y1095852I-1113J-1927D01*
G01Y1095813D01*
G03X419988Y1095755I1475J-4D01*
G03X420690Y1094556I1474J58D01*
G01X420725Y1094536D01*
G02X421836Y1092695I-1114J-1928D01*
G01Y1092608D01*
G03X422539Y1091351I1475J0D01*
G01X422568Y1091334D01*
X422574Y1091331D01*
G03X424048I737J1277D01*
G01X424083Y1091351D01*
G03X424786Y1092608I-772J1257D01*
G03X424785Y1092665I-1475J3D01*
G03X424235Y1093757I-1474J-58D01*
G01X423927Y1093675D01*
X423311Y1092608D01*
G01X1323603Y1121447D02*
X1322987Y1122514D01*
X1323082Y1122865D01*
G03X1323148Y1122916I-1327J1786D01*
G03X1323978Y1124612I-1395J1734D01*
G01Y1124651D01*
G02X1324681Y1125908I1475J0D01*
G01X1324716Y1125928D01*
G03X1325828Y1127783I-1113J1928D01*
G01Y1127856D01*
G02X1326531Y1129113I1475J0D01*
G01X1326566Y1129133D01*
G03X1326597Y1132969I-1113J1927D01*
G01X1326596Y1132968D01*
X1326364Y1133102D01*
G02X1325827Y1134032I537J930D01*
G01Y1134264D01*
G03X1324756Y1136166I-2224J0D01*
G01X1324711Y1136193D01*
X1324712Y1136194D01*
X1324680Y1136212D01*
G02X1323977Y1137469I772J1257D01*
G01Y1138623D01*
X1319141Y1143459D01*
Y1143695D01*
X1319080Y1143756D01*
G01X408163Y1148687D02*
X408224Y1148626D01*
X408456D01*
X409720Y1147362D01*
Y1146562D01*
X411836Y1144446D01*
Y1140338D01*
G02X411111Y1139553I-1475J635D01*
G03X409987Y1138247I1101J-2084D01*
G01Y1137396D01*
G03X411099Y1135541I2225J73D01*
G01X411134Y1135521D01*
G02X411837Y1134264I-772J-1257D01*
G01Y1134225D01*
G03X412949Y1132337I2225J39D01*
G01X412984Y1132317D01*
G02X413687Y1131060I-772J-1257D01*
G01Y1131021D01*
G03X414799Y1129133I2225J39D01*
G02X415536Y1127890I-737J-1277D01*
G01Y1127822D01*
G02X414799Y1126579I-1474J34D01*
G03X413686Y1124681I1113J-1928D01*
G01Y1124651D01*
G03X414774Y1122738I2226J0D01*
G01X414798Y1122724D01*
X414833Y1122704D01*
G02X415536Y1121447I-772J-1257D01*
G01Y1121408D01*
G03X416648Y1119520I2225J39D01*
G01X416651Y1119518D01*
X416661Y1119512D01*
X416683Y1119500D01*
G02X417386Y1118243I-772J-1257D01*
G03X418474Y1116330I2226J0D01*
G01X418498Y1116316D01*
X418533Y1116296D01*
G02X419236Y1115039I-772J-1257D01*
G01Y1114983D01*
G03X420348Y1113111I2226J56D01*
G01X420383Y1113091D01*
G02X421085Y1111892I-772J-1257D01*
G02X421086Y1111834I-1474J-54D01*
G02X420383Y1110577I-1475J0D01*
G01X420348Y1110557D01*
G03X419237Y1108691I1114J-1927D01*
G01Y1108569D01*
G03X420348Y1106703I2225J61D01*
G01X420383Y1106683D01*
G02X421086Y1105426I-772J-1257D01*
G01Y1105370D01*
G03X422199Y1103498I2225J56D01*
G02X422936Y1102255I-737J-1277D01*
G01Y1102182D01*
G03X424048Y1100294I2225J39D01*
G01X424083Y1100274D01*
G02X424786Y1099017I-772J-1257D01*
G03X425875Y1097104I2225J0D01*
G01X425896Y1097092D01*
X425899Y1097090D01*
G02X426636Y1095847I-737J-1277D01*
G01Y1095740D01*
G03X427748Y1093885I2225J73D01*
G01X427783Y1093865D01*
G02X428468Y1092834I-773J-1256D01*
G01X428242Y1092608D01*
X427011D01*
G01X1334703Y1115039D02*
X1335319Y1113972D01*
X1335627Y1113890D01*
G03X1336177Y1114982I-924J1150D01*
G03X1336178Y1115039I-1474J54D01*
G01Y1115078D01*
G02X1337290Y1116966I2225J-39D01*
G01X1337325Y1116986D01*
G03Y1119500I-772J1257D01*
G01X1337290Y1119520D01*
G02X1336178Y1121408I1113J1927D01*
G01Y1121447D01*
G03X1335475Y1122704I-1475J0D01*
G01X1335440Y1122724D01*
G02X1334329Y1124590I1114J1927D01*
G01Y1124738D01*
G02X1335440Y1126579I2225J-87D01*
G01X1335475Y1126599D01*
G03Y1129113I-771J1257D01*
G01X1335444Y1129131D01*
X1335440Y1129133D01*
G02X1334329Y1130999I1114J1927D01*
G01Y1131060D01*
G03X1333626Y1132317I-1475J0D01*
G01X1333566Y1132352D01*
X1333567Y1132351D01*
G02X1332478Y1134264I1136J1913D01*
G03X1332477Y1134322I-1475J4D01*
G03X1331775Y1135521I-1474J-58D01*
G01X1331740Y1135541D01*
G02X1330628Y1137413I1115J1929D01*
G01Y1138754D01*
X1329461Y1139921D01*
Y1142306D01*
X1328836Y1142931D01*
X1328604D01*
X1328543Y1142992D01*
G01X395784Y1162689D02*
Y1162602D01*
X395618Y1162436D01*
Y1160778D01*
X396008Y1160388D01*
Y1159688D01*
X395618Y1159298D01*
Y1158598D01*
X396008Y1158208D01*
Y1157508D01*
X395618Y1157118D01*
Y1156371D01*
X396008Y1155981D01*
Y1155281D01*
X395618Y1154891D01*
Y1152324D01*
X397607Y1150335D01*
X398145D01*
X398853Y1149627D01*
Y1149089D01*
X405185Y1142757D01*
Y1140198D01*
X405186Y1140197D01*
Y1140195D01*
G02X404062Y1138889I-2225J778D01*
G03X403337Y1138104I750J-1420D01*
G01Y1137469D01*
G03X404040Y1136212I1475J0D01*
G01X404075Y1136192D01*
G02X405187Y1134337I-1113J-1928D01*
G01Y1134264D01*
G03X405890Y1133007I1475J0D01*
G01X405925Y1132987D01*
G02X407036Y1131121I-1114J-1927D01*
G01Y1131060D01*
G03X407739Y1129803I1475J0D01*
G01X407799Y1129768D01*
X407798Y1129769D01*
G02X408887Y1127856I-1136J-1913D01*
G01Y1127800D01*
G02X407774Y1125928I-2225J56D01*
G01X407739Y1125908D01*
G03X407036Y1124688I772J-1257D01*
G03Y1124625I1475J-31D01*
G03X407739Y1123394I1475J26D01*
G01X407774Y1123374D01*
X407822Y1123346D01*
G02X408887Y1121447I-1161J-1899D01*
G03X409590Y1120190I1475J0D01*
G01X409621Y1120172D01*
X409625Y1120170D01*
G02X410736Y1118304I-1114J-1927D01*
G01Y1118243D01*
G03X411439Y1116986I1475J0D01*
G01X411522Y1116938D01*
G02X412587Y1115039I-1161J-1899D01*
G03X413290Y1113782I1475J0D01*
G01X413325Y1113762D01*
G02X414436Y1111921I-1114J-1928D01*
G01Y1111773D01*
G02X413325Y1109907I-2225J61D01*
G01X413290Y1109887D01*
G03X412587Y1108630I772J-1257D01*
G02X411498Y1106717I-2225J0D01*
G01X411477Y1106705D01*
X411471Y1106701D01*
X411467Y1106699D01*
X411439Y1106683D01*
G03Y1104169I772J-1257D01*
G01X411474Y1104149D01*
G02X412587Y1102277I-1112J-1928D01*
G01Y1102221D01*
G03X413290Y1100964I1475J0D01*
G01X413325Y1100944D01*
X413349Y1100930D01*
G02X414437Y1099017I-1138J-1913D01*
G03X415140Y1097760I1475J0D01*
G01X415175Y1097740D01*
G02X416286Y1095869I-1115J-1927D01*
G01X416287Y1095813D01*
G03X416990Y1094556I1475J0D01*
G01X417025Y1094536D01*
G02X418136Y1092695I-1114J-1928D01*
G01Y1092608D01*
G03X418839Y1091351I1475J0D01*
G01X418874Y1091331D01*
G03X420144Y1091234I736J1277D01*
G01X420227Y1091541D01*
X419611Y1092608D01*
G01X1338403Y1108630D02*
X1337172D01*
X1336914Y1108888D01*
G03X1336903Y1108971I-2212J-251D01*
G03X1335817Y1110557I-2200J-341D01*
G01X1335782Y1110577D01*
G02X1335079Y1111834I772J1257D01*
G01Y1111890D01*
G03X1333966Y1113762I-2225J-56D01*
G01X1333931Y1113782D01*
G02X1333228Y1115039I772J1257D01*
G01Y1115078D01*
G03X1332116Y1116966I-2225J-39D01*
G01X1332113Y1116968D01*
X1332081Y1116986D01*
G02X1331378Y1118243I772J1257D01*
G01Y1118282D01*
G03X1330266Y1120170I-2225J-39D01*
G01X1330231Y1120190D01*
G02X1329528Y1121447I772J1257D01*
G01Y1121486D01*
G03X1328416Y1123374I-2225J-39D01*
G01X1328381Y1123394D01*
G02X1327678Y1124625I772J1257D01*
G02Y1124688I1475J32D01*
G02X1328381Y1125908I1475J-37D01*
G01X1328416Y1125928D01*
G03X1329529Y1127800I-1112J1928D01*
G01Y1127890D01*
G02X1330266Y1129133I1474J-34D01*
G01X1330314Y1129161D01*
G03Y1132959I-1161J1899D01*
G01X1330282Y1132978D01*
X1330266Y1132987D01*
X1330231Y1133007D01*
G02X1329528Y1134264I772J1257D01*
G01Y1134320D01*
G03X1328415Y1136192I-2225J-56D01*
G01X1328380Y1136212D01*
G02X1327676Y1137424I771J1259D01*
G01Y1138489D01*
X1325801Y1140364D01*
Y1142063D01*
X1324405Y1143459D01*
Y1143695D01*
X1324344Y1143756D01*
G01X401654Y1155549D02*
Y1155462D01*
X401819Y1155297D01*
Y1148927D01*
X408136Y1142610D01*
Y1140338D01*
G02X407411Y1139553I-1475J635D01*
G03X406287Y1138247I1101J-2084D01*
G01Y1137396D01*
G03X407399Y1135541I2225J73D01*
G01X407434Y1135521D01*
G02X408137Y1134264I-772J-1257D01*
G01Y1134203D01*
G03X409248Y1132337I2225J61D01*
G01X409252Y1132335D01*
X409283Y1132317D01*
G02X409986Y1131060I-772J-1257D01*
G03X411074Y1129147I2226J0D01*
G01X411098Y1129133D01*
X411133Y1129113D01*
G02Y1126599I-772J-1257D01*
G01X411098Y1126579D01*
G03X409986Y1124724I1113J-1928D01*
G01Y1124651D01*
G03X411075Y1122738I2225J0D01*
G01X411096Y1122726D01*
X411099Y1122724D01*
G02X411836Y1121481I-737J-1277D01*
G01Y1121408D01*
G03X412948Y1119520I2225J39D01*
G01X412983Y1119500D01*
G02X413686Y1118243I-772J-1257D01*
G03X414775Y1116330I2225J0D01*
G01X414796Y1116318D01*
X414799Y1116316D01*
G02X415536Y1115073I-737J-1277D01*
G01Y1114966D01*
G03X416648Y1113111I2225J73D01*
G01X416683Y1113091D01*
G02X417385Y1111882I-772J-1257D01*
G02Y1111794I-1474J-44D01*
G02X416683Y1110577I-1475J40D01*
G01X416648Y1110557D01*
G03X415537Y1108691I1114J-1927D01*
G01Y1108630D01*
G02X414834Y1107373I-1475J0D01*
G01X414799Y1107353D01*
X414775Y1107339D01*
G03X413686Y1105426I1136J-1913D01*
G01Y1105370D01*
G03X414799Y1103498I2225J56D01*
G01X414834Y1103478D01*
G02X415537Y1102221I-772J-1257D01*
G01Y1102182D01*
G03X416649Y1100294I2225J39D01*
G01X416684Y1100274D01*
G02X417387Y1099017I-772J-1257D01*
G01Y1098978D01*
G03X418499Y1097090I2225J39D01*
G01X418534Y1097070D01*
G02X419237Y1095813I-772J-1257D01*
G01Y1095726D01*
G03X420348Y1093885I2225J87D01*
G01X420383Y1093865D01*
G02X421085Y1092666I-772J-1257D01*
G02X421086Y1092608I-1474J-54D01*
G03X422175Y1090695I2225J0D01*
G01X422259Y1090647D01*
X422257D01*
G03X424425Y1090681I1054J1961D01*
G03X425536Y1092547I-1114J1927D01*
G01Y1092695D01*
G03X424707Y1094344I-2225J-86D01*
G03X424641Y1094395I-1394J-1736D01*
G01X424546Y1094746D01*
X425162Y1095813D01*
G01X1319903Y1127856D02*
X1321134D01*
X1321360Y1127630D01*
G02X1320675Y1126599I-1458J225D01*
G01X1320640Y1126579D01*
G02X1319166I-737J1277D01*
G01X1319131Y1126599D01*
G02X1318429Y1127808I772J1257D01*
G02X1318428Y1127882I1474J57D01*
G02X1319131Y1129113I1475J-26D01*
G01X1319166Y1129133D01*
G03X1320278Y1131021I-1113J1927D01*
G01Y1131060D01*
G02X1320981Y1132317I1475J0D01*
G01X1321016Y1132337D01*
G03X1322128Y1134225I-1113J1927D01*
G01Y1134320D01*
G03X1321015Y1136192I-2225J-56D01*
G02X1320806Y1136336I730J1283D01*
G01Y1136335D01*
G02X1320748Y1136389I539J637D01*
G01Y1136388D01*
X1319818Y1137317D01*
X1318600Y1139142D01*
X1316624Y1141119D01*
Y1141656D01*
X1315916Y1142364D01*
X1315379D01*
X1314672Y1143071D01*
Y1143608D01*
X1313964Y1144316D01*
X1313427D01*
X1312720Y1145023D01*
X1311418Y1146960D01*
X1311521Y1147488D01*
X1310963Y1148318D01*
X1310434Y1148422D01*
X1309396Y1149964D01*
X1309096Y1150408D01*
X1309142Y1150638D01*
X1309094Y1150710D01*
G01X412331Y1150209D02*
Y1150122D01*
X412496Y1149957D01*
Y1147886D01*
X415536Y1144846D01*
Y1140196D01*
G03X415595Y1140043I2227J771D01*
G03X416661Y1138889I2165J931D01*
G02X417387Y1138102I-749J-1420D01*
G01Y1137469D01*
G02X416684Y1136212I-1475J0D01*
G01X416649Y1136192D01*
G03X415536Y1134320I1112J-1928D01*
G01Y1134264D01*
G03X416625Y1132351I2225J0D01*
G01X416684Y1132316D01*
Y1132317D01*
G02X417387Y1131060I-772J-1257D01*
G01Y1130999D01*
G03X418498Y1129133I2225J61D01*
G01X418533Y1129113D01*
G02X419236Y1127856I-772J-1257D01*
G01Y1127800D01*
G03X420349Y1125928I2225J56D01*
G02X421086Y1124685I-737J-1277D01*
G01Y1124612D01*
G03X422198Y1122724I2225J39D01*
G01X422233Y1122704D01*
G02X422936Y1121447I-772J-1257D01*
G03X424024Y1119534I2226J0D01*
G01X424048Y1119520D01*
X424083Y1119500D01*
G02X424786Y1118243I-772J-1257D01*
G03X425851Y1116344I2226J0D01*
G01X425899Y1116316D01*
G02X426636Y1115073I-737J-1277D01*
G01Y1114983D01*
G03X427749Y1113111I2225J56D01*
G02X428486Y1111868I-737J-1277D01*
G01Y1111800D01*
G02X427749Y1110557I-1474J34D01*
G01X427738Y1110550D01*
X427734Y1110548D01*
X427725Y1110543D01*
G03Y1106717I1137J-1913D01*
G01X427749Y1106703D01*
G02X428486Y1105460I-737J-1277D01*
G01Y1105353D01*
G03X429598Y1103498I2225J73D01*
G01X429633Y1103478D01*
G02X430336Y1102221I-772J-1257D01*
G01Y1102182D01*
G03X431448Y1100294I2225J39D01*
G01X431451Y1100292D01*
X431461Y1100286D01*
X431483Y1100274D01*
G02Y1097760I-772J-1257D01*
G01X431480Y1097758D01*
X431461Y1097748D01*
X431458Y1097746D01*
X431451Y1097742D01*
X431448Y1097740D01*
G03X430336Y1095852I1113J-1927D01*
G01Y1095740D01*
G03X431448Y1093885I2225J73D01*
G01X431451Y1093883D01*
X431483Y1093865D01*
G02X432185Y1092656I-772J-1257D01*
G02X432186Y1092582I-1474J-57D01*
G02X431483Y1091351I-1475J26D01*
G01X431448Y1091331D01*
G02X429974I-737J1277D01*
G03X427748I-1113J-1927D01*
G03X426636Y1089443I1113J-1927D01*
G01Y1089370D01*
G02X425899Y1088127I-1474J34D01*
G02X424425I-737J1277D01*
G03X422257Y1088161I-1114J-1927D01*
G01X422175Y1088113D01*
G03X421112Y1086541I1136J-1913D01*
G03X421101Y1086459I2199J-337D01*
G01X420842Y1086200D01*
X419611D01*
G01X1321753Y1124651D02*
X1322369Y1123584D01*
X1322677Y1123502D01*
G03X1323228Y1124651I-924J1150D01*
G01Y1124724D01*
G02X1324340Y1126579I2225J-73D01*
G01X1324375Y1126599D01*
G03X1325078Y1127856I-772J1257D01*
G01Y1127895D01*
G02X1326190Y1129783I2225J-39D01*
G01X1326225Y1129803D01*
G03Y1132317I-772J1257D01*
G01X1326222Y1132319D01*
X1325989Y1132453D01*
G02X1325078Y1134032I913J1579D01*
G01Y1134264D01*
G03X1324375Y1135521I-1475J0D01*
G01X1324340Y1135541D01*
G02X1323227Y1137413I1112J1928D01*
G01Y1138313D01*
X1321302Y1140238D01*
X1320764D01*
X1320056Y1140946D01*
Y1141484D01*
X1318609Y1142931D01*
X1318377D01*
X1318316Y1142992D01*
G01X408927Y1149451D02*
X408988Y1149390D01*
Y1149154D01*
X410469Y1147673D01*
Y1146873D01*
X412585Y1144757D01*
Y1140198D01*
G02X411461Y1138890I-2224J774D01*
G01X411462Y1138889D01*
G03X410737Y1138104I750J-1420D01*
G01Y1137469D01*
G03X411440Y1136212I1475J0D01*
G01X411475Y1136192D01*
G02X412587Y1134337I-1113J-1928D01*
G01Y1134264D01*
G03X413290Y1133007I1475J0D01*
G01X413325Y1132987D01*
G02X414437Y1131099I-1113J-1927D01*
G01Y1131060D01*
G03X415140Y1129803I1475J0D01*
G01X415175Y1129783D01*
G02X416287Y1127895I-1113J-1927D01*
G01Y1127783D01*
G02X415175Y1125928I-2225J73D01*
G01X415140Y1125908D01*
G03X414437Y1124651I772J-1257D01*
G03X415140Y1123394I1475J0D01*
G01X415171Y1123376D01*
X415175Y1123374D01*
G02X416286Y1121508I-1114J-1927D01*
G01Y1121447D01*
G03X416989Y1120190I1475J0D01*
G01X417024Y1120170D01*
X417039Y1120161D01*
X417072Y1120142D01*
G02X418137Y1118243I-1161J-1899D01*
G03X418840Y1116986I1475J0D01*
G01X418875Y1116966D01*
X418899Y1116952D01*
G02X419987Y1115039I-1138J-1913D01*
G03X420690Y1113782I1475J0D01*
G01X420725Y1113762D01*
G02X421836Y1111921I-1114J-1928D01*
G01Y1111773D01*
G02X420725Y1109907I-2225J61D01*
G01X420690Y1109887D01*
G03Y1107373I773J-1257D01*
G01X420725Y1107353D01*
G02X421836Y1105487I-1114J-1927D01*
G01Y1105426D01*
G03X422539Y1104169I1475J0D01*
G01X422574Y1104149D01*
G02X423687Y1102277I-1112J-1928D01*
G01Y1102187D01*
G03X424424Y1100944I1474J34D01*
G02X425536Y1099056I-1113J-1927D01*
G01Y1099017D01*
G03X426239Y1097760I1475J0D01*
G01X426299Y1097725D01*
X426298Y1097726D01*
G02X427387Y1095813I-1136J-1913D01*
G01Y1095779D01*
G03X428124Y1094536I1474J34D01*
G02X429212Y1092950I-1112J-1929D01*
G02X429223Y1092865I-2202J-328D01*
G01X429480Y1092608D01*
X430711D01*
G01X1323603Y1127856D02*
X1322372D01*
X1322115Y1127599D01*
G02X1322104Y1127514I-2213J243D01*
G02X1321016Y1125928I-2200J343D01*
G02X1318790I-1113J1928D01*
G02X1317678Y1127783I1113J1928D01*
G01Y1127895D01*
G02X1318790Y1129783I2225J-39D01*
G01X1318825Y1129803D01*
G03X1319528Y1131060I-772J1257D01*
G01Y1131099D01*
G02X1320640Y1132987I2225J-39D01*
G01X1320675Y1133007D01*
G03X1321378Y1134238I-772J1257D01*
G03Y1134301I-1475J32D01*
G03X1320675Y1135521I-1475J-37D01*
G01X1320640Y1135541D01*
G02X1320328Y1135758I1110J1929D01*
G02X1320218Y1135858I1009J1221D01*
G01X1319236Y1136839D01*
X1318017Y1138664D01*
X1312138Y1144544D01*
X1308775Y1149545D01*
X1308475Y1149990D01*
X1308246Y1150033D01*
X1308198Y1150105D01*
G01X413411Y1150209D02*
Y1150122D01*
X413245Y1149956D01*
Y1148197D01*
X416285Y1145157D01*
Y1140342D01*
X416286Y1140340D01*
G03X417012Y1139553I1475J633D01*
G02X418137Y1138246I-1100J-2084D01*
G01Y1137413D01*
G02X417024Y1135541I-2225J56D01*
G03X416287Y1134298I737J-1277D01*
G01Y1134230D01*
G03X417024Y1132987I1474J34D01*
G01X417027Y1132985D01*
X417048Y1132973D01*
G02X418137Y1131060I-1136J-1913D01*
G03X418840Y1129803I1475J0D01*
G01X418875Y1129783D01*
G02X419986Y1127917I-1114J-1927D01*
G01Y1127856D01*
G03X420689Y1126599I1475J0D01*
G01X420724Y1126579D01*
G02X421837Y1124707I-1112J-1928D01*
G01Y1124617D01*
G03X422574Y1123374I1474J34D01*
G01X422622Y1123346D01*
G02X423687Y1121447I-1161J-1899D01*
G03X424390Y1120190I1475J0D01*
G01X424425Y1120170D01*
X424449Y1120156D01*
G02X425537Y1118243I-1138J-1913D01*
G03X426240Y1116986I1475J0D01*
G01X426275Y1116966D01*
G02X427387Y1115078I-1113J-1927D01*
G01Y1115005D01*
G03X428124Y1113762I1474J34D01*
G02X429237Y1111890I-1112J-1928D01*
G01Y1111834D01*
G02X428148Y1109921I-2225J0D01*
G01X428124Y1109907D01*
G03X427387Y1108664I737J-1277D01*
G01Y1108596D01*
G03X428124Y1107353I1474J34D01*
G01X428148Y1107339D01*
G02X429237Y1105426I-1136J-1913D01*
G01Y1105392D01*
G03X429974Y1104149I1474J34D01*
G02X431086Y1102294I-1113J-1928D01*
G01Y1102221D01*
G03X431789Y1100964I1475J0D01*
G01X431824Y1100944D01*
X431839Y1100935D01*
X431872Y1100916D01*
G02Y1097118I-1161J-1899D01*
G01X431840Y1097099D01*
X431824Y1097090D01*
X431789Y1097070D01*
G03X431086Y1095839I772J-1257D01*
G03X431087Y1095765I1475J-17D01*
G03X431789Y1094556I1475J48D01*
G01X431824Y1094536D01*
G02X432936Y1092681I-1113J-1928D01*
G01Y1092569D01*
G02X431824Y1090681I-2225J39D01*
G02X429598I-1113J1927D01*
G03X428124I-737J-1277D01*
G03X427387Y1089438I737J-1277D01*
G01Y1089404D01*
G02X426298Y1087491I-2225J0D01*
G01X426274Y1087477D01*
X426216Y1087443D01*
G02X424048Y1087477I-1054J1961D01*
G03X422574I-737J-1277D01*
G01X422568Y1087474D01*
X422539Y1087457D01*
G03X421854Y1086426I773J-1256D01*
G01X422080Y1086200D01*
X423311D01*
G01X1316203Y1127856D02*
X1316819Y1128923D01*
X1316724Y1129274D01*
X1316725Y1129275D01*
G02X1316658Y1129327I1330J1783D01*
G02X1315829Y1131059I1395J1732D01*
G01Y1133782D01*
X1314720Y1135515D01*
Y1135897D01*
X1314555Y1136062D01*
Y1136149D01*
G01X416680Y1150477D02*
Y1150390D01*
X416514Y1150224D01*
Y1149498D01*
X423685Y1142327D01*
Y1140198D01*
X423686Y1140197D01*
Y1140195D01*
G02X422562Y1138889I-2225J778D01*
G03X421837Y1138104I750J-1420D01*
G01Y1137413D01*
G02X420724Y1135541I-2225J56D01*
G01X420689Y1135521D01*
G03Y1133007I771J-1257D01*
G01X420749Y1132972D01*
X420748Y1132973D01*
G02X421837Y1131060I-1136J-1913D01*
G01Y1131026D01*
G03X422574Y1129783I1474J34D01*
G01X422622Y1129755D01*
G02X423687Y1127856I-1161J-1899D01*
G03X424390Y1126599I1475J0D01*
G01X424425Y1126579D01*
G02X425537Y1124707I-1114J-1928D01*
G01Y1124651D01*
G03X426240Y1123394I1475J0D01*
G01X426275Y1123374D01*
G02X427387Y1121486I-1113J-1927D01*
G01Y1121413D01*
G03X428124Y1120170I1474J34D01*
G01X428148Y1120156D01*
G02X429237Y1118243I-1136J-1913D01*
G01Y1118209D01*
G03X429974Y1116966I1474J34D01*
G02X431086Y1115078I-1113J-1927D01*
G01Y1115039D01*
G03X431789Y1113782I1475J0D01*
G01X431824Y1113762D01*
G02X432936Y1111907I-1113J-1928D01*
G01Y1111795D01*
G02X431824Y1109907I-2225J39D01*
G01X431789Y1109887D01*
G03Y1107373I772J-1257D01*
G01X431824Y1107353D01*
G02X432936Y1105465I-1113J-1927D01*
G01Y1105426D01*
G03X433639Y1104169I1475J0D01*
G01X433674Y1104149D01*
G02X434787Y1102251I-1113J-1928D01*
G01Y1102221D01*
G03X435490Y1100964I1475J0D01*
G01X435512Y1100952D01*
X435522Y1100946D01*
X435525Y1100944D01*
G02X436637Y1099018I-1112J-1926D01*
G01Y1099017D01*
G02X435548Y1097104I-2225J0D01*
G01X435527Y1097092D01*
X435524Y1097090D01*
X435518Y1097087D01*
X435489Y1097070D01*
G03X434786Y1095813I772J-1257D01*
G01X434785D01*
Y1095754D01*
G03X435519Y1094536I1476J59D01*
G01X435554Y1094516D01*
X435574Y1094504D01*
G02X435564Y1090706I-1163J-1896D01*
G01X435507Y1090672D01*
X435490Y1090661D01*
G03X434787Y1089404I772J-1257D01*
G02X433722Y1087505I-2226J0D01*
G01X433689Y1087486D01*
X433674Y1087477D01*
X433633Y1087453D01*
G02X431447Y1087477I-1072J1951D01*
G03X430177Y1087574I-736J-1277D01*
G01X430094Y1087267D01*
X430710Y1086200D01*
G01X1318054Y1118243D02*
X1318670Y1119310D01*
X1318575Y1119661D01*
G02X1318508Y1119713I1330J1783D01*
G02X1317678Y1121447I1395J1733D01*
G03X1316975Y1122704I-1475J0D01*
G01X1316940Y1122724D01*
G02X1315828Y1124612I1113J1927D01*
G01Y1124651D01*
G03X1315125Y1125908I-1475J0D01*
G01X1315090Y1125928D01*
G02X1313978Y1127783I1113J1928D01*
G01Y1127889D01*
X1313979Y1127887D01*
G03X1313277Y1129113I-1476J-31D01*
G01X1313270Y1129117D01*
X1313258Y1129123D01*
X1313237Y1129135D01*
G02X1312148Y1129972I2661J4588D01*
G01X1310916Y1131204D01*
Y1135407D01*
X1310751Y1135572D01*
Y1135659D01*
G01X427551Y1143029D02*
Y1142942D01*
X427386Y1142777D01*
Y1140341D01*
G02X426266Y1138941I-2225J632D01*
G03X425524Y1138041I747J-1371D01*
G01X425537Y1137530D01*
X425539Y1137489D01*
G02X424497Y1135585I-2226J-19D01*
G02X424425Y1135541I-1197J1877D01*
G01X424422Y1135539D01*
X424390Y1135521D01*
G03Y1133007I772J-1257D01*
G01X424425Y1132987D01*
X424449Y1132973D01*
G02X425537Y1131060I-1138J-1913D01*
G03X426240Y1129803I1475J0D01*
G01X426275Y1129783D01*
G02X427387Y1127895I-1113J-1927D01*
G01Y1127822D01*
G03X428124Y1126579I1474J34D01*
G02X429237Y1124707I-1112J-1928D01*
G01Y1124617D01*
G03X429974Y1123374I1474J34D01*
G02X431086Y1121486I-1113J-1927D01*
G01Y1121447D01*
G03X431789Y1120190I1475J0D01*
G01X431824Y1120170D01*
G02X432936Y1118282I-1113J-1927D01*
G01Y1118243D01*
G03X433639Y1116986I1475J0D01*
G01X433674Y1116966D01*
X433722Y1116938D01*
G02X434787Y1115039I-1161J-1899D01*
G03X435490Y1113782I1475J0D01*
G01X435525Y1113762D01*
G02X436637Y1111890I-1114J-1928D01*
G01Y1111834D01*
G02X435549Y1109921I-2226J0D01*
G01X435525Y1109907D01*
X435490Y1109887D01*
G03Y1107373I772J-1257D01*
G01X435525Y1107353D01*
X435549Y1107339D01*
G02X436637Y1105426I-1138J-1913D01*
G03X437340Y1104169I1475J0D01*
G01X437375Y1104149D01*
G02X438487Y1102294I-1113J-1928D01*
G01Y1102187D01*
G03X439224Y1100944I1474J34D01*
G01X439227Y1100942D01*
X439238Y1100936D01*
X439248Y1100930D01*
G02Y1097104I-1136J-1913D01*
G01X439227Y1097092D01*
X439224Y1097090D01*
X439218Y1097087D01*
X439189Y1097070D01*
G03Y1094556I772J-1257D01*
G01X439224Y1094536D01*
G02X440337Y1092664I-1112J-1928D01*
G01Y1092608D01*
G02X439248Y1090695I-2225J0D01*
G01X439227Y1090683D01*
X439224Y1090681D01*
G03X438487Y1089438I737J-1277D01*
G01Y1089365D01*
G02X437375Y1087477I-2225J39D01*
G01X437340Y1087457D01*
G03X436637Y1086200I772J-1257D01*
G01Y1086144D01*
G02X435525Y1084272I-2226J56D01*
G02X433339Y1084248I-1114J1928D01*
G01X433298Y1084272D01*
G03X431824I-737J-1277D01*
G02X429656Y1084238I-1115J1928D01*
G01X429598Y1084272D01*
G03X428124I-737J-1277D01*
G01X428083Y1084248D01*
G02X426206Y1084124I-1071J1950D01*
G02X426129Y1084156I815J2071D01*
G01X425778Y1084062D01*
X425162Y1082995D01*
G01X1312503Y1121447D02*
X1313734D01*
X1313960Y1121673D01*
X1313961D01*
G03X1312504Y1122922I-1458J-226D01*
G01X1311488Y1123343D01*
X1307830Y1127001D01*
Y1130377D01*
X1307665Y1130542D01*
Y1130629D01*
G01X430520Y1148222D02*
Y1148182D01*
X430354Y1148016D01*
Y1146688D01*
X431085Y1145957D01*
Y1141071D01*
G02X430066Y1139100I-2224J-99D01*
G02X430055Y1139093I-1201J1876D01*
G01X430049Y1139090D01*
X429897Y1139002D01*
G03X429236Y1137690I814J-1233D01*
G01X429260Y1137257D01*
G02X428120Y1135589I-2248J313D01*
G03X427387Y1134627I741J-1325D01*
G01Y1134230D01*
G03X428124Y1132987I1474J34D01*
G01X428148Y1132973D01*
G02X429237Y1131060I-1136J-1913D01*
G01Y1131026D01*
G03X429974Y1129783I1474J34D01*
G02X431086Y1127895I-1113J-1927D01*
G01Y1127856D01*
G03X431789Y1126599I1475J0D01*
G01X431824Y1126579D01*
G02X432936Y1124724I-1113J-1928D01*
G01Y1124651D01*
G03X433639Y1123394I1475J0D01*
G01X433674Y1123374D01*
X433689Y1123365D01*
X433722Y1123346D01*
G02X434787Y1121447I-1161J-1899D01*
G03X435490Y1120190I1475J0D01*
G01X435525Y1120170D01*
X435549Y1120156D01*
G02X436637Y1118243I-1138J-1913D01*
G03X437340Y1116986I1475J0D01*
G01X437343Y1116984D01*
X437362Y1116974D01*
X437365Y1116972D01*
X437372Y1116968D01*
X437375Y1116966D01*
G02X438487Y1115078I-1113J-1927D01*
G01Y1115005D01*
G03X439224Y1113762I1474J34D01*
G02X440337Y1111890I-1112J-1928D01*
G01Y1111834D01*
G02X439248Y1109921I-2225J0D01*
G01X439227Y1109909D01*
X439224Y1109907D01*
G03X438487Y1108664I737J-1277D01*
G01Y1108596D01*
G03X439224Y1107353I1474J34D01*
G01X439227Y1107351D01*
X439248Y1107339D01*
G02X440337Y1105426I-1136J-1913D01*
G03X440338Y1105368I1475J-4D01*
G03X441040Y1104169I1474J58D01*
G01X441075Y1104149D01*
G02X442186Y1102308I-1114J-1928D01*
G01Y1102221D01*
G03X442889Y1100964I1475J0D01*
G01X442948Y1100929D01*
Y1100930D01*
G02Y1097104I-1137J-1913D01*
G01X442889Y1097070D01*
G03Y1094556I772J-1257D01*
G01X442924Y1094536D01*
G02X444037Y1092664I-1112J-1928D01*
G01Y1092608D01*
G02X442948Y1090695I-2225J0D01*
G01X442889Y1090660D01*
Y1090661D01*
G03X442186Y1089404I772J-1257D01*
G01Y1089343D01*
G02X441075Y1087477I-2225J61D01*
G01X441040Y1087457D01*
G03X440337Y1086200I772J-1257D01*
G01Y1086144D01*
G02X439224Y1084272I-2225J56D01*
G03X438487Y1083029I737J-1277D01*
G01Y1082956D01*
G02X437375Y1081068I-2225J39D01*
G01X437334Y1081044D01*
G02X435148Y1081068I-1072J1951D01*
G03X433674I-737J-1277D01*
G02X431448I-1113J1927D01*
G03X429974I-737J-1277D01*
G02X427790Y1081044I-1113J1927D01*
G01X427749Y1081068D01*
G03X426275I-737J-1277D01*
G01X426234Y1081044D01*
G02X424048Y1081068I-1072J1951D01*
G02X422937Y1082934I1114J1927D01*
G01Y1082995D01*
G03X422234Y1084252I-1475J0D01*
G01X422199Y1084272D01*
G03X420725I-737J-1277D01*
G02X418539Y1084248I-1114J1928D01*
G01X418498Y1084272D01*
G03X417024I-737J-1277D01*
G01X416983Y1084248D01*
G02X414799Y1084272I-1071J1952D01*
G03X413529Y1084369I-736J-1277D01*
G01X413446Y1084062D01*
X414062Y1082995D01*
G01X1318053Y1131060D02*
X1317437Y1129993D01*
X1317129Y1129911D01*
G02X1316578Y1131060I924J1150D01*
G01Y1131765D01*
X1316968Y1132155D01*
Y1132845D01*
X1316578Y1133235D01*
Y1134002D01*
X1315469Y1135735D01*
Y1135896D01*
X1315635Y1136062D01*
Y1136149D01*
G01X415600Y1150477D02*
Y1150390D01*
X415765Y1150225D01*
Y1149187D01*
X416368Y1148584D01*
Y1148031D01*
X416863Y1147536D01*
X417416D01*
X417910Y1147042D01*
Y1146489D01*
X418405Y1145994D01*
X418958D01*
X419452Y1145500D01*
Y1144947D01*
X419947Y1144452D01*
X420500D01*
X420994Y1143958D01*
Y1143406D01*
X421489Y1142911D01*
X422041D01*
X422936Y1142016D01*
Y1140338D01*
G02X422211Y1139553I-1475J635D01*
G03X421087Y1138247I1101J-2084D01*
G01Y1137469D01*
G02X420384Y1136212I-1475J0D01*
G01X420349Y1136192D01*
G03X419236Y1134320I1112J-1928D01*
G01Y1134264D01*
G03X420325Y1132351I2225J0D01*
G01X420346Y1132339D01*
X420349Y1132337D01*
G02X421086Y1131094I-737J-1277D01*
G01Y1131021D01*
G03X422198Y1129133I2225J39D01*
G01X422233Y1129113D01*
G02X422936Y1127856I-772J-1257D01*
G01Y1127800D01*
G03X424048Y1125928I2226J56D01*
G01X424083Y1125908D01*
G02X424786Y1124651I-772J-1257D01*
G03X425851Y1122752I2226J0D01*
G01X425899Y1122724D01*
G02X426636Y1121481I-737J-1277D01*
G01Y1121447D01*
G03X427725Y1119534I2225J0D01*
G01X427749Y1119520D01*
G02X428486Y1118277I-737J-1277D01*
G01Y1118204D01*
G03X429598Y1116316I2225J39D01*
G01X429633Y1116296D01*
G02X430336Y1115039I-772J-1257D01*
G01Y1114966D01*
G03X431448Y1113111I2225J73D01*
G01X431483Y1113091D01*
G02X432185Y1111882I-772J-1257D01*
G02X432186Y1111808I-1474J-57D01*
G02X431483Y1110577I-1475J26D01*
G01X431448Y1110557D01*
G03X430336Y1108669I1113J-1927D01*
G01Y1108591D01*
G03X431448Y1106703I2225J39D01*
G01X431483Y1106683D01*
G02X432186Y1105426I-772J-1257D01*
G01Y1105353D01*
G03X433298Y1103498I2225J73D01*
G01X433333Y1103478D01*
G02X434036Y1102221I-772J-1257D01*
G03X435101Y1100322I2226J0D01*
G01X435134Y1100303D01*
X435149Y1100294D01*
X435184Y1100274D01*
G02X435887Y1099017I-772J-1257D01*
G02X435184Y1097760I-1475J0D01*
G01X435155Y1097743D01*
X435149Y1097740D01*
X435138Y1097734D01*
X435125Y1097726D01*
G03X434036Y1095813I1136J-1913D01*
G01Y1095740D01*
G03X435148Y1093885I2225J73D01*
G01X435183Y1093865D01*
G02Y1091351I-772J-1257D01*
G01X435132Y1091322D01*
X435124Y1091317D01*
G03X434036Y1089404I1138J-1913D01*
G02X433333Y1088147I-1475J0D01*
G01X433311Y1088135D01*
X433301Y1088129D01*
X433298Y1088127D01*
G02X431824I-737J1277D01*
G03X429905Y1088276I-1115J-1927D01*
G03X429827Y1088244I806J-2075D01*
G01X429477Y1088337D01*
X428861Y1089404D01*
G01X1319903Y1121447D02*
X1319287Y1120380D01*
X1318979Y1120298D01*
G02X1318428Y1121447I924J1150D01*
G01Y1121486D01*
G03X1317316Y1123374I-2225J-39D01*
G01X1317281Y1123394D01*
G02X1316578Y1124651I772J1257D01*
G01Y1124724D01*
G03X1315466Y1126579I-2225J-73D01*
G01X1315431Y1126599D01*
G02X1314728Y1127856I772J1257D01*
G01Y1127895D01*
G03X1313647Y1129765I-2225J-39D01*
G01X1313613Y1129783D01*
G02X1312678Y1130502I2286J3940D01*
G01X1311665Y1131515D01*
Y1132205D01*
X1312055Y1132595D01*
Y1133285D01*
X1311665Y1133675D01*
Y1135406D01*
X1311831Y1135572D01*
Y1135659D01*
G01X426471Y1143029D02*
Y1142942D01*
X426636Y1142777D01*
Y1140460D01*
G02X425907Y1139601I-1475J513D01*
G03X424769Y1138137I1104J-2033D01*
G01X424787Y1137508D01*
G02X424098Y1136220I-1475J-39D01*
G01X424049Y1136192D01*
G03X422936Y1134294I1113J-1928D01*
G01Y1134264D01*
G03X424024Y1132351I2226J0D01*
G01X424048Y1132337D01*
X424083Y1132317D01*
G02X424786Y1131060I-772J-1257D01*
G03X425851Y1129161I2226J0D01*
G01X425899Y1129133D01*
G02X426636Y1127890I-737J-1277D01*
G01Y1127800D01*
G03X427749Y1125928I2225J56D01*
G02X428486Y1124685I-737J-1277D01*
G01Y1124612D01*
G03X429598Y1122724I2225J39D01*
G01X429633Y1122704D01*
G02X430336Y1121447I-772J-1257D01*
G01Y1121408D01*
G03X431448Y1119520I2225J39D01*
G01X431483Y1119500D01*
G02X432186Y1118243I-772J-1257D01*
G01Y1118204D01*
G03X433298Y1116316I2225J39D01*
G01X433301Y1116314D01*
X433308Y1116310D01*
X433311Y1116308D01*
X433333Y1116296D01*
G02X434036Y1115039I-772J-1257D01*
G01Y1114983D01*
G03X435148Y1113111I2226J56D01*
G01X435183Y1113091D01*
G02Y1110577I-771J-1257D01*
G01X435148Y1110557D01*
X435124Y1110543D01*
G03Y1106717I1138J-1913D01*
G01X435148Y1106703D01*
X435183Y1106683D01*
G02X435886Y1105426I-772J-1257D01*
G01Y1105396D01*
G03X436999Y1103498I2226J30D01*
G02X437736Y1102255I-737J-1277D01*
G01Y1102221D01*
G03X438825Y1100308I2225J0D01*
G01X438844Y1100297D01*
X438853Y1100291D01*
X438861Y1100286D01*
X438871Y1100281D01*
X438884Y1100273D01*
Y1100274D01*
G02X439587Y1099017I-772J-1257D01*
G02X438884Y1097760I-1475J0D01*
G01X438869Y1097751D01*
X438855Y1097743D01*
X438849Y1097740D01*
X438838Y1097734D01*
X438825Y1097726D01*
G03X437736Y1095813I1136J-1913D01*
G01Y1095757D01*
G03X438849Y1093885I2225J56D01*
G01X438884Y1093865D01*
G02Y1091351I-771J-1257D01*
G01X438824Y1091316D01*
X438825Y1091317D01*
G03X437736Y1089404I1136J-1913D01*
G01Y1089370D01*
G02X436999Y1088127I-1474J34D01*
G01X436951Y1088099D01*
G03X435886Y1086200I1161J-1899D01*
G02X435183Y1084943I-1475J0D01*
G01X435148Y1084923D01*
G02X433674I-737J1277D01*
G01X433633Y1084947D01*
G03X431447Y1084923I-1072J-1952D01*
G02X429973I-737J1277D01*
G03X427749I-1112J-1928D01*
G02X426479Y1084826I-736J1277D01*
G01X426396Y1085133D01*
X427012Y1086200D01*
G01X1316203Y1121447D02*
X1314972D01*
X1314714Y1121705D01*
G03X1314703Y1121788I-2211J-251D01*
G01X1314702Y1121789D01*
G03X1312668Y1123666I-2199J-342D01*
G01X1311913Y1123979D01*
X1308579Y1127312D01*
Y1130376D01*
X1308745Y1130542D01*
Y1130629D01*
G01X429440Y1148222D02*
Y1148182D01*
X429605Y1148017D01*
Y1146377D01*
X430336Y1145646D01*
Y1141052D01*
G02X429675Y1139740I-1475J-79D01*
G01X429598Y1139696D01*
X429517Y1139649D01*
G03X428487Y1137648I1194J-1880D01*
G01X428505Y1137299D01*
G02X427753Y1136244I-1494J269D01*
G03X426636Y1134709I1108J-1980D01*
G01Y1134264D01*
G03X427725Y1132351I2225J0D01*
G01X427749Y1132337D01*
G02X428486Y1131094I-737J-1277D01*
G01Y1131021D01*
G03X429598Y1129133I2225J39D01*
G01X429633Y1129113D01*
G02X430336Y1127856I-772J-1257D01*
G01Y1127783D01*
G03X431448Y1125928I2225J73D01*
G01X431483Y1125908D01*
G02X432186Y1124651I-772J-1257D01*
G01Y1124612D01*
G03X433298Y1122724I2225J39D01*
G01X433301Y1122722D01*
X433311Y1122716D01*
X433333Y1122704D01*
G02X434036Y1121447I-772J-1257D01*
G03X435124Y1119534I2226J0D01*
G01X435148Y1119520D01*
X435183Y1119500D01*
G02X435886Y1118243I-772J-1257D01*
G03X436951Y1116344I2226J0D01*
G01X436983Y1116325D01*
X436999Y1116316D01*
G02X437736Y1115073I-737J-1277D01*
G01Y1114983D01*
G03X438849Y1113111I2225J56D01*
G01X438884Y1113091D01*
G02Y1110577I-771J-1257D01*
G01X438855Y1110560D01*
X438849Y1110557D01*
X438838Y1110551D01*
X438825Y1110543D01*
G03Y1106717I1137J-1913D01*
G01X438884Y1106682D01*
Y1106683D01*
G02X439587Y1105426I-772J-1257D01*
G01Y1105339D01*
G03X440698Y1103498I2225J87D01*
G01X440733Y1103478D01*
G02X441435Y1102279I-772J-1257D01*
G02X441436Y1102221I-1474J-54D01*
G03X442525Y1100308I2225J0D01*
G01X442546Y1100296D01*
X442549Y1100294D01*
G02X443286Y1099051I-737J-1277D01*
G01Y1098983D01*
G02X442549Y1097740I-1474J34D01*
G01X442546Y1097738D01*
X442525Y1097726D01*
G03X441436Y1095813I1136J-1913D01*
G01Y1095757D01*
G03X442549Y1093885I2225J56D01*
G02X443286Y1092642I-737J-1277D01*
G01Y1092574D01*
G02X442549Y1091331I-1474J34D01*
G01X442546Y1091329D01*
X442525Y1091317D01*
G03X441436Y1089404I1136J-1913D01*
G02X440733Y1088147I-1475J0D01*
G01X440698Y1088127D01*
G03X439587Y1086261I1114J-1927D01*
G01Y1086200D01*
G02X438884Y1084943I-1475J0D01*
G01X438849Y1084923D01*
G03X437736Y1083051I1112J-1928D01*
G01Y1082961D01*
G02X436999Y1081718I-1474J34D01*
G02X435525I-737J1277D01*
G03X433339Y1081742I-1114J-1927D01*
G01X433298Y1081718D01*
G02X431824I-737J1277D01*
G03X429598I-1113J-1927D01*
G02X428124I-737J1277D01*
G01X428083Y1081742D01*
G03X425899Y1081718I-1071J-1951D01*
G02X424425I-737J1277D01*
G01X424390Y1081738D01*
G02X423687Y1082995I772J1257D01*
G01Y1083051D01*
G03X422574Y1084923I-2225J-56D01*
G01X422516Y1084957D01*
G03X420348Y1084923I-1053J-1962D01*
G02X418874I-737J1277D01*
G03X416690Y1084947I-1113J-1928D01*
G01X416649Y1084923D01*
G02X415175I-737J1277D01*
G01X415134Y1084947D01*
G03X413257Y1085071I-1072J-1952D01*
G03X413178Y1085039I796J-2079D01*
G01X412827Y1085133D01*
X412211Y1086200D01*
G01X348878Y848176D02*
X349494Y849243D01*
X349802Y849325D01*
G02X350353Y848176I-924J-1150D01*
G02X349650Y846919I-1475J0D01*
G01X349615Y846899D01*
G03X348502Y845027I1112J-1928D01*
G01X348504Y845030D01*
Y842331D01*
X349945Y840890D01*
Y840773D01*
X349929Y840757D01*
Y839610D01*
X349538Y839219D01*
Y838169D01*
X349929Y837778D01*
Y836728D01*
X349538Y836337D01*
Y835287D01*
X349929Y834896D01*
Y833107D01*
X349764Y832942D01*
Y832855D01*
G01X350727Y851380D02*
X350111Y850313D01*
X350206Y849962D01*
G02X350273Y849910I-1330J-1783D01*
G02X351103Y848176I-1395J-1733D01*
G01Y848120D01*
G02X349990Y846248I-2225J56D01*
G03X349253Y845005I737J-1277D01*
G01Y842642D01*
X350694Y841201D01*
Y840462D01*
X350678Y840446D01*
Y833108D01*
X350844Y832942D01*
Y832855D01*
G01X354427Y844971D02*
X353811Y846038D01*
X353503Y846120D01*
G03X352952Y844971I924J-1150D01*
G01Y843329D01*
X354372Y841909D01*
Y840678D01*
X354763Y840287D01*
Y839237D01*
X354372Y838846D01*
Y837796D01*
X354763Y837405D01*
Y836355D01*
X354372Y835964D01*
Y833878D01*
X354538Y833712D01*
Y833625D01*
G01X352578Y848176D02*
X353194Y847109D01*
X353099Y846758D01*
G03X353032Y846706I1331J-1784D01*
G03X352202Y845027I1395J-1734D01*
G01X352203Y845029D01*
Y843018D01*
X353623Y841598D01*
Y833877D01*
X353458Y833712D01*
Y833625D01*
G01X357589Y833745D02*
Y833832D01*
X357754Y833997D01*
Y835834D01*
X357363Y836225D01*
Y837275D01*
X357754Y837666D01*
Y838716D01*
X357363Y839107D01*
Y840157D01*
X357754Y840548D01*
Y842100D01*
G03X357237Y842755I-1475J-633D01*
G01X356904Y842652D01*
X356279Y841467D01*
G01X358669Y833745D02*
Y833832D01*
X358503Y833998D01*
Y842245D01*
X358504Y842242D01*
G03X358445Y842395I-2226J-771D01*
G03X357621Y843405I-2166J-926D01*
G01X357502Y843786D01*
X358127Y844971D01*
G01X359978Y848176D02*
X360594Y847109D01*
X360499Y846758D01*
G03X360432Y846706I1331J-1784D01*
G03X359602Y845027I1395J-1734D01*
G01Y844196D01*
G03X360728Y842887I2225J775D01*
G02X361454Y842100I-749J-1420D01*
G01X361455Y842098D01*
Y833997D01*
X361290Y833832D01*
Y833745D01*
G01X361827Y844971D02*
X361211Y846038D01*
X360903Y846120D01*
G03X360352Y844971I924J-1150D01*
G01Y844338D01*
G03X361078Y843551I1475J633D01*
G02X362144Y842396I-1099J-2084D01*
G02X362204Y842242I-2164J-932D01*
G01Y840618D01*
X362595Y840227D01*
Y839177D01*
X362204Y838786D01*
Y837736D01*
X362595Y837345D01*
Y836295D01*
X362204Y835904D01*
Y833998D01*
X362370Y833832D01*
Y833745D01*
G01X363679Y841467D02*
X364304Y842652D01*
X364637Y842755D01*
G02X365154Y842100I-958J-1288D01*
G01Y840548D01*
X364763Y840157D01*
Y839107D01*
X365154Y838716D01*
Y837666D01*
X364763Y837275D01*
Y836225D01*
X365154Y835834D01*
Y833247D01*
X364989Y833082D01*
Y832995D01*
G01X365527Y844971D02*
X364902Y843786D01*
X365021Y843405D01*
G02X365845Y842395I-1342J-1936D01*
G02X365904Y842242I-2167J-924D01*
G01X365903Y842245D01*
Y833248D01*
X366069Y833082D01*
Y832995D01*
G01X369770Y833585D02*
Y833672D01*
X369604Y833838D01*
Y835904D01*
X369995Y836295D01*
Y837345D01*
X369604Y837736D01*
Y838786D01*
X369995Y839177D01*
Y840227D01*
X369604Y840618D01*
Y842242D01*
G03X369544Y842396I-2224J-778D01*
G03X368478Y843551I-2165J-929D01*
G02X367752Y844338I749J1420D01*
G01Y844971D01*
G02X368303Y846120I1475J-1D01*
G01X368611Y846038D01*
X369227Y844971D01*
G01X368690Y833585D02*
Y833672D01*
X368855Y833837D01*
Y842098D01*
X368854Y842100D01*
G03X368128Y842887I-1475J-633D01*
G02X367002Y844196I1099J2084D01*
G01Y845027D01*
G02X367832Y846706I2225J-55D01*
G02X367899Y846758I1398J-1732D01*
G01X367994Y847109D01*
X367378Y848176D01*
G01X372389Y835047D02*
Y835134D01*
X372554Y835299D01*
Y835834D01*
X372163Y836225D01*
Y837275D01*
X372554Y837666D01*
Y838716D01*
X372163Y839107D01*
Y840157D01*
X372554Y840548D01*
Y842100D01*
G03X372037Y842755I-1475J-633D01*
G01X371704Y842652D01*
X371079Y841467D01*
G01X373469Y835047D02*
Y835134D01*
X373303Y835300D01*
Y842245D01*
X373304Y842242D01*
G03X373245Y842395I-2226J-771D01*
G03X372421Y843405I-2166J-926D01*
G01X372302Y843786D01*
X372927Y844971D01*
G01X374778Y848176D02*
X375394Y847109D01*
X375299Y846758D01*
G03X375232Y846706I1331J-1784D01*
G03X374402Y845027I1395J-1734D01*
G01Y844196D01*
G03X375528Y842887I2225J775D01*
G02X376254Y842100I-749J-1420D01*
G01X376255Y842098D01*
Y833997D01*
X376090Y833832D01*
Y833745D01*
G01X376627Y844971D02*
X376011Y846038D01*
X375703Y846120D01*
G03X375152Y844971I924J-1150D01*
G01Y844338D01*
G03X375878Y843551I1475J633D01*
G02X376944Y842396I-1099J-2084D01*
G02X377004Y842242I-2164J-932D01*
G01Y840618D01*
X377395Y840227D01*
Y839177D01*
X377004Y838786D01*
Y837736D01*
X377395Y837345D01*
Y836295D01*
X377004Y835904D01*
Y833998D01*
X377170Y833832D01*
Y833745D01*
G01X380869D02*
Y833832D01*
X380703Y833998D01*
Y842245D01*
X380704Y842242D01*
G03X380645Y842395I-2226J-771D01*
G03X379821Y843405I-2166J-926D01*
G01X379702Y843786D01*
X380327Y844971D01*
G01X379789Y833745D02*
Y833832D01*
X379954Y833997D01*
Y835834D01*
X379563Y836225D01*
Y837275D01*
X379954Y837666D01*
Y838716D01*
X379563Y839107D01*
Y840157D01*
X379954Y840548D01*
Y842100D01*
G03X379437Y842755I-1475J-633D01*
G01X379104Y842652D01*
X378479Y841467D01*
G01X384027Y844971D02*
X383411Y846038D01*
X383103Y846120D01*
G03X382552Y844971I924J-1150D01*
G01Y844338D01*
G03X383278Y843551I1475J633D01*
G02X384344Y842396I-1099J-2084D01*
G02X384404Y842242I-2164J-932D01*
G01Y840618D01*
X384795Y840227D01*
Y839177D01*
X384404Y838786D01*
Y837736D01*
X384795Y837345D01*
Y836295D01*
X384404Y835904D01*
Y833998D01*
X384570Y833832D01*
Y833745D01*
G01X382178Y848176D02*
X382794Y847109D01*
X382699Y846758D01*
G03X382632Y846706I1331J-1784D01*
G03X381802Y845027I1395J-1734D01*
G01Y844196D01*
G03X382928Y842887I2225J775D01*
G02X383654Y842100I-749J-1420D01*
G01X383655Y842098D01*
Y833997D01*
X383490Y833832D01*
Y833745D01*
G01X385879Y841467D02*
X386504Y842652D01*
X386837Y842755D01*
G02X387354Y842100I-958J-1288D01*
G01Y840548D01*
X386963Y840157D01*
Y839107D01*
X387354Y838716D01*
Y837666D01*
X386963Y837275D01*
Y836225D01*
X387354Y835834D01*
Y833997D01*
X387189Y833832D01*
Y833745D01*
G01X387727Y844971D02*
X387102Y843786D01*
X387221Y843405D01*
G02X388045Y842395I-1342J-1936D01*
G02X388104Y842242I-2167J-924D01*
G01X388103Y842245D01*
Y833998D01*
X388269Y833832D01*
Y833745D01*
G01X391427Y844971D02*
X390811Y846038D01*
X390503Y846120D01*
G03X389952Y844971I924J-1150D01*
G01Y844338D01*
G03X390678Y843551I1475J633D01*
G02X391744Y842396I-1099J-2084D01*
G02X391804Y842242I-2164J-932D01*
G01Y840618D01*
X392195Y840227D01*
Y839177D01*
X391804Y838786D01*
Y837736D01*
X392195Y837345D01*
Y836295D01*
X391804Y835904D01*
Y833998D01*
X391970Y833832D01*
Y833745D01*
G01X389578Y848176D02*
X390194Y847109D01*
X390099Y846758D01*
G03X390032Y846706I1331J-1784D01*
G03X389202Y845027I1395J-1734D01*
G01Y844196D01*
G03X390328Y842887I2225J775D01*
G02X391054Y842100I-749J-1420D01*
G01X391055Y842098D01*
Y833997D01*
X390890Y833832D01*
Y833745D01*
G01X395669D02*
Y833832D01*
X395503Y833998D01*
Y842245D01*
X395504Y842242D01*
G03X395445Y842395I-2226J-771D01*
G03X394621Y843405I-2166J-926D01*
G01X394502Y843786D01*
X395127Y844971D01*
G01X394589Y833745D02*
Y833832D01*
X394754Y833997D01*
Y835834D01*
X394363Y836225D01*
Y837275D01*
X394754Y837666D01*
Y838716D01*
X394363Y839107D01*
Y840157D01*
X394754Y840548D01*
Y842100D01*
G03X394237Y842755I-1475J-633D01*
G01X393904Y842652D01*
X393279Y841467D01*
G01X398290Y833465D02*
Y833552D01*
X398455Y833717D01*
Y842098D01*
X398454Y842100D01*
G03X397728Y842887I-1475J-633D01*
G02X396602Y844196I1099J2084D01*
G01Y845027D01*
G02X397432Y846706I2225J-55D01*
G02X397499Y846758I1398J-1732D01*
G01X397594Y847109D01*
X396978Y848176D01*
G01X399370Y833465D02*
Y833509D01*
X399204Y833675D01*
Y835904D01*
X399595Y836295D01*
Y837345D01*
X399204Y837736D01*
Y838786D01*
X399595Y839177D01*
Y840227D01*
X399204Y840618D01*
Y842242D01*
G03X399144Y842396I-2224J-778D01*
G03X398078Y843551I-2165J-929D01*
G02X397352Y844338I749J1420D01*
G01Y844971D01*
G02X397903Y846120I1475J-1D01*
G01X398211Y846038D01*
X398827Y844971D01*
G01X400679Y841467D02*
X401304Y842652D01*
X401637Y842755D01*
G02X402154Y842100I-958J-1288D01*
G01Y840548D01*
X401763Y840157D01*
Y839107D01*
X402154Y838716D01*
Y837666D01*
X401763Y837275D01*
Y836225D01*
X402154Y835834D01*
Y833997D01*
X401989Y833832D01*
Y833745D01*
G01X402527Y844971D02*
X401902Y843786D01*
X402021Y843405D01*
G02X402845Y842395I-1342J-1936D01*
G02X402904Y842242I-2167J-924D01*
G01X402903Y842245D01*
Y833955D01*
X403069Y833789D01*
Y833745D01*
G01X406227Y844971D02*
X405611Y846038D01*
X405303Y846120D01*
G03X404752Y844971I924J-1150D01*
G01Y844338D01*
G03X405478Y843551I1475J633D01*
G02X406544Y842396I-1099J-2084D01*
G02X406604Y842242I-2164J-932D01*
G01Y840618D01*
X406995Y840227D01*
Y839177D01*
X406604Y838786D01*
Y837736D01*
X406995Y837345D01*
Y836295D01*
X406604Y835904D01*
Y833955D01*
X406770Y833789D01*
Y833745D01*
G01X404378Y848176D02*
X404994Y847109D01*
X404899Y846758D01*
G03X404832Y846706I1331J-1784D01*
G03X404002Y845027I1395J-1734D01*
G01Y844196D01*
G03X405128Y842887I2225J775D01*
G02X405854Y842100I-749J-1420D01*
G01X405855Y842098D01*
Y833997D01*
X405690Y833832D01*
Y833745D01*
G01X409927Y844971D02*
X409302Y843786D01*
X409421Y843405D01*
G02X410245Y842395I-1342J-1936D01*
G02X410304Y842242I-2167J-924D01*
G01X410303Y842245D01*
Y833955D01*
X410469Y833789D01*
Y833745D01*
G01X414170D02*
Y833789D01*
X414004Y833955D01*
Y835904D01*
X414395Y836295D01*
Y837307D01*
X414004Y837698D01*
Y838786D01*
X414395Y839177D01*
Y840227D01*
X414004Y840618D01*
Y842242D01*
G03X413944Y842396I-2224J-778D01*
G03X412878Y843551I-2165J-929D01*
G02X412152Y844338I749J1420D01*
G01Y844971D01*
G02X412703Y846120I1475J-1D01*
G01X413011Y846038D01*
X413627Y844971D01*
G01X408079Y841467D02*
X408704Y842652D01*
X409037Y842755D01*
G02X409554Y842100I-958J-1288D01*
G01Y840548D01*
X409163Y840157D01*
Y839107D01*
X409554Y838716D01*
Y837666D01*
X409163Y837275D01*
Y836225D01*
X409554Y835834D01*
Y833997D01*
X409389Y833832D01*
Y833745D01*
G01X413090D02*
Y833832D01*
X413255Y833997D01*
Y842098D01*
X413254Y842100D01*
G03X412528Y842887I-1475J-633D01*
G02X411402Y844196I1099J2084D01*
G01Y845027D01*
G02X412232Y846706I2225J-55D01*
G02X412299Y846758I1398J-1732D01*
G01X412394Y847109D01*
X411778Y848176D01*
G01X417327Y844971D02*
X416702Y843786D01*
X416821Y843405D01*
G02X417645Y842395I-1342J-1936D01*
G02X417704Y842242I-2167J-924D01*
G01X417703Y842245D01*
Y833955D01*
X417869Y833789D01*
Y833745D01*
G01X415479Y841467D02*
X416104Y842652D01*
X416437Y842755D01*
G02X416954Y842100I-958J-1288D01*
G01Y840548D01*
X416563Y840157D01*
Y839107D01*
X416954Y838716D01*
Y837666D01*
X416563Y837275D01*
Y836225D01*
X416954Y835834D01*
Y833997D01*
X416789Y833832D01*
Y833745D01*
G01X420490D02*
Y833832D01*
X420655Y833997D01*
Y842098D01*
X420654Y842100D01*
G03X419928Y842887I-1475J-633D01*
G02X418802Y844196I1099J2084D01*
G01Y845027D01*
G02X419632Y846706I2225J-55D01*
G02X419699Y846758I1398J-1732D01*
G01X419794Y847109D01*
X419178Y848176D01*
G01X421570Y833745D02*
Y833832D01*
X421404Y833998D01*
Y835904D01*
X421795Y836295D01*
Y837345D01*
X421404Y837736D01*
Y838786D01*
X421795Y839177D01*
Y840227D01*
X421404Y840618D01*
Y842242D01*
G03X421344Y842396I-2224J-778D01*
G03X420278Y843551I-2165J-929D01*
G02X419552Y844338I749J1420D01*
G01Y844971D01*
G02X420103Y846120I1475J-1D01*
G01X420411Y846038D01*
X421027Y844971D01*
G01X424189Y833745D02*
Y833832D01*
X424354Y833997D01*
Y835834D01*
X423963Y836225D01*
Y837275D01*
X424354Y837666D01*
Y838716D01*
X423963Y839107D01*
Y840157D01*
X424354Y840548D01*
Y842100D01*
G03X423837Y842755I-1475J-633D01*
G01X423504Y842652D01*
X422879Y841467D01*
G01X425269Y833745D02*
Y833789D01*
X425103Y833955D01*
Y842245D01*
X425104Y842242D01*
G03X425045Y842395I-2226J-771D01*
G03X424221Y843405I-2166J-926D01*
G01X424102Y843786D01*
X424727Y844971D01*
G01X428427D02*
X427811Y846038D01*
X427503Y846120D01*
G03X426952Y844971I924J-1150D01*
G01Y844338D01*
G03X427678Y843551I1475J633D01*
G01X429966Y841263D01*
Y840213D01*
X430357Y839822D01*
Y838772D01*
X429966Y838381D01*
Y837331D01*
X430357Y836940D01*
Y835890D01*
X429966Y835499D01*
Y833955D01*
X430132Y833789D01*
Y833745D01*
G01X426578Y848176D02*
X427194Y847109D01*
X427099Y846758D01*
G03X427032Y846706I1331J-1784D01*
G03X426202Y845027I1395J-1734D01*
G01Y844196D01*
G03X427221Y842947I2225J775D01*
G01X429217Y840952D01*
Y833997D01*
X429052Y833832D01*
Y833745D01*
G01X433978Y848176D02*
X432988D01*
G03X432542Y847458I-1J-497D01*
G03X433226Y846754I1439J714D01*
G02X434351Y844887I-984J-1865D01*
G01Y833455D01*
X434517Y833289D01*
Y833245D01*
G01X430278Y848176D02*
X431243D01*
G02X431740Y847679I0J-497D01*
G03X431871Y847125I1246J2D01*
G01X431868Y847123D01*
G03X432877Y846091I2110J1053D01*
G02X433602Y844888I-635J-1203D01*
G01Y833497D01*
X433437Y833332D01*
Y833245D01*
G01X437139D02*
Y833332D01*
X437304Y833497D01*
Y835734D01*
X436913Y836125D01*
Y837175D01*
X437304Y837566D01*
Y838616D01*
X436913Y839007D01*
Y840057D01*
X437304Y840448D01*
Y845304D01*
G03X436787Y845959I-1475J-633D01*
G01X436454Y845856D01*
X435829Y844671D01*
G01X438219Y833245D02*
Y833289D01*
X438053Y833455D01*
Y845453D01*
X438054Y845450D01*
G03X437996Y845600I-2227J-775D01*
G03X437172Y846609I-2167J-929D01*
G01X437053Y846991D01*
X437678Y848176D01*
G01X1411969Y844971D02*
X1412585Y846038D01*
X1412893Y846120D01*
G02X1413443Y845028I-924J-1150D01*
G02X1413444Y844971I-1474J-54D01*
G01Y843456D01*
X1411596Y841608D01*
Y840358D01*
X1411205Y839967D01*
Y838917D01*
X1411596Y838526D01*
Y837476D01*
X1411205Y837085D01*
Y836035D01*
X1411596Y835644D01*
Y833837D01*
X1411431Y833672D01*
Y833585D01*
G01X446961Y837051D02*
Y837138D01*
X446795Y837304D01*
Y840747D01*
X445451Y842091D01*
Y844184D01*
X445938Y844671D01*
X446927D01*
G01X1410120Y848176D02*
X1408889D01*
X1408663Y847950D01*
G03X1409348Y846919I1458J225D01*
G01X1409379Y846901D01*
X1409383Y846899D01*
G02X1410494Y845058I-1114J-1928D01*
G01Y843736D01*
X1408644Y841886D01*
Y833437D01*
X1408809Y833272D01*
Y833185D01*
G01X450091Y833715D02*
Y833802D01*
X450256Y833967D01*
Y841936D01*
X448403Y843789D01*
Y844790D01*
G02X449223Y846707I2225J182D01*
G02X449302Y846768I1404J-1736D01*
G01X449394Y847109D01*
X448778Y848176D01*
G01X1413820D02*
X1413204Y847109D01*
X1413299Y846758D01*
G02X1413365Y846707I-1328J-1787D01*
G02X1414194Y845058I-1396J-1735D01*
G01Y843146D01*
X1412345Y841297D01*
Y833838D01*
X1412511Y833672D01*
Y833585D01*
G01X445881Y837051D02*
Y837138D01*
X446046Y837303D01*
Y840436D01*
X444702Y841780D01*
Y844120D01*
X444151Y844671D01*
X443227D01*
G01X1406420Y848176D02*
X1407651D01*
X1407908Y847919D01*
G03X1407919Y847835I2213J247D01*
G03X1409006Y846248I2200J341D01*
G01X1409041Y846228D01*
G02X1409743Y845029I-772J-1257D01*
G02X1409744Y844975I-1474J-54D01*
G01X1409745D01*
Y844047D01*
X1407895Y842197D01*
Y840398D01*
X1407504Y840007D01*
Y838957D01*
X1407895Y838566D01*
Y837516D01*
X1407504Y837125D01*
Y836075D01*
X1407895Y835684D01*
Y833438D01*
X1407729Y833272D01*
Y833185D01*
G01X451171Y833715D02*
Y833802D01*
X451005Y833968D01*
Y835812D01*
X451396Y836203D01*
Y837253D01*
X451005Y837644D01*
Y838766D01*
X451396Y839157D01*
Y840207D01*
X451005Y840598D01*
Y842247D01*
X449152Y844100D01*
Y844852D01*
G02X449697Y846122I1476J119D01*
G01X450012Y846038D01*
X450628Y844971D01*
G01X1402720Y848176D02*
X1403336Y847109D01*
X1403241Y846758D01*
G03X1403174Y846706I1331J-1784D01*
G03X1402344Y845027I1395J-1734D01*
G01Y844196D01*
G03X1403363Y842947I2225J775D01*
G01X1404196Y842115D01*
Y833568D01*
X1404030Y833402D01*
Y833315D01*
G01X454869Y833695D02*
Y833782D01*
X454703Y833948D01*
Y842245D01*
X454704Y842242D01*
G03X454645Y842395I-2226J-771D01*
G03X453821Y843405I-2166J-926D01*
G01X453702Y843786D01*
X454327Y844971D01*
G01X1404569D02*
X1403953Y846038D01*
X1403645Y846120D01*
G03X1403094Y844971I924J-1150D01*
G01Y844338D01*
G03X1403820Y843551I1475J633D01*
G01X1404945Y842426D01*
Y840618D01*
X1405336Y840227D01*
Y839177D01*
X1404945Y838786D01*
Y837736D01*
X1405336Y837345D01*
Y836295D01*
X1404945Y835904D01*
Y833567D01*
X1405110Y833402D01*
Y833315D01*
G01X453789Y833695D02*
Y833782D01*
X453954Y833947D01*
Y842100D01*
G03X453437Y842755I-1475J-633D01*
G01X453104Y842652D01*
X452479Y841467D01*
G01X1399021D02*
X1399646Y842652D01*
X1399979Y842755D01*
G02X1400496Y842100I-958J-1288D01*
G01Y840506D01*
X1400105Y840115D01*
Y839065D01*
X1400496Y838674D01*
Y837624D01*
X1400105Y837233D01*
Y836183D01*
X1400496Y835792D01*
Y833677D01*
X1400331Y833512D01*
Y833425D01*
G01X458570Y833405D02*
Y833492D01*
X458404Y833658D01*
Y835812D01*
X458795Y836203D01*
Y837253D01*
X458404Y837644D01*
Y838766D01*
X458795Y839157D01*
Y840207D01*
X458404Y840598D01*
Y842242D01*
G03X458344Y842396I-2224J-778D01*
G03X457278Y843551I-2165J-929D01*
G02X456552Y844338I749J1420D01*
G01Y844971D01*
G02X457103Y846120I1475J-1D01*
G01X457411Y846038D01*
X458027Y844971D01*
G01X1400869D02*
X1400244Y843786D01*
X1400363Y843405D01*
G02X1401187Y842395I-1342J-1936D01*
G02X1401246Y842242I-2167J-924D01*
G01Y833677D01*
X1401411Y833512D01*
Y833425D01*
G01X457490Y833492D02*
X457655Y833657D01*
Y842098D01*
X457654Y842100D01*
G03X456928Y842887I-1475J-633D01*
G02X455802Y844196I1099J2084D01*
G01Y845027D01*
G02X456632Y846706I2225J-55D01*
G02X456699Y846758I1398J-1732D01*
G01X456794Y847109D01*
X456178Y848176D01*
G01X1393469Y844971D02*
X1392844Y843786D01*
X1392963Y843405D01*
G02X1393787Y842395I-1342J-1936D01*
G02X1393846Y842242I-2167J-924D01*
G01Y833567D01*
X1394011Y833402D01*
Y833315D01*
G01X464890Y833615D02*
Y833702D01*
X465055Y833867D01*
Y842098D01*
X465054Y842100D01*
G03X464328Y842887I-1475J-633D01*
G02X463202Y844196I1099J2084D01*
G01Y845027D01*
G02X464032Y846706I2225J-55D01*
G02X464099Y846758I1398J-1732D01*
G01X464194Y847109D01*
X463578Y848176D01*
G01X1397169Y844971D02*
X1396553Y846038D01*
X1396245Y846120D01*
G03X1395694Y844971I924J-1150D01*
G01Y844338D01*
G03X1396420Y843551I1475J633D01*
G02X1397486Y842396I-1099J-2084D01*
G02X1397546Y842242I-2164J-932D01*
G01Y840486D01*
X1397937Y840095D01*
Y839045D01*
X1397546Y838654D01*
Y837604D01*
X1397937Y837213D01*
Y836163D01*
X1397546Y835772D01*
Y833998D01*
X1397712Y833832D01*
Y833745D01*
G01X461189D02*
Y833832D01*
X461354Y833997D01*
Y842100D01*
G03X460837Y842755I-1475J-633D01*
G01X460504Y842652D01*
X459879Y841467D01*
G01X1391621D02*
X1392246Y842652D01*
X1392579Y842755D01*
G02X1393096Y842100I-958J-1288D01*
G01Y840506D01*
X1392705Y840115D01*
Y839065D01*
X1393096Y838674D01*
Y837624D01*
X1392705Y837233D01*
Y836183D01*
X1393096Y835792D01*
Y833567D01*
X1392931Y833402D01*
Y833315D01*
G01X465970Y833615D02*
Y833702D01*
X465804Y833868D01*
Y835812D01*
X466195Y836203D01*
Y837253D01*
X465804Y837644D01*
Y838766D01*
X466195Y839157D01*
Y840207D01*
X465804Y840598D01*
Y842242D01*
G03X465744Y842396I-2224J-778D01*
G03X464678Y843551I-2165J-929D01*
G02X463952Y844338I749J1420D01*
G01Y844971D01*
G02X464503Y846120I1475J-1D01*
G01X464811Y846038D01*
X465427Y844971D01*
G01X1395320Y848176D02*
X1395936Y847109D01*
X1395841Y846758D01*
G03X1395774Y846706I1331J-1784D01*
G03X1394944Y845027I1395J-1734D01*
G01Y844196D01*
G03X1396070Y842887I2225J775D01*
G02X1396796Y842100I-749J-1420D01*
G01X1396797Y842098D01*
Y833997D01*
X1396632Y833832D01*
Y833745D01*
G01X462269D02*
Y833832D01*
X462103Y833998D01*
Y842245D01*
X462104Y842242D01*
G03X462045Y842395I-2226J-771D01*
G03X461221Y843405I-2166J-926D01*
G01X461102Y843786D01*
X461727Y844971D01*
G01X1389769D02*
X1389153Y846038D01*
X1388845Y846120D01*
G03X1388294Y844971I924J-1150D01*
G01Y844338D01*
G03X1389020Y843551I1475J633D01*
G02X1390086Y842396I-1099J-2084D01*
G02X1390146Y842242I-2164J-932D01*
G01Y840486D01*
X1390537Y840095D01*
Y839045D01*
X1390146Y838654D01*
Y837604D01*
X1390537Y837213D01*
Y836163D01*
X1390146Y835772D01*
Y833568D01*
X1390312Y833402D01*
Y833315D01*
G01X468589Y833135D02*
Y833222D01*
X468754Y833387D01*
Y842100D01*
G03X468237Y842755I-1475J-633D01*
G01X467904Y842652D01*
X467279Y841467D01*
G01X545441Y1129883D02*
X543562D01*
G03X542874Y1129763I-1J-2027D01*
G01X542182Y1129404D01*
G02X540966Y1129687I-170J2023D01*
G03X539289Y1129728I-875J-1458D01*
G01X539038Y1129595D01*
G03X538066Y1128188I882J-1649D01*
G01X538062Y1127775D01*
G02X537140Y1126356I-1854J195D01*
G01X536931Y1126236D01*
G03X536192Y1124696I1140J-1494D01*
G02X535530Y1123219I-1880J-44D01*
G01X535199Y1123027D01*
G02X533386Y1123049I-887J1624D01*
G03X531536I-925J-1602D01*
G02X529686I-925J1602D01*
G01X529633Y1123080D01*
G03X527836Y1123049I-871J-1633D01*
G01X527837D01*
G02X525987I-925J1602D01*
G01X525986D01*
G03X523212Y1121485I-925J-1602D01*
G01Y1121447D01*
G02X522287Y1119846I-1848J0D01*
G01X522286Y1119845D01*
X522233Y1119814D01*
G02X520436Y1119845I-871J1633D01*
G03X518586I-925J-1602D01*
G01X518533Y1119814D01*
G02X516736Y1119845I-871J1633D01*
G03X514886I-925J-1602D01*
G01X514833Y1119814D01*
G02X513036Y1119845I-871J1633D01*
G03X511186I-925J-1602D01*
G01X511133Y1119814D01*
G02X509336Y1119845I-871J1633D01*
G03X507486I-925J-1602D01*
G01X507433Y1119814D01*
G02X505636Y1119845I-871J1633D01*
G03X503786I-925J-1602D01*
G01X503733Y1119814D01*
G02X501936Y1119845I-871J1633D01*
G03X500086I-925J-1602D01*
G01X500033Y1119814D01*
G02X498236Y1119845I-871J1633D01*
G03X496386I-925J-1602D01*
G01X496348Y1119823D01*
G02X494537Y1119845I-886J1624D01*
G03X492687I-925J-1602D01*
G01X492649Y1119823D01*
G02X490836Y1119845I-887J1624D01*
G03X488986I-925J-1602D01*
G01X488933Y1119814D01*
G02X487136Y1119845I-871J1633D01*
G01X487137D01*
G03X485287I-925J-1602D01*
G01X485286D01*
X485267Y1119834D01*
G03X484361Y1118243I944J-1591D01*
G02X483455Y1116652I-1850J0D01*
G01X483436Y1116641D01*
G03X482512Y1115077I926J-1602D01*
G01Y1115039D01*
G02X481642Y1113470I-1850J0D01*
G01X481586Y1113437D01*
G03X481567Y1110243I925J-1603D01*
G01X481628Y1110207D01*
G02X482512Y1108630I-965J-1577D01*
G01Y1108592D01*
G03X483436Y1107028I1850J38D01*
G01X483455Y1107017D01*
G02X483436Y1103823I-944J-1591D01*
G03X482512Y1102259I926J-1602D01*
G01Y1102221D01*
G02X481628Y1100644I-1849J0D01*
G01X481567Y1100608D01*
G03X480661Y1099017I944J-1591D01*
G02X479755Y1097426I-1850J0D01*
G01X479736Y1097415D01*
G03X478812Y1095870I925J-1602D01*
G01Y1095813D01*
G02X477928Y1094236I-1849J0D01*
G01X477886Y1094211D01*
G03X476961Y1092661I925J-1603D01*
G01Y1092608D01*
G02X476055Y1091017I-1850J0D01*
G01X476036Y1091006D01*
G03Y1087802I926J-1602D01*
G01Y1087801D01*
G02Y1084597I-924J-1602D01*
G02X474190I-923J1599D01*
G01X474187Y1084598D01*
X474186Y1084597D01*
X474133Y1084628D01*
G03X472336Y1084597I-871J-1633D01*
G03X471412Y1082996I925J-1601D01*
G01Y1082995D01*
G02X470528Y1081418I-1849J0D01*
G01X470467Y1081382D01*
G03X469561Y1079791I944J-1591D01*
G02X468655Y1078200I-1850J0D01*
G01X468636Y1078189D01*
X468637D01*
X465862Y1076587D01*
G01X1386069Y844971D02*
X1385444Y843786D01*
X1385563Y843405D01*
G02X1386387Y842395I-1342J-1936D01*
G02X1386446Y842242I-2167J-924D01*
G01Y833567D01*
X1386611Y833402D01*
Y833315D01*
G01X472290Y833785D02*
Y833872D01*
X472455Y834037D01*
Y842098D01*
X472454Y842100D01*
G03X471728Y842887I-1475J-633D01*
G02X470602Y844196I1099J2084D01*
G01Y845027D01*
G02X471432Y846706I2225J-55D01*
G02X471499Y846758I1398J-1732D01*
G01X471594Y847109D01*
X470978Y848176D01*
G01X1382369Y844971D02*
X1381753Y846038D01*
X1381445Y846120D01*
G03X1380894Y844971I924J-1150D01*
G01Y844338D01*
G03X1381620Y843551I1475J633D01*
G02X1382686Y842396I-1099J-2084D01*
G02X1382746Y842242I-2164J-932D01*
G01Y840486D01*
X1383137Y840095D01*
Y839045D01*
X1382746Y838654D01*
Y837604D01*
X1383137Y837213D01*
Y836163D01*
X1382746Y835772D01*
Y833568D01*
X1382912Y833402D01*
Y833315D01*
G01X475989Y833705D02*
Y833792D01*
X476154Y833957D01*
Y842100D01*
G03X475637Y842755I-1475J-633D01*
G01X475304Y842652D01*
X474679Y841467D01*
G01X1384221D02*
X1384846Y842652D01*
X1385179Y842755D01*
G02X1385696Y842100I-958J-1288D01*
G01Y840506D01*
X1385305Y840115D01*
Y839065D01*
X1385696Y838674D01*
Y837624D01*
X1385305Y837233D01*
Y836183D01*
X1385696Y835792D01*
Y833567D01*
X1385531Y833402D01*
Y833315D01*
G01X473370Y833785D02*
Y833872D01*
X473204Y834038D01*
Y835812D01*
X473595Y836203D01*
Y837253D01*
X473204Y837644D01*
Y838766D01*
X473595Y839157D01*
Y840207D01*
X473204Y840598D01*
Y842242D01*
G03X473144Y842396I-2224J-778D01*
G03X472078Y843551I-2165J-929D01*
G02X471352Y844338I749J1420D01*
G01Y844971D01*
G02X471903Y846120I1475J-1D01*
G01X472211Y846038D01*
X472827Y844971D01*
G01X1387920Y848176D02*
X1388536Y847109D01*
X1388441Y846758D01*
G03X1388374Y846706I1331J-1784D01*
G03X1387544Y845027I1395J-1734D01*
G01Y844196D01*
G03X1388670Y842887I2225J775D01*
G02X1389396Y842100I-749J-1420D01*
G01X1389397Y842098D01*
Y833567D01*
X1389232Y833402D01*
Y833315D01*
G01X469669Y833135D02*
Y833222D01*
X469503Y833388D01*
Y842245D01*
X469504Y842242D01*
G03X469445Y842395I-2226J-771D01*
G03X468621Y843405I-2166J-926D01*
G01X468502Y843786D01*
X469127Y844971D01*
G01X1376821Y841467D02*
X1377446Y842652D01*
X1377779Y842755D01*
G02X1378296Y842100I-958J-1288D01*
G01Y840506D01*
X1377905Y840115D01*
Y839065D01*
X1378296Y838674D01*
Y837624D01*
X1377905Y837233D01*
Y836183D01*
X1378296Y835792D01*
Y833567D01*
X1378131Y833402D01*
Y833315D01*
G01X480768D02*
Y833402D01*
X480602Y833568D01*
Y835294D01*
X480993Y835685D01*
Y836735D01*
X480602Y837126D01*
Y838176D01*
X480993Y838567D01*
Y839617D01*
X480602Y840008D01*
Y842243D01*
G03X479477Y843550I-2223J-776D01*
G01X479478Y843551D01*
G02X478752Y844338I749J1420D01*
G01Y844971D01*
G02X479303Y846120I1475J-1D01*
G01X479611Y846038D01*
X480227Y844971D01*
G01X1380520Y848176D02*
X1381136Y847109D01*
X1381041Y846758D01*
G03X1380974Y846706I1331J-1784D01*
G03X1380144Y845027I1395J-1734D01*
G01Y844196D01*
G03X1381270Y842887I2225J775D01*
G02X1381996Y842100I-749J-1420D01*
G01X1381997Y842098D01*
Y833567D01*
X1381832Y833402D01*
Y833315D01*
G01X477069Y833705D02*
Y833792D01*
X476903Y833958D01*
Y842245D01*
X476904Y842242D01*
G03X476845Y842395I-2226J-771D01*
G03X476021Y843405I-2166J-926D01*
G01X475902Y843786D01*
X476527Y844971D01*
G01X1378669D02*
X1378044Y843786D01*
X1378163Y843405D01*
G02X1378987Y842395I-1342J-1936D01*
G02X1379046Y842242I-2167J-924D01*
G01Y833567D01*
X1379211Y833402D01*
Y833315D01*
G01X479688D02*
Y833402D01*
X479853Y833567D01*
Y842103D01*
G03X479128Y842887I-1474J-636D01*
G02X478002Y844196I1099J2084D01*
G01Y845027D01*
G02X478832Y846706I2225J-55D01*
G02X478899Y846758I1398J-1732D01*
G01X478994Y847109D01*
X478378Y848176D01*
G01X1373120D02*
X1373736Y847109D01*
X1373641Y846758D01*
G03X1373574Y846706I1331J-1784D01*
G03X1372744Y845027I1395J-1734D01*
G01Y844196D01*
G03X1373870Y842887I2225J775D01*
G02X1374596Y842100I-749J-1420D01*
G01X1374597Y842098D01*
Y833567D01*
X1374432Y833402D01*
Y833315D01*
G01X484469Y833365D02*
Y833452D01*
X484303Y833618D01*
Y842245D01*
X484304Y842242D01*
G03X484245Y842395I-2226J-771D01*
G03X483421Y843405I-2166J-926D01*
G01X483302Y843786D01*
X483927Y844971D01*
G01X1374969D02*
X1374353Y846038D01*
X1374045Y846120D01*
G03X1373494Y844971I924J-1150D01*
G01Y844338D01*
G03X1374220Y843551I1475J633D01*
G02X1375286Y842396I-1099J-2084D01*
G02X1375346Y842242I-2164J-932D01*
G01Y840486D01*
X1375737Y840095D01*
Y839045D01*
X1375346Y838654D01*
Y837604D01*
X1375737Y837213D01*
Y836163D01*
X1375346Y835772D01*
Y833568D01*
X1375512Y833402D01*
Y833315D01*
G01X483389Y833365D02*
Y833452D01*
X483554Y833617D01*
Y842100D01*
G03X483037Y842755I-1475J-633D01*
G01X482704Y842652D01*
X482079Y841467D01*
G01X545654Y1126727D02*
G03X544696Y1126467I0J-1893D01*
G01X544307Y1126239D01*
G02X542754Y1126421I-569J1861D01*
G03X541371Y1126647I-984J-1680D01*
G01X540845Y1126343D01*
Y1126344D01*
G03X539920Y1124742I925J-1602D01*
G01Y1124684D01*
G02X538996Y1123139I-1849J57D01*
G01X538709Y1122973D01*
G03X538041Y1121491I1211J-1437D01*
G01Y1121492D01*
G02X537129Y1119871I-1822J-42D01*
G01X537086Y1119845D01*
G02X535236I-925J1602D01*
G03X533386I-925J-1602D01*
G02X531536I-925J1602D01*
G03X529686I-925J-1602D01*
G01X529633Y1119814D01*
G02X527836Y1119845I-871J1633D01*
G01X527837D01*
G03X525987I-925J-1602D01*
G01X525986D01*
X525967Y1119834D01*
G03X525061Y1118243I944J-1591D01*
G02X524136Y1116642I-1848J0D01*
G01Y1116641D01*
G02X522286I-925J1602D01*
G03X520436I-925J-1602D01*
G02X518586I-925J1602D01*
G01X518533Y1116672D01*
G03X516736Y1116641I-871J-1633D01*
G02X514886I-925J1602D01*
G03X513036I-925J-1602D01*
G02X511186I-925J1602D01*
G03X509336I-925J-1602D01*
G02X507486I-925J1602D01*
G01X507433Y1116672D01*
G03X505636Y1116641I-871J-1633D01*
G02X503786I-925J1602D01*
G01X503733Y1116672D01*
G03X501936Y1116641I-871J-1633D01*
G02X500086I-925J1602D01*
G03X497312Y1115096I-925J-1602D01*
G01Y1115039D01*
G02X494536Y1113437I-1850J0D01*
G01X494537D01*
G03X491761Y1111887I-926J-1602D01*
G01Y1111834D01*
G02X490855Y1110243I-1850J0D01*
G01X490836Y1110232D01*
G03X489912Y1108668I926J-1602D01*
G01Y1108630D01*
G02X489028Y1107053I-1849J0D01*
G01X488967Y1107017D01*
G03X488061Y1105426I944J-1591D01*
G01Y1105425D01*
G02X487136Y1103823I-1850J0D01*
G03X486212Y1102278I925J-1602D01*
G01Y1102221D01*
G02X485306Y1100630I-1850J0D01*
G01X485268Y1100608D01*
G03X484362Y1099017I944J-1591D01*
G02X483438Y1097417I-1847J0D01*
G01X483436Y1097415D01*
G03Y1094211I926J-1602D01*
G02X483455Y1091017I-925J-1603D01*
G01X483436Y1091006D01*
G03X482512Y1089442I926J-1602D01*
G01Y1089404D01*
G02X481606Y1087813I-1850J0D01*
G01X481568Y1087791D01*
G03X480662Y1086200I944J-1591D01*
G02X479763Y1084613I-1850J0D01*
G01X479736Y1084597D01*
G03X478812Y1083033I926J-1602D01*
G01Y1082995D01*
G02X477906Y1081404I-1850J0D01*
G01X477868Y1081382D01*
G03X476962Y1079791I944J-1591D01*
G02X476092Y1078222I-1850J0D01*
G01X476036Y1078189D01*
X475112Y1076625D01*
Y1076587D01*
X475111Y1073383D01*
G01X1367569Y844971D02*
X1366953Y846038D01*
X1366645Y846120D01*
G03X1366094Y844971I924J-1150D01*
G01Y844338D01*
G03X1366820Y843551I1475J633D01*
G02X1367886Y842396I-1099J-2084D01*
G02X1367946Y842242I-2164J-932D01*
G01Y840486D01*
X1368337Y840095D01*
Y839045D01*
X1367946Y838654D01*
Y837604D01*
X1368337Y837213D01*
Y836163D01*
X1367946Y835772D01*
Y833568D01*
X1368112Y833402D01*
Y833315D01*
G01X490788Y833275D02*
Y833362D01*
X490953Y833527D01*
Y842100D01*
G03X490436Y842755I-1475J-633D01*
G01X490103Y842652D01*
X489478Y841467D01*
G01X1369421D02*
X1370046Y842652D01*
X1370379Y842755D01*
G02X1370896Y842100I-958J-1288D01*
G01Y840506D01*
X1370505Y840115D01*
Y839065D01*
X1370896Y838674D01*
Y837624D01*
X1370505Y837233D01*
Y836183D01*
X1370896Y835792D01*
Y833567D01*
X1370731Y833402D01*
Y833315D01*
G01X488168Y833205D02*
Y833292D01*
X488002Y833458D01*
Y835294D01*
X488393Y835685D01*
Y836735D01*
X488002Y837126D01*
Y838176D01*
X488393Y838567D01*
Y839617D01*
X488002Y840008D01*
Y842243D01*
G03X486877Y843550I-2223J-776D01*
G01X486878Y843551D01*
G02X486152Y844338I749J1420D01*
G01Y844971D01*
G02X486703Y846120I1475J-1D01*
G01X487011Y846038D01*
X487627Y844971D01*
G01X1371269D02*
X1370644Y843786D01*
X1370763Y843405D01*
G02X1371587Y842395I-1342J-1936D01*
G02X1371646Y842242I-2167J-924D01*
G01Y833567D01*
X1371811Y833402D01*
Y833315D01*
G01X487088Y833205D02*
Y833292D01*
X487253Y833457D01*
Y842103D01*
G03X486528Y842887I-1474J-636D01*
G02X485402Y844196I1099J2084D01*
G01Y845027D01*
G02X486232Y846706I2225J-55D01*
G02X486299Y846758I1398J-1732D01*
G01X486394Y847109D01*
X485778Y848176D01*
G01X1363869Y844971D02*
X1363244Y843786D01*
X1363363Y843405D01*
G02X1364187Y842395I-1342J-1936D01*
G02X1364246Y842242I-2167J-924D01*
G01Y833567D01*
X1364411Y833402D01*
Y833315D01*
G01X494488Y833085D02*
Y833172D01*
X494653Y833337D01*
Y842103D01*
G03X493928Y842887I-1474J-636D01*
G02X492802Y844196I1099J2084D01*
G01Y845027D01*
G02X493632Y846706I2225J-55D01*
G02X493699Y846758I1398J-1732D01*
G01X493794Y847109D01*
X493178Y848176D01*
G01X1362021Y841467D02*
X1362646Y842652D01*
X1362979Y842755D01*
G02X1363496Y842100I-958J-1288D01*
G01Y840506D01*
X1363105Y840115D01*
Y839065D01*
X1363496Y838674D01*
Y837624D01*
X1363105Y837233D01*
Y836183D01*
X1363496Y835792D01*
Y833567D01*
X1363331Y833402D01*
Y833315D01*
G01X495568Y833085D02*
Y833172D01*
X495402Y833338D01*
Y835294D01*
X495793Y835685D01*
Y836735D01*
X495402Y837126D01*
Y838176D01*
X495793Y838567D01*
Y839617D01*
X495402Y840008D01*
Y842243D01*
G03X494277Y843550I-2223J-776D01*
G01X494278Y843551D01*
G02X493552Y844338I749J1420D01*
G01Y844971D01*
G02X494103Y846120I1475J-1D01*
G01X494411Y846038D01*
X495027Y844971D01*
G01X1365720Y848176D02*
X1366336Y847109D01*
X1366241Y846758D01*
G03X1366174Y846706I1331J-1784D01*
G03X1365344Y845027I1395J-1734D01*
G01Y844196D01*
G03X1366470Y842887I2225J775D01*
G02X1367196Y842100I-749J-1420D01*
G01X1367197Y842098D01*
Y833567D01*
X1367032Y833402D01*
Y833315D01*
G01X491868Y833275D02*
Y833362D01*
X491702Y833528D01*
Y842244D01*
X491704Y842241D01*
G03X490821Y843404I-2225J-773D01*
G01X490702Y843786D01*
X491327Y844971D01*
G01X1360169D02*
X1359553Y846038D01*
X1359245Y846120D01*
G03X1358694Y844971I924J-1150D01*
G01Y844338D01*
G03X1359420Y843551I1475J633D01*
G02X1360486Y842396I-1099J-2084D01*
G02X1360546Y842242I-2164J-932D01*
G01Y840486D01*
X1360937Y840095D01*
Y839045D01*
X1360546Y838654D01*
Y837604D01*
X1360937Y837213D01*
Y836163D01*
X1360546Y835772D01*
Y833568D01*
X1360712Y833402D01*
Y833315D01*
G01X498190Y833345D02*
Y833432D01*
X498355Y833597D01*
Y842095D01*
X498353Y842100D01*
G03X497836Y842755I-1475J-633D01*
G01X497503Y842652D01*
X496878Y841467D01*
G01X1358320Y848176D02*
X1358936Y847109D01*
X1358841Y846758D01*
G03X1358774Y846706I1331J-1784D01*
G03X1357944Y845027I1395J-1734D01*
G01Y844196D01*
G03X1359070Y842887I2225J775D01*
G02X1359796Y842100I-749J-1420D01*
G01X1359797Y842098D01*
Y833567D01*
X1359632Y833402D01*
Y833315D01*
G01X499270Y833345D02*
Y833432D01*
X499104Y833598D01*
Y842241D01*
G03X498221Y843404I-2225J-773D01*
G01X498102Y843786D01*
X498727Y844971D01*
G01X1356469D02*
X1355844Y843786D01*
X1355963Y843405D01*
G02X1356787Y842395I-1342J-1936D01*
G02X1356846Y842242I-2167J-924D01*
G01Y833567D01*
X1357011Y833402D01*
Y833315D01*
G01X501890Y833785D02*
Y833872D01*
X502055Y834037D01*
Y842098D01*
X502054Y842100D01*
G03X501328Y842887I-1475J-633D01*
G02X500202Y844196I1099J2084D01*
G01Y845027D01*
G02X501032Y846706I2225J-55D01*
G02X501099Y846758I1398J-1732D01*
G01X501194Y847109D01*
X500578Y848176D01*
G01X1352769Y844971D02*
X1352153Y846038D01*
X1351845Y846120D01*
G03X1351294Y844971I924J-1150D01*
G01Y844338D01*
G03X1352020Y843551I1475J633D01*
G02X1353086Y842396I-1099J-2084D01*
G02X1353146Y842242I-2164J-932D01*
G01Y840486D01*
X1353537Y840095D01*
Y839045D01*
X1353146Y838654D01*
Y837604D01*
X1353537Y837213D01*
Y836163D01*
X1353146Y835772D01*
Y833298D01*
X1353312Y833132D01*
Y833045D01*
G01X505589Y833745D02*
Y833832D01*
X505754Y833997D01*
Y842100D01*
G03X505237Y842755I-1475J-633D01*
G01X504904Y842652D01*
X504279Y841467D01*
G01X1350920Y848176D02*
X1351536Y847109D01*
X1351441Y846758D01*
G03X1351374Y846706I1331J-1784D01*
G03X1350544Y845027I1395J-1734D01*
G01Y844196D01*
G03X1351670Y842887I2225J775D01*
G02X1352396Y842100I-749J-1420D01*
G01X1352397Y842098D01*
Y833297D01*
X1352232Y833132D01*
Y833045D01*
G01X506669Y833745D02*
Y833832D01*
X506503Y833998D01*
Y842245D01*
X506504Y842242D01*
G03X506445Y842395I-2226J-771D01*
G03X505621Y843405I-2166J-926D01*
G01X505502Y843786D01*
X506127Y844971D01*
G01X1354621Y841467D02*
X1355246Y842652D01*
X1355579Y842755D01*
G02X1356096Y842100I-958J-1288D01*
G01Y840506D01*
X1355705Y840115D01*
Y839065D01*
X1356096Y838674D01*
Y837624D01*
X1355705Y837233D01*
Y836183D01*
X1356096Y835792D01*
Y833567D01*
X1355931Y833402D01*
Y833315D01*
G01X502970Y833785D02*
Y833872D01*
X502804Y834038D01*
Y835812D01*
X503195Y836203D01*
Y837253D01*
X502804Y837644D01*
Y838766D01*
X503195Y839157D01*
Y840207D01*
X502804Y840598D01*
Y842242D01*
G03X502744Y842396I-2224J-778D01*
G03X501678Y843551I-2165J-929D01*
G02X500952Y844338I749J1420D01*
G01Y844971D01*
G02X501503Y846120I1475J-1D01*
G01X501811Y846038D01*
X502427Y844971D01*
G01X1345369D02*
X1344753Y846038D01*
X1344445Y846120D01*
G03X1343894Y844971I924J-1150D01*
G01Y844338D01*
G03X1344620Y843551I1475J633D01*
G02X1345686Y842396I-1099J-2084D01*
G02X1345746Y842242I-2164J-932D01*
G01Y840486D01*
X1346137Y840095D01*
Y839045D01*
X1345746Y838654D01*
Y837604D01*
X1346137Y837213D01*
Y836163D01*
X1345746Y835772D01*
Y833568D01*
X1345912Y833402D01*
Y833315D01*
G01X512989Y833265D02*
Y833352D01*
X513154Y833517D01*
Y842100D01*
G03X512637Y842755I-1475J-633D01*
G01X512304Y842652D01*
X511679Y841467D01*
G01X1347221D02*
X1347846Y842652D01*
X1348179Y842755D01*
G02X1348696Y842100I-958J-1288D01*
G01Y840506D01*
X1348305Y840115D01*
Y839065D01*
X1348696Y838674D01*
Y837624D01*
X1348305Y837233D01*
Y836183D01*
X1348696Y835792D01*
Y833567D01*
X1348531Y833402D01*
Y833315D01*
G01X510370Y833745D02*
Y833832D01*
X510204Y833998D01*
Y835812D01*
X510595Y836203D01*
Y837253D01*
X510204Y837644D01*
Y838766D01*
X510595Y839157D01*
Y840207D01*
X510204Y840598D01*
Y842242D01*
G03X510144Y842396I-2224J-778D01*
G03X509078Y843551I-2165J-929D01*
G02X508352Y844338I749J1420D01*
G01Y844971D01*
G02X508903Y846120I1475J-1D01*
G01X509211Y846038D01*
X509827Y844971D01*
G01X1349069D02*
X1348444Y843786D01*
X1348563Y843405D01*
G02X1349387Y842395I-1342J-1936D01*
G02X1349446Y842242I-2167J-924D01*
G01Y833567D01*
X1349611Y833402D01*
Y833315D01*
G01X509290Y833745D02*
Y833832D01*
X509455Y833997D01*
Y842098D01*
X509454Y842100D01*
G03X508728Y842887I-1475J-633D01*
G02X507602Y844196I1099J2084D01*
G01Y845027D01*
G02X508432Y846706I2225J-55D01*
G02X508499Y846758I1398J-1732D01*
G01X508594Y847109D01*
X507978Y848176D01*
G01X1343520D02*
X1344136Y847109D01*
X1344041Y846758D01*
G03X1343974Y846706I1331J-1784D01*
G03X1343144Y845027I1395J-1734D01*
G01Y844196D01*
G03X1344270Y842887I2225J775D01*
G02X1344996Y842100I-749J-1420D01*
G01X1344997Y842098D01*
Y833567D01*
X1344832Y833402D01*
Y833315D01*
G01X514069Y833265D02*
Y833352D01*
X513903Y833518D01*
Y842245D01*
X513904Y842242D01*
G03X513845Y842395I-2226J-771D01*
G03X513021Y843405I-2166J-926D01*
G01X512902Y843786D01*
X513527Y844971D01*
G01X1339821Y841467D02*
X1340446Y842652D01*
X1340779Y842755D01*
G02X1341296Y842100I-958J-1288D01*
G01Y840506D01*
X1340905Y840115D01*
Y839065D01*
X1341296Y838674D01*
Y837624D01*
X1340905Y837233D01*
Y836183D01*
X1341296Y835792D01*
Y833957D01*
X1341131Y833792D01*
Y833705D01*
G01X527127Y830477D02*
X527066Y830538D01*
X526830D01*
X524298Y833070D01*
Y833622D01*
X523555Y834365D01*
X523003D01*
X522261Y835107D01*
Y835659D01*
X521518Y836402D01*
X520966D01*
X520224Y837144D01*
Y837696D01*
X519481Y838439D01*
X518929D01*
X517604Y839764D01*
Y842239D01*
G03X517544Y842395I-2227J-767D01*
G03X516479Y843551I-2166J-927D01*
G02X515752Y844338I748J1420D01*
G01Y844971D01*
G02X516303Y846120I1475J-1D01*
G01X516611Y846038D01*
X517227Y844971D01*
G01X1341669D02*
X1341044Y843786D01*
X1341163Y843405D01*
G02X1341987Y842395I-1342J-1936D01*
G02X1342046Y842242I-2167J-924D01*
G01Y833957D01*
X1342211Y833792D01*
Y833705D01*
G01X526363Y829713D02*
X526302Y829774D01*
Y830006D01*
X516855Y839453D01*
Y842098D01*
X516854Y842100D01*
G03X516128Y842887I-1475J-633D01*
G02X515002Y844196I1099J2084D01*
G01Y845027D01*
G02X515832Y846706I2225J-55D01*
G02X515899Y846758I1398J-1732D01*
G01X515994Y847109D01*
X515378Y848176D01*
G01X1332421Y841467D02*
X1333046Y842652D01*
X1333379Y842755D01*
G02X1333896Y842100I-958J-1288D01*
G01Y840506D01*
X1333505Y840115D01*
Y839065D01*
X1333896Y838674D01*
Y837624D01*
X1333505Y837233D01*
Y836183D01*
X1333896Y835792D01*
Y833567D01*
X1333731Y833402D01*
Y833315D01*
G01X533185Y834476D02*
X533124Y834537D01*
X532892D01*
X531033Y836396D01*
Y836949D01*
X530290Y837692D01*
X529737D01*
X528995Y838434D01*
Y838987D01*
X528252Y839731D01*
X527699D01*
X526957Y840473D01*
Y841026D01*
X526214Y841769D01*
X525661D01*
X523282Y844148D01*
G02X523151Y844464I315J316D01*
G01Y844970D01*
X523152Y844971D01*
G02X523703Y846120I1475J-1D01*
G01X524011Y846038D01*
X524627Y844971D01*
G01X1337969D02*
X1337353Y846038D01*
X1337045Y846120D01*
G03X1336494Y844971I924J-1150D01*
G01Y844338D01*
G03X1337220Y843551I1475J633D01*
G02X1338286Y842396I-1099J-2084D01*
G02X1338346Y842242I-2164J-932D01*
G01Y840486D01*
X1338737Y840095D01*
Y839045D01*
X1338346Y838654D01*
Y837604D01*
X1338737Y837213D01*
Y836163D01*
X1338346Y835772D01*
Y833568D01*
X1338512Y833402D01*
Y833315D01*
G01X529369Y831819D02*
X529308Y831880D01*
Y832112D01*
X522747Y838673D01*
X522367D01*
X520554Y840486D01*
Y842100D01*
G03X520037Y842755I-1475J-633D01*
G01X519704Y842652D01*
X519079Y841467D01*
G01X1334269Y844971D02*
X1333644Y843786D01*
X1333763Y843405D01*
G02X1334587Y842395I-1342J-1936D01*
G02X1334646Y842242I-2167J-924D01*
G01Y833567D01*
X1334811Y833402D01*
Y833315D01*
G01X532421Y833712D02*
X532360Y833773D01*
Y834009D01*
X522752Y843617D01*
Y843618D01*
G02X522402Y844465I845J845D01*
G01Y845027D01*
G02X523232Y846706I2225J-55D01*
G02X523299Y846758I1398J-1732D01*
G01X523394Y847109D01*
X522778Y848176D01*
G01X1336120D02*
X1336736Y847109D01*
X1336641Y846758D01*
G03X1336574Y846706I1331J-1784D01*
G03X1335744Y845027I1395J-1734D01*
G01Y844196D01*
G03X1336870Y842887I2225J775D01*
G02X1337596Y842100I-749J-1420D01*
G01X1337597Y842098D01*
Y833567D01*
X1337432Y833402D01*
Y833315D01*
G01X530133Y832583D02*
X530072Y832644D01*
X529836D01*
X527134Y835346D01*
Y835899D01*
X526391Y836642D01*
X525838D01*
X525096Y837384D01*
Y837937D01*
X524353Y838680D01*
X523800D01*
X523058Y839422D01*
X522678D01*
X521303Y840797D01*
Y842245D01*
X521304Y842242D01*
G03X521245Y842395I-2226J-771D01*
G03X520421Y843405I-2166J-926D01*
G01X520302Y843786D01*
X520927Y844971D01*
G01X1326869Y851380D02*
X1326253Y850313D01*
X1326348Y849962D01*
G02X1326415Y849910I-1330J-1783D01*
G02X1327245Y848176I-1395J-1733D01*
G01Y848120D01*
G02X1326132Y846248I-2225J56D01*
G03X1325395Y845005I737J-1277D01*
G01Y842424D01*
X1326836Y840983D01*
Y833568D01*
X1327002Y833402D01*
Y833315D01*
G01X536556Y839948D02*
X536495Y840009D01*
Y840245D01*
X533503Y843237D01*
Y844671D01*
G03X532952Y845820I-1475J-1D01*
G01X532644Y845738D01*
X532028Y844671D01*
G01X1330569Y844971D02*
X1329953Y846038D01*
X1329645Y846120D01*
G03X1329094Y844971I924J-1150D01*
G01X1329093Y844970D01*
Y842288D01*
X1330514Y840867D01*
Y839578D01*
X1330905Y839187D01*
Y838137D01*
X1330514Y837746D01*
Y836696D01*
X1330905Y836305D01*
Y835255D01*
X1330514Y834864D01*
Y833568D01*
X1330680Y833402D01*
Y833315D01*
G01X534445Y837049D02*
X534384Y837110D01*
Y837346D01*
X529805Y841925D01*
Y845302D01*
X529803Y845307D01*
G03X529078Y846091I-1474J-636D01*
G02X527953Y847397I1100J2085D01*
G01Y847932D01*
X527709Y848176D01*
X526478D01*
G01X1325020D02*
X1325636Y849243D01*
X1325944Y849325D01*
G02X1326495Y848176I-924J-1150D01*
G02X1325792Y846919I-1475J0D01*
G01X1325757Y846899D01*
G03X1324644Y845027I1112J-1928D01*
G01Y842115D01*
X1326087Y840672D01*
Y839622D01*
X1325696Y839231D01*
Y838181D01*
X1326087Y837790D01*
Y836740D01*
X1325696Y836349D01*
Y835299D01*
X1326087Y834908D01*
Y833567D01*
X1325922Y833402D01*
Y833315D01*
G01X537320Y840712D02*
X537259Y840773D01*
X537027D01*
X534252Y843548D01*
Y844672D01*
G03X533421Y846404I-2224J-2D01*
G01X533424Y846407D01*
G03X533358Y846458I-1394J-1736D01*
G01X533263Y846809D01*
X533878Y848176D01*
G01X1328720D02*
X1329336Y847109D01*
X1329241Y846758D01*
G03X1329174Y846706I1331J-1784D01*
G03X1328344Y845027I1395J-1734D01*
G01Y841977D01*
X1329765Y840556D01*
Y833567D01*
X1329600Y833402D01*
Y833315D01*
G01X535209Y837813D02*
X535148Y837874D01*
X534916D01*
X530554Y842236D01*
Y845450D01*
G03X530494Y845605I-2227J-773D01*
G03X529429Y846756I-2164J-934D01*
G02X528703Y847543I749J1420D01*
G01Y847932D01*
X528947Y848176D01*
X530178D01*
G01X1386071Y896240D02*
X1386687Y897307D01*
X1386995Y897389D01*
G02X1387546Y896240I-924J-1150D01*
G01Y896201D01*
G03X1388658Y894313I2225J39D01*
G02X1389395Y893070I-737J-1277D01*
G01Y893036D01*
G03X1390484Y891123I2225J0D01*
G01X1390543Y891088D01*
Y891089D01*
G02X1391246Y889832I-772J-1257D01*
G01Y889745D01*
G03X1392357Y887904I2225J87D01*
G01X1392392Y887884D01*
G02X1393094Y886685I-772J-1257D01*
G02X1393095Y886627I-1474J-54D01*
G02X1392392Y885370I-1475J0D01*
G01X1392357Y885350D01*
G03X1391246Y883484I1114J-1927D01*
G01Y883362D01*
G03X1392357Y881496I2225J61D01*
G01X1392361Y881494D01*
X1392392Y881476D01*
G02X1393095Y880219I-772J-1257D01*
G01Y880189D01*
G03X1394208Y878291I2226J30D01*
G01X1394243Y878271D01*
G02X1394946Y877014I-772J-1257D01*
G01Y876953D01*
G03X1396057Y875087I2225J61D01*
G01X1396092Y875067D01*
G02X1396795Y873810I-772J-1257D01*
G03X1397884Y871897I2225J0D01*
G01X1397905Y871885D01*
X1397908Y871883D01*
X1397914Y871880D01*
X1397943Y871863D01*
G02Y869349I-771J-1257D01*
G01X1397908Y869329D01*
G03X1396795Y867457I1112J-1928D01*
G01Y867401D01*
G03X1397884Y865488I2225J0D01*
G01X1397943Y865453D01*
Y865454D01*
G02X1398646Y864197I-772J-1257D01*
G01Y864136D01*
G03X1399757Y862270I2225J61D01*
G01X1399792Y862250D01*
G02Y859736I-773J-1257D01*
G01X1399757Y859716D01*
G03X1398646Y857850I1114J-1927D01*
G01Y857702D01*
G03X1399757Y855861I2225J87D01*
G01X1399792Y855841D01*
G02X1400495Y854584I-772J-1257D01*
G03X1401560Y852685I2226J0D01*
G01X1401608Y852657D01*
X1401643Y852637D01*
G02X1402346Y851380I-772J-1257D01*
G01Y851319D01*
G03X1403457Y849453I2225J61D01*
G03X1405625Y849419I1114J1927D01*
G01X1405683Y849453D01*
G02X1407157I737J-1277D01*
G03X1409325Y849419I1114J1927D01*
G01X1409383Y849453D01*
G02X1410857I737J-1277D01*
G03X1413025Y849419I1114J1927D01*
G01X1413083Y849453D01*
G02X1414557I737J-1277D01*
G01X1414592Y849433D01*
G02X1415295Y848176I-772J-1257D01*
G01Y848120D01*
G03X1416408Y846248I2225J56D01*
G02X1416715Y846015I-731J-1282D01*
G01X1417882Y844848D01*
Y843591D01*
X1417492Y843201D01*
Y842161D01*
X1417882Y841771D01*
Y840731D01*
X1417492Y840341D01*
Y839301D01*
X1417882Y838911D01*
Y837304D01*
X1417716Y837138D01*
Y837051D01*
G01X1387920Y899445D02*
X1387304Y898378D01*
X1387399Y898027D01*
G02X1387466Y897975I-1331J-1784D01*
G02X1388296Y896296I-1395J-1734D01*
G01Y896240D01*
G03X1388999Y894983I1475J0D01*
G01X1389034Y894963D01*
G02X1390146Y893075I-1113J-1927D01*
G01Y893002D01*
G03X1390883Y891759I1474J34D01*
G01X1390886Y891757D01*
X1390907Y891745D01*
G02X1391996Y889832I-1136J-1913D01*
G03X1391997Y889774I1475J-4D01*
G03X1392699Y888575I1474J58D01*
G01X1392730Y888557D01*
X1392734Y888555D01*
G02X1393845Y886714I-1114J-1928D01*
G01Y886566D01*
G02X1392734Y884700I-2225J61D01*
G01X1392730Y884698D01*
X1392699Y884680D01*
G03Y882166I773J-1257D01*
G01X1392734Y882146D01*
X1392758Y882132D01*
G02X1393846Y880219I-1138J-1913D01*
G03X1394549Y878962I1475J0D01*
G01X1394584Y878942D01*
G02X1395696Y877087I-1113J-1928D01*
G01Y877014D01*
G03X1396399Y875757I1475J0D01*
G01X1396434Y875737D01*
G02X1397545Y873871I-1114J-1927D01*
G01Y873810D01*
G03X1398248Y872553I1475J0D01*
G01X1398277Y872536D01*
X1398283Y872533D01*
X1398286Y872531D01*
X1398307Y872519D01*
G02X1399396Y870606I-1136J-1913D01*
G01Y870550D01*
G02X1398283Y868678I-2225J56D01*
G03X1397546Y867435I737J-1277D01*
G01Y867367D01*
G03X1398283Y866124I1474J34D01*
G01X1398286Y866122D01*
X1398307Y866110D01*
G02X1399396Y864197I-1136J-1913D01*
G03X1400099Y862940I1475J0D01*
G01X1400134Y862920D01*
G02X1401245Y861054I-1114J-1927D01*
G01Y860932D01*
G02X1400134Y859066I-2225J61D01*
G01X1400099Y859046D01*
G03X1399396Y857789I772J-1257D01*
G03X1399397Y857731I1475J-4D01*
G03X1400099Y856532I1474J58D01*
G01X1400134Y856512D01*
G02X1401246Y854640I-1114J-1928D01*
G01Y854584D01*
G03X1401949Y853327I1475J0D01*
G01X1401971Y853315D01*
X1401974Y853313D01*
X1401981Y853309D01*
X1401984Y853307D01*
G02X1403096Y851419I-1113J-1927D01*
G01Y851380D01*
G03X1403799Y850123I1475J0D01*
G01X1403834Y850103D01*
G03X1405308I737J1277D01*
G01X1405366Y850137D01*
G02X1407534Y850103I1054J-1961D01*
G03X1409008I737J1277D01*
G01X1409066Y850137D01*
G02X1411234Y850103I1054J-1961D01*
G03X1412708I737J1277D01*
G01X1412766Y850137D01*
G02X1416045Y848237I1054J-1961D01*
G01Y848176D01*
G03X1416748Y846919I1475J0D01*
G01X1416783Y846899D01*
G02X1417245Y846545I-1111J-1929D01*
G01X1418631Y845159D01*
Y838911D01*
X1418632Y838910D01*
X1418631Y838909D01*
Y837303D01*
X1418796Y837138D01*
Y837051D01*
G01X1422586Y834897D02*
Y834984D01*
X1422421Y835149D01*
Y844385D01*
G03X1422017Y845361I-1382J0D01*
G01X1420758Y846621D01*
G03X1420317Y847008I-3334J-3354D01*
G01X1420318Y847009D01*
G02X1419745Y848176I902J1167D01*
G01Y848215D01*
G03X1418633Y850103I-2225J-39D01*
G02X1417896Y851346I737J1277D01*
G01Y851419D01*
G03X1416784Y853307I-2225J-39D01*
G03X1414558I-1113J-1927D01*
G02X1413084I-737J1277D01*
G03X1410858I-1113J-1927D01*
G02X1409384I-737J1277D01*
G01X1409343Y853331D01*
G03X1407157Y853307I-1072J-1951D01*
G02X1405683I-737J1277D01*
G02X1404946Y854550I737J1277D01*
G01Y854657D01*
G03X1403834Y856512I-2225J-73D01*
G01X1403799Y856532D01*
G02X1403097Y857741I773J1257D01*
G02Y857829I1475J44D01*
G02X1403799Y859046I1475J-40D01*
G01X1403834Y859066D01*
G03X1404945Y860932I-1114J1927D01*
G01Y861054D01*
G03X1403834Y862920I-2225J-61D01*
G01X1403799Y862940D01*
G02X1403096Y864197I772J1257D01*
G01Y864236D01*
G03X1401984Y866124I-2225J-39D01*
G01X1401981Y866126D01*
X1401974Y866130D01*
X1401971Y866132D01*
X1401949Y866144D01*
G02Y868658I772J1257D01*
G01X1401984Y868678D01*
G03X1403096Y870533I-1113J1928D01*
G01Y870606D01*
G03X1402007Y872519I-2225J0D01*
G01X1401986Y872531D01*
X1401983Y872533D01*
X1401977Y872536D01*
X1401948Y872553D01*
G02X1401245Y873810I772J1257D01*
G01Y873871D01*
G03X1400134Y875737I-2225J-61D01*
G01X1400099Y875757D01*
G02X1399396Y877014I772J1257D01*
G01Y877070D01*
G03X1398283Y878942I-2225J-56D01*
G02X1397546Y880185I737J1277D01*
G01Y880258D01*
G03X1396434Y882146I-2225J-39D01*
G01X1396399Y882166D01*
G02X1395696Y883397I772J1257D01*
G02Y883463I1475J33D01*
G02X1396399Y884680I1474J-40D01*
G01X1396434Y884700D01*
G03X1397545Y886566I-1114J1927D01*
G01Y886714D01*
G03X1396434Y888555I-2225J-87D01*
G01X1396399Y888575D01*
G02X1395697Y889774I772J1257D01*
G02X1395696Y889832I1474J54D01*
G01Y889871D01*
G03X1394584Y891759I-2225J-39D01*
G01X1394581Y891761D01*
X1394574Y891765D01*
X1394571Y891767D01*
X1394549Y891779D01*
G02X1393846Y893036I772J1257D01*
G03X1392758Y894949I-2226J0D01*
G01X1392734Y894963D01*
G03X1390815Y895112I-1115J-1927D01*
G03X1390737Y895080I806J-2075D01*
G01X1390387Y895173D01*
X1389771Y896240D01*
G01X1393471D02*
X1394087Y897307D01*
X1394395Y897389D01*
G02X1394946Y896240I-924J-1150D01*
G01Y896201D01*
G03X1396058Y894313I2225J39D01*
G02X1396795Y893070I-737J-1277D01*
G01Y893036D01*
G03X1397884Y891123I2225J0D01*
G01X1397943Y891088D01*
Y891089D01*
G02X1398646Y889832I-772J-1257D01*
G01Y889745D01*
G03X1399757Y887904I2225J87D01*
G01X1399792Y887884D01*
G02X1400494Y886685I-772J-1257D01*
G02X1400495Y886627I-1474J-54D01*
G02X1399792Y885370I-1475J0D01*
G01X1399761Y885352D01*
X1399757Y885350D01*
G03X1398646Y883484I1114J-1927D01*
G01Y883362D01*
G03X1399757Y881496I2225J61D01*
G01X1399761Y881494D01*
X1399792Y881476D01*
G02X1400495Y880219I-772J-1257D01*
G01Y880189D01*
G03X1401608Y878291I2226J30D01*
G01X1401643Y878271D01*
G02X1402346Y877014I-772J-1257D01*
G01Y876953D01*
G03X1403457Y875087I2225J61D01*
G01X1403492Y875067D01*
G02X1404195Y873810I-772J-1257D01*
G03X1405284Y871897I2225J0D01*
G01X1405305Y871885D01*
X1405308Y871883D01*
X1405314Y871880D01*
X1405343Y871863D01*
G02Y869349I-771J-1257D01*
G01X1405308Y869329D01*
G03X1404195Y867457I1112J-1928D01*
G01Y867401D01*
G03X1405284Y865488I2225J0D01*
G01X1405343Y865453D01*
Y865454D01*
G02X1406046Y864197I-772J-1257D01*
G01Y864136D01*
G03X1407157Y862270I2225J61D01*
G01X1407161Y862268D01*
X1407192Y862250D01*
G02Y859736I-772J-1257D01*
G01X1407161Y859718D01*
X1407157Y859716D01*
G03X1406046Y857850I1114J-1927D01*
G01Y857702D01*
G03X1407157Y855861I2225J87D01*
G03X1409343Y855837I1114J1928D01*
G01X1409384Y855861D01*
G03X1410496Y857716I-1113J1928D01*
G01Y857789D01*
G02X1411199Y859046I1475J0D01*
G01X1411234Y859066D01*
G02X1412708I737J-1277D01*
G01X1412743Y859046D01*
G02X1413446Y857789I-772J-1257D01*
G01Y857716D01*
G03X1414558Y855861I2225J73D01*
G03X1416784I1113J1928D01*
G02X1418258I737J-1277D01*
G02X1418995Y854618I-737J-1277D01*
G01Y854545D01*
G03X1420107Y852657I2225J39D01*
G01X1420142Y852637D01*
G02X1420845Y851380I-772J-1257D01*
G01Y851341D01*
G03X1421957Y849453I2225J39D01*
G01X1421992Y849433D01*
G02X1422695Y848176I-772J-1257D01*
G01Y848137D01*
G03X1423807Y846249I2225J39D01*
G02X1424112Y846015I-738J-1277D01*
G01X1424114D01*
X1425263Y844866D01*
Y843826D01*
X1424873Y843436D01*
Y842396D01*
X1425263Y842006D01*
Y840966D01*
X1424873Y840576D01*
Y839536D01*
X1425258Y839151D01*
Y837304D01*
X1425092Y837138D01*
Y837051D01*
G01X1421506Y834897D02*
Y834984D01*
X1421672Y835150D01*
Y835684D01*
X1421282Y836074D01*
Y837114D01*
X1421672Y837504D01*
Y838544D01*
X1421282Y838934D01*
Y839974D01*
X1421672Y840364D01*
Y841404D01*
X1421282Y841794D01*
Y842834D01*
X1421672Y843224D01*
Y844384D01*
G03X1421487Y844831I-633J0D01*
G01X1420228Y846090D01*
G03X1419854Y846419I-2810J-2818D01*
G02X1418995Y848176I1366J1756D01*
G03X1418292Y849433I-1475J0D01*
G01X1418257Y849453D01*
G02X1417145Y851341I1113J1927D01*
G01Y851414D01*
G03X1416408Y852657I-1474J-34D01*
G03X1414934I-737J-1277D01*
G02X1412708I-1113J1927D01*
G03X1411234I-737J-1277D01*
G02X1409008I-1113J1927D01*
G03X1407534I-737J-1277D01*
G02X1405366Y852623I-1114J1927D01*
G01X1405308Y852657D01*
X1405284Y852671D01*
G02X1404195Y854584I1136J1913D01*
G01Y854618D01*
G03X1403458Y855861I-1474J-34D01*
G02X1402346Y857716I1113J1928D01*
G01Y857850D01*
G02X1403457Y859716I2225J-61D01*
G01X1403492Y859736D01*
G03Y862250I-773J1257D01*
G01X1403457Y862270D01*
G02X1402346Y864136I1114J1927D01*
G01Y864197D01*
G03X1401643Y865454I-1475J0D01*
G01X1401608Y865474D01*
X1401560Y865502D01*
G02X1400495Y867401I1161J1899D01*
G01Y867431D01*
G02X1401608Y869329I2226J-30D01*
G01X1401611Y869331D01*
X1401643Y869349D01*
G03Y871863I-773J1257D01*
G01X1401614Y871880D01*
X1401608Y871883D01*
X1401605Y871885D01*
X1401584Y871897D01*
G02X1400495Y873810I1136J1913D01*
G03X1399792Y875067I-1475J0D01*
G01X1399757Y875087D01*
G02X1398646Y876953I1114J1927D01*
G01Y877014D01*
G03X1397943Y878271I-1475J0D01*
G01X1397908Y878291D01*
G02X1396795Y880163I1112J1928D01*
G01Y880253D01*
G03X1396058Y881496I-1474J-34D01*
G02X1394946Y883384I1113J1927D01*
G01Y883484D01*
G02X1396057Y885350I2225J-61D01*
G01X1396092Y885370D01*
G03X1396795Y886627I-772J1257D01*
G03X1396794Y886685I-1475J4D01*
G03X1396092Y887884I-1474J-58D01*
G01X1396057Y887904D01*
G02X1394946Y889745I1114J1928D01*
G01Y889832D01*
G03X1394243Y891089I-1475J0D01*
G01X1394208Y891109D01*
X1394160Y891137D01*
G02X1393095Y893036I1161J1899D01*
G03X1392392Y894293I-1475J0D01*
G01X1392361Y894311D01*
X1392357Y894313D01*
G03X1391087Y894410I-736J-1277D01*
G01X1391004Y894103D01*
X1391620Y893036D01*
G01X1395320Y899445D02*
X1394704Y898378D01*
X1394799Y898027D01*
G02X1394866Y897975I-1331J-1784D01*
G02X1395696Y896296I-1395J-1734D01*
G01Y896240D01*
G03X1396399Y894983I1475J0D01*
G01X1396434Y894963D01*
G02X1397546Y893075I-1113J-1927D01*
G01Y893002D01*
G03X1398283Y891759I1474J34D01*
G01X1398286Y891757D01*
X1398307Y891745D01*
G02X1399396Y889832I-1136J-1913D01*
G03X1399397Y889774I1475J-4D01*
G03X1400099Y888575I1474J58D01*
G01X1400134Y888555D01*
G02X1401245Y886714I-1114J-1928D01*
G01Y886566D01*
G02X1400134Y884700I-2225J61D01*
G01X1400099Y884680D01*
G03Y882166I773J-1257D01*
G01X1400134Y882146D01*
X1400158Y882132D01*
G02X1401246Y880219I-1138J-1913D01*
G03X1401949Y878962I1475J0D01*
G01X1401984Y878942D01*
G02X1403096Y877087I-1113J-1928D01*
G01Y877014D01*
G03X1403799Y875757I1475J0D01*
G01X1403834Y875737D01*
G02X1404945Y873871I-1114J-1927D01*
G01Y873810D01*
G03X1405648Y872553I1475J0D01*
G01X1405677Y872536D01*
X1405683Y872533D01*
X1405686Y872531D01*
X1405707Y872519D01*
G02X1406796Y870606I-1136J-1913D01*
G01Y870550D01*
G02X1405683Y868678I-2225J56D01*
G03X1404946Y867435I737J-1277D01*
G01Y867367D01*
G03X1405683Y866124I1474J34D01*
G01X1405686Y866122D01*
X1405707Y866110D01*
G02X1406796Y864197I-1136J-1913D01*
G03X1407499Y862940I1475J0D01*
G01X1407534Y862920D01*
X1407558Y862906D01*
G02Y859080I-1138J-1913D01*
G01X1407534Y859066D01*
X1407499Y859046D01*
G03X1406796Y857789I772J-1257D01*
G03X1406797Y857731I1475J-4D01*
G03X1407499Y856532I1474J58D01*
G01X1407534Y856512D01*
G03X1409008I737J1277D01*
G01X1409043Y856532D01*
G03X1409746Y857789I-772J1257D01*
G01Y857828D01*
G02X1410858Y859716I2225J-39D01*
G01X1410899Y859740D01*
G02X1413085Y859716I1072J-1951D01*
G02X1414196Y857850I-1114J-1927D01*
G01Y857789D01*
G03X1414899Y856532I1475J0D01*
G01X1414934Y856512D01*
G03X1416408I737J1277D01*
G02X1418634I1113J-1928D01*
G02X1419746Y854657I-1113J-1928D01*
G01Y854550D01*
G03X1420483Y853307I1474J34D01*
G02X1421595Y851419I-1113J-1927D01*
G01Y851380D01*
G03X1422298Y850123I1475J0D01*
G01X1422333Y850103D01*
G02X1423445Y848215I-1113J-1927D01*
G01Y848176D01*
G03X1424148Y846919I1475J0D01*
G01X1424183Y846899D01*
G02X1424643Y846546I-1113J-1927D01*
G01X1426013Y845176D01*
Y839468D01*
X1426007Y839462D01*
Y837303D01*
X1426172Y837138D01*
Y837051D01*
G01X1417520Y899445D02*
X1418751D01*
X1418977Y899219D01*
G02X1418292Y898188I-1458J225D01*
G01X1418261Y898170D01*
X1418257Y898168D01*
G03X1417146Y896327I1114J-1928D01*
G01Y896201D01*
G03X1418258Y894313I2225J39D01*
G02X1418995Y893070I-737J-1277D01*
G01Y893036D01*
G03X1420084Y891123I2225J0D01*
G01X1420103Y891112D01*
X1420112Y891106D01*
X1420143Y891088D01*
Y891089D01*
G02X1420846Y889832I-772J-1257D01*
G01Y889745D01*
G03X1421957Y887904I2225J87D01*
G01X1421992Y887884D01*
G02X1422694Y886685I-772J-1257D01*
G02X1422695Y886627I-1474J-54D01*
G02X1421992Y885370I-1475J0D01*
G01X1421961Y885352D01*
X1421957Y885350D01*
G03X1420846Y883484I1114J-1927D01*
G01Y883362D01*
G03X1421957Y881496I2225J61D01*
G03X1424143Y881472I1114J1927D01*
G01X1424184Y881496D01*
G03X1425296Y883384I-1113J1927D01*
G01Y883423D01*
G02X1425999Y884680I1475J0D01*
G01X1426034Y884700D01*
G02X1427508I737J-1277D01*
G01X1427514Y884697D01*
X1427543Y884680D01*
G02X1428246Y883423I-772J-1257D01*
G01Y883384D01*
G03X1429358Y881496I2225J39D01*
G01X1429393Y881476D01*
G02X1430096Y880219I-772J-1257D01*
G01Y880146D01*
G03X1431208Y878291I2225J73D01*
G03X1433434I1113J1928D01*
G02X1434908I737J-1277D01*
G01X1434943Y878271D01*
G02X1435646Y877014I-772J-1257D01*
G01Y876953D01*
G03X1436757Y875087I2225J61D01*
G01X1436792Y875067D01*
G02X1437495Y873810I-772J-1257D01*
G03X1438584Y871897I2225J0D01*
G01X1438597Y871889D01*
X1438608Y871883D01*
X1438614Y871880D01*
X1438643Y871863D01*
G02Y869349I-772J-1257D01*
G01X1438611Y869331D01*
X1438608Y869329D01*
G03X1437495Y867431I1113J-1928D01*
G01Y867401D01*
G03X1438560Y865502I2226J0D01*
G01X1438608Y865474D01*
X1438643Y865454D01*
G02X1439346Y864197I-772J-1257D01*
G01Y864136D01*
G03X1440457Y862270I2225J61D01*
G01X1440492Y862250D01*
G02X1441195Y860993I-772J-1257D01*
G03X1442284Y859080I2225J0D01*
G01X1442338Y859049D01*
X1442335Y859051D01*
X1442343Y859046D01*
G02Y856532I-772J-1257D01*
G01X1442308Y856512D01*
G03X1441195Y854640I1112J-1928D01*
G01Y854584D01*
G03X1442284Y852671I2225J0D01*
G01X1442303Y852660D01*
X1442312Y852654D01*
X1442343Y852636D01*
Y852637D01*
G02X1443046Y851380I-772J-1257D01*
G01Y851319D01*
G03X1444157Y849453I2225J61D01*
G01X1444192Y849433D01*
G02X1444895Y848176I-772J-1257D01*
G01Y848115D01*
G03X1446006Y846249I2225J61D01*
G02X1446311Y846015I-738J-1277D01*
G01X1448647Y843679D01*
Y840669D01*
X1448257Y840279D01*
Y839239D01*
X1448647Y838849D01*
Y837809D01*
X1448257Y837419D01*
Y836379D01*
X1448647Y835989D01*
Y834949D01*
X1448257Y834559D01*
Y833519D01*
X1448647Y833129D01*
Y832068D01*
X1448481Y831902D01*
Y831815D01*
G01X1434800Y837051D02*
Y837138D01*
X1434635Y837303D01*
Y843274D01*
G03X1434231Y844250I-1382J0D01*
G01X1431264Y847217D01*
G02X1430845Y848215I1161J1074D01*
G03X1429733Y850103I-2225J-39D01*
G02X1428996Y851346I737J1277D01*
G01Y851380D01*
G03X1427907Y853293I-2225J0D01*
G01X1427883Y853307D01*
G02X1427146Y854550I737J1277D01*
G01Y854618D01*
G02X1427883Y855861I1474J-34D01*
G03X1428996Y857733I-1112J1928D01*
G01Y857828D01*
G03X1427884Y859716I-2225J-39D01*
G01X1427881Y859718D01*
X1427849Y859736D01*
G02X1427146Y860993I772J1257D01*
G01Y861032D01*
G03X1426034Y862920I-2225J-39D01*
G03X1423808I-1113J-1927D01*
G02X1422334I-737J1277D01*
G01X1422299Y862940D01*
G02X1421596Y864197I772J1257D01*
G03X1420507Y866110I-2225J0D01*
G01X1420500Y866114D01*
X1420492Y866119D01*
X1420483Y866124D01*
X1420442Y866148D01*
G03X1418258Y866124I-1071J-1951D01*
G02X1416784I-737J1277D01*
G01X1416743Y866148D01*
G03X1414557Y866124I-1072J-1951D01*
G02X1413083I-737J1277D01*
G02X1412346Y867367I737J1277D01*
G01Y867435D01*
G02X1413083Y868678I1474J-34D01*
G03X1414196Y870550I-1112J1928D01*
G01Y870645D01*
G03X1413084Y872533I-2225J-39D01*
G01X1413049Y872553D01*
G02X1412346Y873810I772J1257D01*
G01Y873849D01*
G03X1411234Y875737I-2225J-39D01*
G01X1411231Y875739D01*
X1411199Y875757D01*
G02X1410496Y877014I772J1257D01*
G01Y877087D01*
G03X1409384Y878942I-2225J-73D01*
G01X1409349Y878962D01*
G02X1408646Y880219I772J1257D01*
G03X1407558Y882132I-2226J0D01*
G01X1407534Y882146D01*
X1407499Y882166D01*
G02Y884680I773J1257D01*
G01X1407534Y884700D01*
G03X1408645Y886566I-1114J1927D01*
G01Y886714D01*
G03X1407534Y888555I-2225J-87D01*
G01X1407530Y888557D01*
X1407499Y888575D01*
G02X1406797Y889774I772J1257D01*
G02X1406796Y889832I1474J54D01*
G03X1405707Y891745I-2225J0D01*
G01X1405697Y891751D01*
X1405686Y891757D01*
X1405683Y891759D01*
G02X1404946Y893002I737J1277D01*
G01Y893075D01*
G03X1403834Y894963I-2225J-39D01*
G01X1403799Y894983D01*
G02X1403096Y896240I772J1257D01*
G01Y896296D01*
G03X1402266Y897975I-2225J-55D01*
G03X1402199Y898027I-1398J-1732D01*
G01X1402104Y898378D01*
X1402720Y899445D01*
G01X1433720Y837051D02*
Y837138D01*
X1433886Y837304D01*
Y843273D01*
G03X1433701Y843720I-633J0D01*
G01X1430724Y846696D01*
G02X1430096Y848179I1701J1595D01*
G01Y848199D01*
X1430094Y848201D01*
G03X1429392Y849433I-1475J-24D01*
G01X1429357Y849453D01*
G02X1428245Y851341I1113J1927D01*
G01Y851414D01*
G03X1427508Y852657I-1474J-34D01*
G01X1427484Y852671D01*
G02X1426395Y854584I1136J1913D01*
G01Y854640D01*
G02X1427508Y856512I2225J-56D01*
G01X1427543Y856532D01*
G03X1428246Y857752I-772J1257D01*
G03Y857815I-1475J32D01*
G03X1427543Y859046I-1475J-26D01*
G01X1427508Y859066D01*
G02X1426396Y860954I1113J1927D01*
G01Y860993D01*
G03X1425693Y862250I-1475J0D01*
G01X1425658Y862270D01*
G03X1424184I-737J-1277D01*
G01X1424143Y862246D01*
G02X1421957Y862270I-1072J1951D01*
G02X1420846Y864136I1114J1927D01*
G01Y864197D01*
G03X1420143Y865454I-1475J0D01*
G01X1420114Y865471D01*
X1420108Y865474D01*
G03X1418634I-737J-1277D01*
G02X1416408I-1113J1927D01*
G03X1414934I-737J-1277D01*
G02X1412766Y865440I-1114J1927D01*
G01X1412708Y865474D01*
X1412684Y865488D01*
G02X1411595Y867401I1136J1913D01*
G01Y867457D01*
G02X1412708Y869329I2225J-56D01*
G01X1412743Y869349D01*
G03X1413446Y870569I-772J1257D01*
G03Y870632I-1475J32D01*
G03X1412743Y871863I-1475J-26D01*
G01X1412708Y871883D01*
G02X1411596Y873771I1113J1927D01*
G01Y873810D01*
G03X1410893Y875067I-1475J0D01*
G01X1410858Y875087D01*
G02X1409746Y876975I1113J1927D01*
G01Y877014D01*
G03X1409043Y878271I-1475J0D01*
G01X1409008Y878291D01*
G02X1407895Y880189I1113J1928D01*
G01Y880219D01*
G03X1407192Y881476I-1475J0D01*
G01X1407161Y881494D01*
X1407157Y881496D01*
G02X1406046Y883362I1114J1927D01*
G01Y883484D01*
G02X1407157Y885350I2225J-61D01*
G01X1407161Y885352D01*
X1407192Y885370D01*
G03X1407895Y886627I-772J1257D01*
G03X1407894Y886685I-1475J4D01*
G03X1407192Y887884I-1474J-58D01*
G01X1407157Y887904D01*
G02X1406046Y889745I1114J1928D01*
G01Y889832D01*
G03X1405343Y891089I-1475J0D01*
G01Y891088D01*
X1405284Y891123D01*
G02X1404195Y893036I1136J1913D01*
G01Y893070D01*
G03X1403458Y894313I-1474J-34D01*
G02X1402346Y896201I1113J1927D01*
G01Y896240D01*
G03X1401795Y897389I-1475J-1D01*
G01X1401487Y897307D01*
X1400871Y896240D01*
G01X1406420Y893036D02*
X1405804Y894103D01*
X1405887Y894410D01*
G02X1407895Y893036I534J-1374D01*
G03X1408960Y891137I2226J0D01*
G01X1408997Y891115D01*
X1409003Y891112D01*
X1409008Y891109D01*
X1409043Y891089D01*
G02X1409746Y889832I-772J-1257D01*
G01Y889745D01*
G03X1410857Y887904I2225J87D01*
G01X1410892Y887884D01*
G02X1411593Y886685I-773J-1256D01*
G02X1411594Y886587I-1474J-64D01*
G02X1410892Y885370I-1475J40D01*
G01X1410857Y885350D01*
G03X1410858Y881496I1114J-1927D01*
G02X1411595Y880253I-737J-1277D01*
G01Y880163D01*
G03X1412708Y878291I2225J56D01*
G01X1412743Y878271D01*
G02X1413446Y877014I-772J-1257D01*
G01Y876975D01*
G03X1414558Y875087I2225J39D01*
G02X1415295Y873844I-737J-1277D01*
G01Y873810D01*
G03X1416384Y871897I2225J0D01*
G01X1416414Y871880D01*
X1416443Y871863D01*
G02X1417146Y870606I-772J-1257D01*
G01Y870533D01*
G03X1421596Y870550I2225J73D01*
G01Y870606D01*
G02X1423843Y869349I1475J0D01*
G01X1423808Y869329D01*
G03X1422695Y867401I1113J-1928D01*
G03X1426034Y865474I2226J0D01*
G02X1427508I737J-1277D01*
G01X1427514Y865471D01*
X1427543Y865454D01*
G02X1428246Y864197I-772J-1257D01*
G01Y864158D01*
G03X1429358Y862270I2225J39D01*
G02X1430095Y861027I-737J-1277D01*
G01Y860993D01*
G03X1431184Y859080I2225J0D01*
G01X1431214Y859063D01*
X1431243Y859046D01*
G02Y856532I-773J-1257D01*
G01X1431208Y856512D01*
G03X1430095Y854584I1113J-1928D01*
G03X1431183Y852671I2226J0D01*
G01X1431242Y852637D01*
G02X1431945Y851380I-772J-1257D01*
G03X1432996Y849490I2225J0D01*
G01X1433059Y849453D01*
G02X1433796Y848210I-737J-1277D01*
G01Y847908D01*
X1433797Y847906D01*
G03X1434280Y846739I1650J-1D01*
G01X1437420Y843599D01*
Y841378D01*
X1437030Y840988D01*
Y839948D01*
X1437420Y839558D01*
Y838518D01*
X1437030Y838128D01*
Y837088D01*
X1437420Y836698D01*
Y835658D01*
X1437030Y835268D01*
Y834228D01*
X1437420Y833838D01*
Y830895D01*
X1437254Y830729D01*
Y830642D01*
G01X1430472Y833045D02*
Y833132D01*
X1430307Y833297D01*
Y844413D01*
X1427690Y847030D01*
X1427668Y847050D01*
G02X1427145Y848150I952J1127D01*
G01X1427146Y848176D01*
Y848237D01*
G03X1426034Y850103I-2224J-61D01*
G01X1425999Y850123D01*
G02X1425296Y851380I772J1257D01*
G03X1424208Y853293I-2226J0D01*
G01X1424149Y853327D01*
G02Y855841I772J1257D01*
G01X1424181Y855859D01*
X1424184Y855861D01*
G03X1425296Y857787I-1112J1926D01*
G01Y857828D01*
G03X1421957Y859716I-2226J-39D01*
G02X1420483I-737J1277D01*
G01X1420477Y859719D01*
X1420448Y859736D01*
G02X1419745Y860993I772J1257D01*
G01Y861054D01*
G03X1418634Y862920I-2225J-61D01*
G03X1416466Y862954I-1114J-1927D01*
G01X1416408Y862920D01*
G02X1414934I-737J1277D01*
G01X1414854Y862966D01*
X1414832Y862978D01*
G03X1412751Y862945I-1011J-1882D01*
G01X1412708Y862920D01*
G02X1411261Y862905I-737J1277D01*
G02X1410496Y864197I709J1292D01*
G01Y864236D01*
G03X1409384Y866124I-2225J-39D01*
G01X1409381Y866126D01*
X1409371Y866132D01*
X1409349Y866144D01*
G02Y868658I772J1257D01*
G01X1409384Y868678D01*
G03X1410496Y870534I-1112J1928D01*
G03X1410497Y870646I-2224J76D01*
G03X1409384Y872533I-2225J-41D01*
G01X1409378Y872537D01*
X1409370Y872541D01*
X1409358Y872548D01*
X1409349Y872553D01*
G02X1408646Y873810I772J1257D01*
G03X1407558Y875723I-2226J0D01*
G01X1407543Y875732D01*
X1407536Y875736D01*
X1407499Y875757D01*
G02X1406796Y877014I772J1257D01*
G01Y877070D01*
G03X1405683Y878942I-2225J-56D01*
G02X1404946Y880185I737J1277D01*
G01Y880258D01*
G03X1403834Y882146I-2225J-39D01*
G01X1403799Y882166D01*
G02X1403096Y883397I772J1257D01*
G02Y883463I1475J33D01*
G02X1403799Y884680I1474J-40D01*
G01X1403834Y884700D01*
G03X1404945Y886566I-1114J1927D01*
G01Y886714D01*
G03X1403834Y888555I-2225J-87D01*
G01X1403830Y888557D01*
X1403799Y888575D01*
G02X1403097Y889774I772J1257D01*
G02X1403096Y889832I1474J54D01*
G01Y889871D01*
G03X1401984Y891759I-2225J-39D01*
G01X1401981Y891761D01*
X1401971Y891767D01*
X1401949Y891779D01*
G02X1401246Y893036I772J1257D01*
G03X1400158Y894949I-2226J0D01*
G03X1398215Y895112I-1139J-1913D01*
G03X1398137Y895080I806J-2075D01*
G01X1397787Y895173D01*
X1397171Y896240D01*
G01X1429392Y833045D02*
Y833132D01*
X1429558Y833298D01*
Y834969D01*
X1429168Y835359D01*
Y836399D01*
X1429558Y836789D01*
Y837829D01*
X1429168Y838219D01*
Y839259D01*
X1429558Y839649D01*
Y840809D01*
X1429168Y841199D01*
Y842239D01*
X1429558Y842629D01*
Y844102D01*
X1427182Y846478D01*
G02X1426396Y848137I1438J1697D01*
G01Y848210D01*
G03X1425659Y849453I-1474J-34D01*
G01X1425596Y849490D01*
G02X1424545Y851380I1174J1890D01*
G03X1423842Y852637I-1475J0D01*
G01X1423807Y852657D01*
X1423783Y852671D01*
G02X1422695Y854584I1138J1913D01*
G01Y854614D01*
G02X1423808Y856512I2226J-30D01*
G01X1423843Y856532D01*
G03Y859046I-772J1257D01*
G01X1423808Y859066D01*
G03X1422334I-737J-1277D01*
G02X1420166Y859032I-1114J1927D01*
G01X1420108Y859066D01*
X1420099Y859071D01*
X1420091Y859076D01*
X1420084Y859080D01*
G02X1418995Y860993I1136J1913D01*
G03X1418292Y862250I-1475J0D01*
G01X1418257Y862270D01*
G03X1416783I-737J-1277D01*
G02X1414559I-1112J1927D01*
G01X1414478Y862317D01*
X1414470Y862321D01*
G03X1413127Y862297I-650J-1226D01*
G01X1413084Y862271D01*
G02X1410900Y862248I-1112J1926D01*
G02X1410859Y862271I1067J1951D01*
G01X1410858Y862270D01*
G02X1409746Y864158I1113J1927D01*
G01Y864197D01*
G03X1409043Y865454I-1475J0D01*
G01X1409008Y865474D01*
X1408993Y865483D01*
X1408960Y865502D01*
G02X1407895Y867401I1161J1899D01*
G01Y867431D01*
G02X1409008Y869329I2226J-30D01*
G01X1409011Y869331D01*
X1409043Y869349D01*
G03X1409745Y870558I-772J1257D01*
G03X1409746Y870632I-1474J57D01*
G03X1409043Y871863I-1475J-26D01*
G01X1409008Y871883D01*
X1408998Y871888D01*
X1408972Y871904D01*
X1408960Y871911D01*
G02X1407895Y873810I1161J1899D01*
G03X1407192Y875067I-1475J0D01*
G01X1407161Y875085D01*
X1407157Y875087D01*
G02X1406046Y876953I1114J1927D01*
G01Y877014D01*
G03X1405343Y878271I-1475J0D01*
G01X1405308Y878291D01*
G02X1404195Y880163I1112J1928D01*
G01Y880253D01*
G03X1403458Y881496I-1474J-34D01*
G02X1402346Y883384I1113J1927D01*
G01Y883484D01*
G02X1403457Y885350I2225J-61D01*
G01X1403492Y885370D01*
G03X1404195Y886627I-772J1257D01*
G03X1404194Y886685I-1475J4D01*
G03X1403492Y887884I-1474J-58D01*
G01X1403457Y887904D01*
G02X1402346Y889745I1114J1928D01*
G01Y889832D01*
G03X1401643Y891089I-1475J0D01*
G01X1401611Y891107D01*
X1401608Y891109D01*
X1401593Y891118D01*
X1401560Y891137D01*
G02X1400495Y893036I1161J1899D01*
G03X1399792Y894293I-1475J0D01*
G01X1399761Y894311D01*
X1399757Y894313D01*
G03X1398487Y894410I-736J-1277D01*
G01X1398404Y894103D01*
X1399020Y893036D01*
G01X1421220Y899445D02*
X1419989D01*
X1419732Y899188D01*
G02X1419721Y899104I-2213J247D01*
G02X1418634Y897517I-2200J341D01*
G01X1418599Y897497D01*
G03X1417897Y896298I772J-1257D01*
G03X1417896Y896240I1474J-54D01*
G03X1418599Y894983I1475J0D01*
G01X1418634Y894963D01*
G02X1419746Y893075I-1113J-1927D01*
G01Y893002D01*
G03X1420483Y891759I1474J34D01*
G01X1420486Y891757D01*
X1420497Y891751D01*
X1420507Y891745D01*
G02X1421596Y889832I-1136J-1913D01*
G03X1421597Y889774I1475J-4D01*
G03X1422299Y888575I1474J58D01*
G01X1422334Y888555D01*
G02X1423445Y886714I-1114J-1928D01*
G01Y886566D01*
G02X1422334Y884700I-2225J61D01*
G01X1422299Y884680D01*
G03Y882166I773J-1257D01*
G01X1422334Y882146D01*
G03X1423808I737J1277D01*
G01X1423843Y882166D01*
G03X1424546Y883423I-772J1257D01*
G01Y883484D01*
G02X1425657Y885350I2225J-61D01*
G02X1427825Y885384I1114J-1927D01*
G01X1427907Y885336D01*
G02X1428996Y883423I-1136J-1913D01*
G03X1429699Y882166I1475J0D01*
G01X1429734Y882146D01*
G02X1430846Y880258I-1113J-1927D01*
G01Y880219D01*
G03X1431549Y878962I1475J0D01*
G01X1431584Y878942D01*
G03X1433058I737J1277D01*
G02X1435242Y878966I1113J-1928D01*
G01X1435283Y878942D01*
G02X1436396Y877070I-1112J-1928D01*
G01Y877014D01*
G03X1437099Y875757I1475J0D01*
G01X1437134Y875737D01*
G02X1438245Y873871I-1114J-1927D01*
G01Y873810D01*
G03X1438948Y872553I1475J0D01*
G01X1438977Y872536D01*
X1438983Y872533D01*
X1438986Y872531D01*
X1439007Y872519D01*
G02X1440096Y870606I-1136J-1913D01*
G01Y870533D01*
G02X1438984Y868678I-2225J73D01*
G01X1438949Y868658D01*
G03Y866144I772J-1257D01*
G01X1438981Y866126D01*
X1438984Y866124D01*
G02X1440096Y864236I-1113J-1927D01*
G01Y864197D01*
G03X1440799Y862940I1475J0D01*
G01X1440834Y862920D01*
G02X1441945Y861054I-1114J-1927D01*
G01Y860993D01*
G03X1442648Y859736I1475J0D01*
G01X1442683Y859716D01*
X1442707Y859702D01*
G02X1443796Y857789I-1136J-1913D01*
G01Y857733D01*
G02X1442683Y855861I-2225J56D01*
G03X1441946Y854618I737J-1277D01*
G01Y854550D01*
G03X1442683Y853307I1474J34D01*
G01X1442686Y853305D01*
X1442697Y853299D01*
X1442707Y853293D01*
G02X1443796Y851380I-1136J-1913D01*
G03X1444499Y850123I1475J0D01*
G01X1444534Y850103D01*
G02X1445645Y848237I-1114J-1927D01*
G01Y848176D01*
G03X1446348Y846919I1475J0D01*
G01X1446381Y846901D01*
X1446380Y846898D01*
G02X1446841Y846545I-1110J-1927D01*
G01X1449396Y843990D01*
Y832067D01*
X1449561Y831902D01*
Y831815D01*
G01X1419371Y896240D02*
X1419987Y895173D01*
X1420337Y895080D01*
G02X1420415Y895112I884J-2043D01*
G02X1422334Y894963I804J-2076D01*
G01X1422358Y894949D01*
G02X1423446Y893036I-1138J-1913D01*
G03X1424149Y891779I1475J0D01*
G01X1424181Y891761D01*
X1424184Y891759D01*
G02X1425296Y889871I-1113J-1927D01*
G01Y889832D01*
G03X1425297Y889774I1475J-4D01*
G03X1425999Y888575I1474J58D01*
G01X1426034Y888555D01*
G03X1427508I737J1277D01*
G01X1427566Y888589D01*
G02X1429734Y888555I1053J-1962D01*
G03X1431208I737J1277D01*
G01X1431266Y888589D01*
G02X1433434Y888555I1053J-1962D01*
G02X1434545Y886714I-1114J-1928D01*
G01Y886627D01*
G03X1435248Y885370I1475J0D01*
G01X1435283Y885350D01*
X1435307Y885336D01*
G02X1436396Y883423I-1136J-1913D01*
G03X1437099Y882166I1475J0D01*
G01X1437134Y882146D01*
X1437158Y882132D01*
G02X1438246Y880219I-1138J-1913D01*
G03X1438949Y878962I1475J0D01*
G01X1438984Y878942D01*
G02X1440096Y877087I-1113J-1928D01*
G01Y877014D01*
G03X1440799Y875757I1475J0D01*
G01X1440834Y875737D01*
G02X1441945Y873871I-1114J-1927D01*
G01Y873810D01*
G03X1442648Y872553I1475J0D01*
G01X1442683Y872533D01*
X1442707Y872519D01*
G02X1443796Y870606I-1136J-1913D01*
G01Y870550D01*
G02X1442683Y868678I-2225J56D01*
G03X1441946Y867435I737J-1277D01*
G01Y867367D01*
G03X1442683Y866124I1474J34D01*
G01X1442686Y866122D01*
X1442697Y866116D01*
X1442707Y866110D01*
G02X1443796Y864197I-1136J-1913D01*
G03X1444499Y862940I1475J0D01*
G01X1444534Y862920D01*
G02X1445645Y861054I-1114J-1927D01*
G01Y860993D01*
G03X1446348Y859736I1475J0D01*
G01X1446383Y859716D01*
X1446407Y859702D01*
G02X1447496Y857789I-1136J-1913D01*
G01Y857716D01*
G02X1446384Y855861I-2225J73D01*
G01X1446349Y855841D01*
G03Y853327I772J-1257D01*
G01X1446384Y853307D01*
G02X1447496Y851419I-1113J-1927D01*
G01Y851380D01*
G03X1448199Y850123I1475J0D01*
G01X1448234Y850103D01*
G02X1449346Y848215I-1113J-1927D01*
G01Y848142D01*
G03X1450083Y846899I1474J34D01*
G01X1450082Y846898D01*
G02X1450544Y846544I-1110J-1928D01*
G01X1452968Y844120D01*
Y833697D01*
X1453133Y833532D01*
Y833445D01*
G01X1421220Y893036D02*
X1420604Y894103D01*
X1420687Y894410D01*
G02X1421957Y894313I534J-1374D01*
G01X1421961Y894311D01*
X1421992Y894293D01*
G02X1422695Y893036I-772J-1257D01*
G03X1423760Y891137I2226J0D01*
G01X1423808Y891109D01*
X1423843Y891089D01*
G02X1424546Y889832I-772J-1257D01*
G01Y889745D01*
G03X1425657Y887904I2225J87D01*
G03X1427825Y887870I1115J1928D01*
G01X1427883Y887904D01*
G02X1429357I737J-1277D01*
G03X1431525Y887870I1115J1928D01*
G01X1431583Y887904D01*
G02X1433057I737J-1277D01*
G01X1433092Y887884D01*
G02X1433794Y886685I-772J-1257D01*
G02X1433795Y886627I-1474J-54D01*
G03X1434884Y884714I2225J0D01*
G01X1434938Y884683D01*
X1434935Y884685D01*
X1434943Y884680D01*
G02X1435646Y883423I-772J-1257D01*
G01Y883362D01*
G03X1436757Y881496I2225J61D01*
G01X1436761Y881494D01*
X1436792Y881476D01*
G02X1437495Y880219I-772J-1257D01*
G01Y880189D01*
G03X1438608Y878291I2226J30D01*
G01X1438643Y878271D01*
G02X1439346Y877014I-772J-1257D01*
G01Y876953D01*
G03X1440457Y875087I2225J61D01*
G01X1440492Y875067D01*
G02X1441195Y873810I-772J-1257D01*
G03X1442284Y871897I2225J0D01*
G01X1442338Y871866D01*
X1442335Y871868D01*
X1442343Y871863D01*
G02Y869349I-772J-1257D01*
G01X1442308Y869329D01*
G03X1441195Y867457I1112J-1928D01*
G01Y867401D01*
G03X1442284Y865488I2225J0D01*
G01X1442303Y865477D01*
X1442312Y865471D01*
X1442343Y865453D01*
Y865454D01*
G02X1443046Y864197I-772J-1257D01*
G01Y864136D01*
G03X1444157Y862270I2225J61D01*
G01X1444192Y862250D01*
G02X1444895Y860993I-772J-1257D01*
G03X1445984Y859080I2225J0D01*
G01X1446038Y859049D01*
X1446035Y859051D01*
X1446043Y859046D01*
G02Y856532I-772J-1257D01*
G01X1446011Y856514D01*
X1446008Y856512D01*
G03X1444895Y854614I1113J-1928D01*
G01Y854584D01*
G03X1445960Y852685I2226J0D01*
G01X1446043Y852637D01*
G02X1446746Y851380I-772J-1257D01*
G01Y851341D01*
G03X1447858Y849453I2225J39D01*
G02X1448595Y848210I-737J-1277D01*
G01Y848176D01*
G03X1449684Y846263I2225J0D01*
G01X1449708Y846249D01*
G02X1450014Y846014I-738J-1277D01*
G01X1452219Y843809D01*
Y841841D01*
X1451829Y841451D01*
Y840411D01*
X1452219Y840021D01*
Y838872D01*
X1451829Y838482D01*
Y837442D01*
X1452219Y837052D01*
Y833698D01*
X1452053Y833532D01*
Y833445D01*
G01X1404571Y896240D02*
X1405187Y895173D01*
X1405537Y895080D01*
G02X1405615Y895112I884J-2043D01*
G02X1407558Y894949I804J-2076D01*
G02X1408646Y893036I-1138J-1913D01*
G03X1409349Y891779I1475J0D01*
G01X1409374Y891765D01*
X1409381Y891761D01*
X1409384Y891759D01*
G02X1410496Y889871I-1113J-1927D01*
G01Y889832D01*
G03X1410497Y889774I1475J-4D01*
G03X1411199Y888575I1474J58D01*
G01X1411234Y888555D01*
G02X1412345Y886714I-1114J-1928D01*
G01Y886566D01*
G02X1411234Y884700I-2225J61D01*
G01X1411199Y884680D01*
G03Y882166I771J-1257D01*
G01X1411234Y882146D01*
G02X1412346Y880258I-1113J-1927D01*
G01Y880185D01*
G03X1413083Y878942I1474J34D01*
G02X1414196Y877070I-1112J-1928D01*
G01Y877014D01*
G03X1414899Y875757I1475J0D01*
G01X1414934Y875737D01*
G02X1416046Y873849I-1113J-1927D01*
G01Y873776D01*
G03X1416783Y872533I1474J34D01*
G01X1416786Y872531D01*
X1416807Y872519D01*
G02X1417896Y870606I-1136J-1913D01*
G03X1420846I1475J0D01*
G01Y870667D01*
G02X1424184Y868678I2225J-61D01*
G01X1424181Y868676D01*
X1424149Y868658D01*
G03Y866144I772J-1257D01*
G01X1424184Y866124D01*
G03X1425658I737J1277D01*
G02X1427842Y866148I1113J-1927D01*
G01X1427886Y866122D01*
X1427907Y866110D01*
G02X1428996Y864197I-1136J-1913D01*
G03X1429699Y862940I1475J0D01*
G01X1429734Y862920D01*
G02X1430846Y861032I-1113J-1927D01*
G01Y860959D01*
G03X1431583Y859716I1474J34D01*
G01X1431586Y859714D01*
X1431607Y859702D01*
G02X1431584Y855861I-1135J-1914D01*
G01X1431581Y855859D01*
X1431549Y855841D01*
G03Y853327I772J-1257D01*
G01X1431608Y853293D01*
G02X1432696Y851380I-1138J-1913D01*
G03X1433399Y850123I1475J0D01*
G01X1433434Y850103D01*
G02X1434546Y848237I-1112J-1927D01*
G01Y847906D01*
G03X1434810Y847269I901J0D01*
G01X1438169Y843910D01*
Y830894D01*
X1438334Y830729D01*
Y830642D01*
G01X1410120Y899445D02*
X1409504Y898378D01*
X1409599Y898027D01*
G02X1409666Y897975I-1331J-1784D01*
G02X1410496Y896296I-1395J-1734D01*
G01Y896240D01*
G03X1411199Y894983I1475J0D01*
G01X1411234Y894963D01*
G02X1412346Y893075I-1113J-1927D01*
G01Y893002D01*
G03X1413083Y891759I1474J34D01*
G01X1413086Y891757D01*
X1413107Y891745D01*
G02X1414196Y889832I-1136J-1913D01*
G03X1414197Y889774I1475J-4D01*
G03X1414899Y888575I1474J58D01*
G01X1414930Y888557D01*
X1414934Y888555D01*
G02X1416045Y886714I-1114J-1928D01*
G01Y886566D01*
G02X1414934Y884700I-2225J61D01*
G01X1414899Y884680D01*
G03Y882166I773J-1257D01*
G01X1414934Y882146D01*
X1414958Y882132D01*
G02X1416046Y880219I-1138J-1913D01*
G03X1416749Y878962I1475J0D01*
G01X1416784Y878942D01*
G02X1417896Y877087I-1113J-1928D01*
G01Y877014D01*
G03X1418599Y875757I1475J0D01*
G01X1418634Y875737D01*
G03X1420108I737J1277D01*
G01X1420166Y875771D01*
G02X1422334Y875737I1054J-1961D01*
G03X1423808I737J1277D01*
G02X1426034I1113J-1927D01*
G02X1427146Y873849I-1113J-1927D01*
G01Y873810D01*
G03X1427849Y872553I1475J0D01*
G01X1427884Y872533D01*
G03X1429358I737J1277D01*
G02X1431542Y872557I1113J-1927D01*
G01X1431607Y872519D01*
G02X1432696Y870606I-1136J-1913D01*
G01Y870533D01*
G02X1431584Y868678I-2225J73D01*
G01X1431581Y868676D01*
X1431549Y868658D01*
G03Y866144I772J-1257D01*
G01X1431571Y866132D01*
X1431581Y866126D01*
X1431584Y866124D01*
G02X1432696Y864236I-1113J-1927D01*
G01Y864197D01*
G03X1433399Y862940I1475J0D01*
G01X1433434Y862920D01*
G02X1434545Y861054I-1114J-1927D01*
G01Y860993D01*
G03X1435248Y859736I1475J0D01*
G01X1435277Y859719D01*
X1435283Y859716D01*
X1435286Y859714D01*
X1435307Y859702D01*
G02X1436396Y857789I-1136J-1913D01*
G01Y857733D01*
G02X1435283Y855861I-2225J56D01*
G03X1434546Y854618I737J-1277D01*
G01Y854550D01*
G03X1435283Y853307I1474J34D01*
G01X1435286Y853305D01*
X1435307Y853293D01*
G02X1436396Y851380I-1136J-1913D01*
G03X1437099Y850123I1475J0D01*
G01X1437134Y850103D01*
G02X1438245Y848237I-1114J-1927D01*
G01Y848176D01*
G03X1438948Y846919I1475J0D01*
G01X1438983Y846899D01*
G02X1439442Y846546I-1116J-1926D01*
G01X1442077Y843908D01*
Y833287D01*
X1442242Y833122D01*
Y833035D01*
G01X1413820Y893036D02*
X1413204Y894103D01*
X1413287Y894410D01*
G02X1414557Y894313I534J-1374D01*
G01X1414561Y894311D01*
X1414592Y894293D01*
G02X1415295Y893036I-772J-1257D01*
G03X1416360Y891137I2226J0D01*
G01X1416408Y891109D01*
X1416443Y891089D01*
G02X1417146Y889832I-772J-1257D01*
G01Y889745D01*
G03X1418257Y887904I2225J87D01*
G01X1418292Y887884D01*
G02X1418994Y886685I-772J-1257D01*
G02X1418995Y886627I-1474J-54D01*
G02X1418292Y885370I-1475J0D01*
G01X1418257Y885350D01*
G03X1417146Y883484I1114J-1927D01*
G01Y883384D01*
G03X1418258Y881496I2225J39D01*
G02X1418995Y880253I-737J-1277D01*
G01Y880163D01*
G03X1420108Y878291I2225J56D01*
G01X1420166Y878257D01*
G03X1422334Y878291I1053J1962D01*
G02X1423808I737J-1277D01*
G03X1426034I1113J1928D01*
G02X1427508I737J-1277D01*
G01X1427543Y878271D01*
G02X1428246Y877014I-772J-1257D01*
G01Y876975D01*
G03X1429358Y875087I2225J39D01*
G03X1431542Y875063I1113J1927D01*
G01X1431583Y875087D01*
G02X1433057I737J-1277D01*
G01X1433092Y875067D01*
G02X1433795Y873810I-772J-1257D01*
G03X1434884Y871897I2225J0D01*
G01X1434908Y871883D01*
X1434943Y871863D01*
G02Y869349I-771J-1257D01*
G01X1434908Y869329D01*
G03X1433795Y867457I1112J-1928D01*
G01Y867401D01*
G03X1434884Y865488I2225J0D01*
G01X1434943Y865453D01*
Y865454D01*
G02X1435646Y864197I-772J-1257D01*
G01Y864136D01*
G03X1436757Y862270I2225J61D01*
G01X1436792Y862250D01*
G02X1437495Y860993I-772J-1257D01*
G03X1438584Y859080I2225J0D01*
G01X1438608Y859066D01*
X1438643Y859046D01*
G02Y856532I-773J-1257D01*
G01X1438611Y856514D01*
X1438608Y856512D01*
G03X1437495Y854614I1113J-1928D01*
G01Y854584D01*
G03X1438560Y852685I2226J0D01*
G01X1438608Y852657D01*
X1438643Y852637D01*
G02X1439346Y851380I-772J-1257D01*
G01Y851341D01*
G03X1440458Y849453I2225J39D01*
G02X1441195Y848210I-737J-1277D01*
G01Y848176D01*
G03X1442284Y846263I2225J0D01*
G01X1442308Y846249D01*
G02X1442399Y846193I-728J-1284D01*
G02X1442615Y846015I-827J-1223D01*
G01X1444865Y843765D01*
Y838973D01*
X1444475Y838583D01*
Y837543D01*
X1444865Y837153D01*
Y836113D01*
X1444475Y835723D01*
Y834683D01*
X1444865Y834293D01*
Y832737D01*
X1444700Y832572D01*
Y832485D01*
G01X1408271Y896240D02*
X1408887Y897307D01*
X1409195Y897389D01*
G02X1409746Y896240I-924J-1150D01*
G01Y896201D01*
G03X1410858Y894313I2225J39D01*
G02X1411595Y893070I-737J-1277D01*
G01Y893036D01*
G03X1412684Y891123I2225J0D01*
G01X1412743Y891088D01*
Y891089D01*
G02X1413446Y889832I-772J-1257D01*
G01Y889745D01*
G03X1414557Y887904I2225J87D01*
G01X1414592Y887884D01*
G02X1415294Y886685I-772J-1257D01*
G02X1415295Y886627I-1474J-54D01*
G02X1414592Y885370I-1475J0D01*
G01X1414561Y885352D01*
X1414557Y885350D01*
G03X1413446Y883484I1114J-1927D01*
G01Y883362D01*
G03X1414557Y881496I2225J61D01*
G01X1414561Y881494D01*
X1414592Y881476D01*
G02X1415295Y880219I-772J-1257D01*
G01Y880189D01*
G03X1416408Y878291I2226J30D01*
G01X1416443Y878271D01*
G02X1417146Y877014I-772J-1257D01*
G01Y876953D01*
G03X1418257Y875087I2225J61D01*
G03X1420425Y875053I1114J1927D01*
G01X1420483Y875087D01*
G02X1421957I737J-1277D01*
G03X1424143Y875063I1114J1927D01*
G01X1424184Y875087D01*
G02X1425658I737J-1277D01*
G01X1425693Y875067D01*
G02X1426396Y873810I-772J-1257D01*
G01Y873771D01*
G03X1427508Y871883I2225J39D01*
G03X1429734I1113J1927D01*
G02X1431208I737J-1277D01*
G01X1431214Y871880D01*
X1431243Y871863D01*
G02Y869349I-773J-1257D01*
G01X1431208Y869329D01*
G03X1430095Y867431I1113J-1928D01*
G01Y867401D01*
G03X1431160Y865502I2226J0D01*
G01X1431193Y865483D01*
X1431208Y865474D01*
X1431243Y865454D01*
G02X1431946Y864197I-772J-1257D01*
G01Y864136D01*
G03X1433057Y862270I2225J61D01*
G01X1433092Y862250D01*
G02X1433795Y860993I-772J-1257D01*
G03X1434884Y859080I2225J0D01*
G01X1434905Y859068D01*
X1434908Y859066D01*
X1434914Y859063D01*
X1434943Y859046D01*
G02Y856532I-771J-1257D01*
G01X1434908Y856512D01*
G03X1433795Y854640I1112J-1928D01*
G01Y854584D01*
G03X1434884Y852671I2225J0D01*
G01X1434943Y852636D01*
Y852637D01*
G02X1435646Y851380I-772J-1257D01*
G01Y851319D01*
G03X1436757Y849453I2225J61D01*
G01X1436792Y849433D01*
G02X1437495Y848176I-772J-1257D01*
G01Y848115D01*
G03X1438606Y846249I2225J61D01*
G02X1438911Y846015I-738J-1277D01*
G01X1438912D01*
X1441328Y843598D01*
Y840752D01*
X1440938Y840362D01*
Y839322D01*
X1441328Y838932D01*
Y837892D01*
X1440938Y837502D01*
Y836462D01*
X1441328Y836072D01*
Y833288D01*
X1441162Y833122D01*
Y833035D01*
G01X1411971Y896240D02*
X1412587Y895173D01*
X1412937Y895080D01*
G02X1413015Y895112I884J-2043D01*
G02X1414934Y894963I804J-2076D01*
G01X1414958Y894949D01*
G02X1416046Y893036I-1138J-1913D01*
G03X1416749Y891779I1475J0D01*
G01X1416771Y891767D01*
X1416774Y891765D01*
X1416781Y891761D01*
X1416784Y891759D01*
G02X1417896Y889871I-1113J-1927D01*
G01Y889832D01*
G03X1417897Y889774I1475J-4D01*
G03X1418599Y888575I1474J58D01*
G01X1418634Y888555D01*
G02X1419745Y886714I-1114J-1928D01*
G01Y886566D01*
G02X1418634Y884700I-2225J61D01*
G01X1418599Y884680D01*
G03X1417896Y883463I771J-1257D01*
G03Y883397I1474J-33D01*
G03X1418599Y882166I1474J26D01*
G01X1418634Y882146D01*
G02X1419746Y880258I-1113J-1927D01*
G01Y880185D01*
G03X1420483Y878942I1474J34D01*
G03X1421957I737J1277D01*
G02X1424143Y878966I1114J-1928D01*
G01X1424184Y878942D01*
G03X1425658I737J1277D01*
G02X1427884I1113J-1928D01*
G02X1428996Y877087I-1113J-1928D01*
G01Y877014D01*
G03X1429699Y875757I1475J0D01*
G01X1429734Y875737D01*
G03X1431208I737J1277D01*
G01X1431266Y875771D01*
G02X1433434Y875737I1054J-1961D01*
G02X1434545Y873871I-1114J-1927D01*
G01Y873810D01*
G03X1435248Y872553I1475J0D01*
G01X1435283Y872533D01*
X1435307Y872519D01*
G02X1436396Y870606I-1136J-1913D01*
G01Y870550D01*
G02X1435283Y868678I-2225J56D01*
G03X1434546Y867435I737J-1277D01*
G01Y867367D01*
G03X1435283Y866124I1474J34D01*
G01X1435286Y866122D01*
X1435307Y866110D01*
G02X1436396Y864197I-1136J-1913D01*
G03X1437099Y862940I1475J0D01*
G01X1437134Y862920D01*
G02X1438245Y861054I-1114J-1927D01*
G01Y860993D01*
G03X1438948Y859736I1475J0D01*
G01X1438983Y859716D01*
X1439007Y859702D01*
G02X1440096Y857789I-1136J-1913D01*
G01Y857716D01*
G02X1438984Y855861I-2225J73D01*
G01X1438949Y855841D01*
G03Y853327I772J-1257D01*
G01X1438971Y853315D01*
X1438974Y853313D01*
X1438981Y853309D01*
X1438984Y853307D01*
G02X1440096Y851419I-1113J-1927D01*
G01Y851380D01*
G03X1440799Y850123I1475J0D01*
G01X1440834Y850103D01*
G02X1441946Y848215I-1113J-1927D01*
G01Y848142D01*
G03X1442683Y846899I1474J34D01*
G02X1442818Y846815I-1108J-1931D01*
G02X1443145Y846546I-1244J-1846D01*
G01X1445614Y844076D01*
Y832738D01*
X1445780Y832572D01*
Y832485D01*
G01X1437871Y896240D02*
X1438487Y897307D01*
X1438795Y897389D01*
G02X1439346Y896240I-924J-1150D01*
G01Y896201D01*
G03X1440458Y894313I2225J39D01*
G02X1441195Y893070I-737J-1277D01*
G01Y893036D01*
G03X1442284Y891123I2225J0D01*
G01X1442343Y891089D01*
G02X1443046Y889832I-772J-1257D01*
G01Y889745D01*
G03X1444157Y887904I2225J87D01*
G01X1444192Y887884D01*
G02X1444894Y886685I-772J-1257D01*
G02X1444895Y886587I-1474J-64D01*
G02X1444192Y885370I-1475J40D01*
G01X1444157Y885350D01*
G03X1443046Y883484I1114J-1927D01*
G01Y883362D01*
G03X1444157Y881496I2225J61D01*
G01X1444192Y881476D01*
G02X1444895Y880219I-772J-1257D01*
G01Y880189D01*
G03X1446008Y878291I2226J30D01*
G01X1446043Y878271D01*
G02X1446746Y877014I-772J-1257D01*
G01Y876975D01*
G03X1447858Y875087I2225J39D01*
G02X1448595Y873844I-737J-1277D01*
G01Y873771D01*
G03X1449707Y871883I2225J39D01*
G01X1449710Y871881D01*
X1449717Y871877D01*
X1449720Y871875D01*
X1449739Y871865D01*
X1449742Y871863D01*
G02Y869349I-772J-1257D01*
G01X1449707Y869329D01*
G03X1448595Y867474I1113J-1928D01*
G01Y867401D01*
G03X1449684Y865488I2225J0D01*
G01X1449743Y865454D01*
G02X1450446Y864197I-772J-1257D01*
G01Y864136D01*
G03X1451557Y862270I2225J61D01*
G01X1451592Y862250D01*
G02X1452295Y860993I-772J-1257D01*
G03X1453384Y859080I2225J0D01*
G01X1453435Y859051D01*
X1453443Y859046D01*
G02Y856532I-772J-1257D01*
G01X1453411Y856514D01*
X1453408Y856512D01*
G03X1453360Y852685I1112J-1928D01*
G01X1453443Y852637D01*
G02X1454146Y851380I-772J-1257D01*
G01Y851341D01*
G03X1455258Y849453I2225J39D01*
G02X1455995Y848210I-737J-1277D01*
G01Y848176D01*
G03X1457084Y846263I2225J0D01*
G01X1457108Y846249D01*
G02X1457414Y846014I-738J-1277D01*
G01X1459662Y843766D01*
Y842454D01*
X1459272Y842064D01*
Y841024D01*
X1459662Y840634D01*
Y839594D01*
X1459272Y839204D01*
Y838164D01*
X1459662Y837774D01*
Y834018D01*
X1459496Y833852D01*
Y833765D01*
G01X1439720Y899445D02*
X1439104Y898378D01*
X1439199Y898027D01*
G02X1439266Y897975I-1331J-1784D01*
G02X1440096Y896296I-1395J-1734D01*
G01Y896240D01*
G03X1440799Y894983I1475J0D01*
G01X1440834Y894963D01*
G02X1441946Y893075I-1113J-1927D01*
G01Y893002D01*
G03X1442683Y891759I1474J34D01*
G01X1442686Y891757D01*
X1442707Y891745D01*
G02X1443796Y889832I-1136J-1913D01*
G03X1443797Y889774I1475J-4D01*
G03X1444499Y888575I1474J58D01*
G01X1444534Y888555D01*
G02X1445645Y886714I-1114J-1928D01*
G01Y886566D01*
G02X1444534Y884700I-2225J61D01*
G01X1444499Y884680D01*
G03Y882166I773J-1257D01*
G01X1444553Y882135D01*
X1444558Y882132D01*
G02X1445646Y880219I-1138J-1913D01*
G03X1446349Y878962I1475J0D01*
G01X1446381Y878944D01*
X1446384Y878942D01*
G02X1447496Y877087I-1113J-1928D01*
G01Y877014D01*
G03X1448199Y875757I1475J0D01*
G01X1448234Y875737D01*
G02X1449346Y873849I-1113J-1927D01*
G01Y873776D01*
G03X1450083Y872533I1474J34D01*
G01X1450131Y872505D01*
G02X1450083Y868678I-1161J-1899D01*
G03X1449346Y867435I737J-1277D01*
G01Y867367D01*
G03X1450083Y866124I1474J34D01*
G01X1450086Y866122D01*
X1450107Y866110D01*
G02X1451196Y864197I-1136J-1913D01*
G03X1451899Y862940I1475J0D01*
G01X1451934Y862920D01*
G02X1453045Y861054I-1114J-1927D01*
G01Y860993D01*
G03X1453748Y859736I1475J0D01*
G01X1453807Y859702D01*
G02X1453784Y855861I-1136J-1914D01*
G01X1453749Y855841D01*
G03Y853327I772J-1257D01*
G01X1453781Y853309D01*
X1453784Y853307D01*
G02X1454896Y851419I-1113J-1927D01*
G01Y851380D01*
G03X1455599Y850123I1475J0D01*
G01X1455634Y850103D01*
G02X1456746Y848215I-1113J-1927D01*
G01Y848172D01*
X1456744Y848176D01*
G03X1457462Y846910I1475J0D01*
G01X1457484Y846897D01*
G02X1457944Y846544I-1113J-1926D01*
G01X1460412Y844076D01*
Y837775D01*
X1460411Y837774D01*
Y834017D01*
X1460576Y833852D01*
Y833765D01*
G01X1430471Y896240D02*
X1431087Y897307D01*
X1431437Y897400D01*
G03X1431515Y897368I884J2044D01*
G03X1434545Y899358I805J2077D01*
G01Y899445D01*
G02X1435248Y900702I1475J0D01*
G01X1435277Y900719D01*
X1435283Y900722D01*
X1435286Y900724D01*
X1435307Y900736D01*
G03X1436396Y902649I-1136J1913D01*
G02X1438608Y903926I1475J0D01*
G01X1438666Y903892D01*
G03X1440834Y903926I1054J1961D01*
G02X1443046Y902649I737J-1277D01*
G01Y902588D01*
G03X1446325Y900688I2225J61D01*
G01X1446383Y900722D01*
G02X1448595Y899445I737J-1277D01*
G01Y899389D01*
G03X1449708Y897517I2225J56D01*
G01X1449743Y897497D01*
G02X1450446Y896240I-772J-1257D01*
G01Y896179D01*
G03X1451557Y894313I2225J61D01*
G01X1451561Y894311D01*
X1451592Y894293D01*
G02X1452295Y893036I-772J-1257D01*
G03X1453360Y891137I2226J0D01*
G01X1453443Y891089D01*
G02X1454146Y889832I-772J-1257D01*
G01Y889745D01*
G03X1455257Y887904I2225J87D01*
G01X1455292Y887884D01*
G02X1455994Y886685I-772J-1257D01*
G02X1455995Y886587I-1474J-64D01*
G02X1455292Y885370I-1475J40D01*
G01X1455257Y885350D01*
G03X1455258Y881496I1114J-1927D01*
G02X1455995Y880253I-737J-1277D01*
G01Y880163D01*
G03X1457108Y878291I2225J56D01*
G01X1457143Y878271D01*
G02X1457846Y877014I-772J-1257D01*
G01Y876953D01*
G03X1458957Y875087I2225J61D01*
G01X1458992Y875067D01*
G02X1459695Y873810I-772J-1257D01*
G03X1460784Y871897I2225J0D01*
G01X1460835Y871868D01*
X1460843Y871863D01*
G02Y869349I-772J-1257D01*
G01X1460811Y869331D01*
X1460808Y869329D01*
G03X1460760Y865502I1112J-1928D01*
G01X1460843Y865454D01*
G02X1461546Y864197I-772J-1257D01*
G01Y864136D01*
G03X1462657Y862270I2225J61D01*
G01X1462692Y862250D01*
G02X1463395Y860993I-772J-1257D01*
G03X1464484Y859080I2225J0D01*
G01X1464535Y859051D01*
X1464543Y859046D01*
G02Y856532I-772J-1257D01*
G01X1464508Y856512D01*
G03X1463395Y854640I1112J-1928D01*
G01Y854584D01*
G03X1464484Y852671I2225J0D01*
G01X1464543Y852637D01*
G02X1465246Y851380I-772J-1257D01*
G01Y851319D01*
G03X1466357Y849453I2225J61D01*
G01X1466392Y849433D01*
G02X1467095Y848176I-772J-1257D01*
G01Y848115D01*
G03X1468206Y846249I2225J61D01*
G02X1468511Y846015I-738J-1277D01*
G01X1470956Y843570D01*
Y840496D01*
X1470566Y840106D01*
Y839066D01*
X1470956Y838676D01*
Y837636D01*
X1470566Y837246D01*
Y836206D01*
X1470956Y835816D01*
Y834776D01*
X1470566Y834386D01*
Y833346D01*
X1470956Y832956D01*
Y831947D01*
X1470791Y831782D01*
Y831695D01*
G01X1436020Y893036D02*
X1435404Y894103D01*
X1435499Y894454D01*
G03X1435566Y894506I-1330J1783D01*
G03X1436396Y896240I-1395J1733D01*
G02X1436397Y896298I1475J4D01*
G02X1437099Y897497I1474J-58D01*
G01X1437134Y897517D01*
G03X1438245Y899358I-1114J1928D01*
G01Y899445D01*
G02X1441195I1475J0D01*
G01Y899389D01*
G03X1444534Y897517I2226J56D01*
G02X1446746Y896240I737J-1277D01*
G01Y896201D01*
G03X1447858Y894313I2225J39D01*
G02X1448595Y893070I-737J-1277D01*
G01Y893036D01*
G03X1449684Y891123I2225J0D01*
G01X1449743Y891089D01*
G02X1450446Y889832I-772J-1257D01*
G01Y889745D01*
G03X1451557Y887904I2225J87D01*
G01X1451592Y887884D01*
G02X1452294Y886685I-772J-1257D01*
G02X1452295Y886587I-1474J-64D01*
G02X1451592Y885370I-1475J40D01*
G01X1451561Y885352D01*
X1451557Y885350D01*
G03X1450446Y883484I1114J-1927D01*
G01Y883362D01*
G03X1451557Y881496I2225J61D01*
G01X1451561Y881494D01*
X1451592Y881476D01*
G02X1452295Y880219I-772J-1257D01*
G01Y880189D01*
G03X1453408Y878291I2226J30D01*
G01X1453443Y878271D01*
G02X1454146Y877014I-772J-1257D01*
G01Y876953D01*
G03X1455257Y875087I2225J61D01*
G01X1455292Y875067D01*
G02X1455995Y873810I-772J-1257D01*
G03X1457084Y871897I2225J0D01*
G01X1457097Y871889D01*
X1457108Y871883D01*
X1457114Y871880D01*
X1457143Y871863D01*
G02Y869349I-772J-1257D01*
G01X1457108Y869329D01*
G03X1455995Y867457I1112J-1928D01*
G01Y867401D01*
G03X1457084Y865488I2225J0D01*
G01X1457108Y865474D01*
X1457143Y865454D01*
G02X1457846Y864197I-772J-1257D01*
G01Y864136D01*
G03X1458957Y862270I2225J61D01*
G01X1458992Y862250D01*
G02X1459695Y860993I-772J-1257D01*
G03X1460784Y859080I2225J0D01*
G01X1460835Y859051D01*
X1460843Y859046D01*
G02Y856532I-772J-1257D01*
G01X1460811Y856514D01*
X1460808Y856512D01*
G03X1460760Y852685I1112J-1928D01*
G01X1460843Y852637D01*
G02X1461546Y851380I-772J-1257D01*
G01Y851341D01*
G03X1462658Y849453I2225J39D01*
G02X1463395Y848210I-737J-1277D01*
G01Y848176D01*
G03X1464484Y846263I2225J0D01*
G01X1464508Y846249D01*
G02X1464814Y846014I-738J-1277D01*
G01X1467054Y843774D01*
Y841331D01*
X1466664Y840941D01*
Y839901D01*
X1467054Y839511D01*
Y837991D01*
X1466664Y837601D01*
Y836561D01*
X1467054Y836171D01*
Y835636D01*
X1466889Y835471D01*
Y835384D01*
G01X1441571Y896240D02*
X1442187Y895173D01*
X1442537Y895080D01*
G02X1442615Y895112I884J-2043D01*
G02X1444534Y894963I804J-2076D01*
G01X1444558Y894949D01*
G02X1445646Y893036I-1138J-1913D01*
G03X1446349Y891779I1475J0D01*
G01X1446381Y891761D01*
X1446384Y891759D01*
G02X1447496Y889871I-1113J-1927D01*
G01Y889832D01*
G03X1447497Y889774I1475J-4D01*
G03X1448199Y888575I1474J58D01*
G01X1448230Y888557D01*
X1448234Y888555D01*
G02X1449345Y886714I-1114J-1928D01*
G01Y886566D01*
G02X1448234Y884700I-2225J61D01*
G01X1448199Y884680D01*
G03X1447497Y883463I773J-1257D01*
G03Y883397I1475J-33D01*
G03X1448199Y882166I1475J25D01*
G01X1448234Y882146D01*
G02X1449346Y880258I-1113J-1927D01*
G01Y880185D01*
G03X1450083Y878942I1474J34D01*
G02X1451196Y877070I-1112J-1928D01*
G01Y877014D01*
G03X1451899Y875757I1475J0D01*
G01X1451934Y875737D01*
G02X1453045Y873871I-1114J-1927D01*
G01Y873810D01*
G03X1453748Y872553I1475J0D01*
G01X1453808Y872518D01*
X1453807Y872519D01*
G02X1454896Y870606I-1136J-1913D01*
G01Y870533D01*
G02X1453784Y868678I-2225J73D01*
G01X1453749Y868658D01*
G03Y866144I772J-1257D01*
G01X1453781Y866126D01*
X1453784Y866124D01*
G02X1454896Y864236I-1113J-1927D01*
G01Y864197D01*
G03X1455599Y862940I1475J0D01*
G01X1455634Y862920D01*
G02X1456745Y861054I-1114J-1927D01*
G01Y860993D01*
G03X1457448Y859736I1475J0D01*
G01X1457477Y859719D01*
X1457483Y859716D01*
X1457486Y859714D01*
X1457507Y859702D01*
G02X1458596Y857789I-1136J-1913D01*
G01Y857733D01*
G02X1457483Y855861I-2225J56D01*
G03X1456746Y854618I737J-1277D01*
G01Y854550D01*
G03X1457483Y853307I1474J34D01*
G01X1457486Y853305D01*
X1457497Y853299D01*
X1457507Y853293D01*
G02X1458596Y851380I-1136J-1913D01*
G03X1459299Y850123I1475J0D01*
G01X1459334Y850103D01*
G02X1460445Y848237I-1114J-1927D01*
G01Y848176D01*
G03X1461148Y846919I1475J0D01*
G01X1461180Y846898D01*
G02X1461641Y846545I-1110J-1927D01*
G01X1464147Y844039D01*
Y832817D01*
X1464312Y832652D01*
Y832565D01*
G01X1432320Y899445D02*
X1431704Y898378D01*
X1431787Y898071D01*
G03X1433794Y899387I533J1375D01*
G03X1433795Y899445I-1474J54D01*
G02X1434884Y901358I2225J0D01*
G01X1434897Y901366D01*
X1434908Y901372D01*
X1434914Y901375D01*
X1434943Y901392D01*
G03X1435646Y902649I-772J1257D01*
G01Y902710D01*
G02X1438925Y904610I2225J-61D01*
G01X1438983Y904576D01*
G03X1440457I737J1277D01*
G02X1443796Y902649I1113J-1927D01*
G03X1446008Y901372I1475J0D01*
G01X1446066Y901406D01*
G02X1449345Y899506I1054J-1961D01*
G01Y899445D01*
G03X1450048Y898188I1475J0D01*
G01X1450083Y898168D01*
G02X1451196Y896296I-1112J-1928D01*
G01Y896240D01*
G03X1451899Y894983I1475J0D01*
G01X1451943Y894958D01*
X1451958Y894949D01*
G02X1453046Y893036I-1138J-1913D01*
G03X1453749Y891779I1475J0D01*
G01X1453781Y891761D01*
X1453784Y891759D01*
G02X1454896Y889871I-1113J-1927D01*
G01Y889832D01*
G03X1454897Y889774I1475J-4D01*
G03X1455599Y888575I1474J58D01*
G01X1455634Y888555D01*
G02X1456745Y886714I-1114J-1928D01*
G01Y886566D01*
G02X1455634Y884700I-2225J61D01*
G01X1455599Y884680D01*
G03Y882166I772J-1257D01*
G01X1455634Y882146D01*
G02X1456746Y880258I-1113J-1927D01*
G01Y880185D01*
G03X1457483Y878942I1474J34D01*
G02X1458596Y877070I-1112J-1928D01*
G01Y877014D01*
G03X1459299Y875757I1475J0D01*
G01X1459334Y875737D01*
G02X1460445Y873871I-1114J-1927D01*
G01Y873810D01*
G03X1461148Y872553I1475J0D01*
G01X1461207Y872519D01*
G02X1461184Y868678I-1136J-1914D01*
G01X1461149Y868658D01*
G03Y866144I772J-1257D01*
G01X1461181Y866126D01*
X1461184Y866124D01*
G02X1462296Y864236I-1113J-1927D01*
G01Y864197D01*
G03X1462999Y862940I1475J0D01*
G01X1463034Y862920D01*
G02X1464145Y861054I-1114J-1927D01*
G01Y860993D01*
G03X1464848Y859736I1475J0D01*
G01X1464907Y859702D01*
G02X1464883Y855861I-1136J-1913D01*
G03X1464146Y854618I737J-1277D01*
G01Y854550D01*
G03X1464883Y853307I1474J34D01*
G01X1464886Y853305D01*
X1464907Y853293D01*
G02X1465996Y851380I-1136J-1913D01*
G03X1466699Y850123I1475J0D01*
G01X1466734Y850103D01*
G02X1467845Y848237I-1114J-1927D01*
G01Y848176D01*
G03X1468548Y846919I1475J0D01*
G01X1468580Y846898D01*
G02X1469041Y846545I-1110J-1927D01*
G01X1471705Y843881D01*
Y837467D01*
X1471706Y837466D01*
Y832957D01*
X1471705Y832956D01*
Y831948D01*
X1471871Y831782D01*
Y831695D01*
G01X1434171Y896240D02*
X1434787Y895173D01*
X1435095Y895091D01*
G03X1435646Y896240I-924J1150D01*
G01Y896327D01*
G02X1436757Y898168I2225J-87D01*
G01X1436792Y898188D01*
G03X1437494Y899387I-772J1257D01*
G03X1437495Y899445I-1474J54D01*
G02X1441945Y899506I2225J0D01*
G01Y899445D01*
G03X1444157Y898168I1475J0D01*
G02X1447496Y896296I1114J-1927D01*
G01Y896240D01*
G03X1448199Y894983I1475J0D01*
G01X1448234Y894963D01*
G02X1449346Y893075I-1113J-1927D01*
G01Y893002D01*
G03X1450083Y891759I1474J34D01*
G01X1450086Y891757D01*
X1450107Y891745D01*
G02X1451196Y889832I-1136J-1913D01*
G03X1451197Y889774I1475J-4D01*
G03X1451899Y888575I1474J58D01*
G01X1451930Y888557D01*
X1451934Y888555D01*
G02X1453045Y886714I-1114J-1928D01*
G01Y886566D01*
G02X1451934Y884700I-2225J61D01*
G01X1451899Y884680D01*
G03Y882166I773J-1257D01*
G01X1451943Y882141D01*
X1451958Y882132D01*
G02X1453046Y880219I-1138J-1913D01*
G03X1453749Y878962I1475J0D01*
G01X1453784Y878942D01*
G02X1454896Y877087I-1113J-1928D01*
G01Y877014D01*
G03X1455599Y875757I1475J0D01*
G01X1455634Y875737D01*
G02X1456745Y873871I-1114J-1927D01*
G01Y873810D01*
G03X1457448Y872553I1475J0D01*
G01X1457477Y872536D01*
X1457483Y872533D01*
X1457486Y872531D01*
X1457507Y872519D01*
G02X1457483Y868678I-1136J-1913D01*
G03X1456746Y867435I737J-1277D01*
G01Y867367D01*
G03X1457483Y866124I1474J34D01*
G01X1457498Y866115D01*
X1457507Y866110D01*
G02X1458596Y864197I-1136J-1913D01*
G03X1459299Y862940I1475J0D01*
G01X1459334Y862920D01*
G02X1460445Y861054I-1114J-1927D01*
G01Y860993D01*
G03X1461148Y859736I1475J0D01*
G01X1461207Y859702D01*
G02X1461184Y855861I-1136J-1914D01*
G01X1461149Y855841D01*
G03Y853327I772J-1257D01*
G01X1461173Y853313D01*
X1461181Y853309D01*
X1461184Y853307D01*
G02X1462296Y851419I-1113J-1927D01*
G01Y851380D01*
G03X1462999Y850123I1475J0D01*
G01X1463034Y850103D01*
G02X1464146Y848215I-1113J-1927D01*
G01Y848172D01*
X1464144Y848176D01*
G03X1464862Y846910I1475J0D01*
G01X1464886Y846896D01*
G02X1465344Y846544I-1115J-1925D01*
G01X1467803Y844085D01*
Y835637D01*
X1467969Y835471D01*
Y835384D01*
G01X1443420Y893036D02*
X1442804Y894103D01*
X1442887Y894410D01*
G02X1444157Y894313I534J-1374D01*
G01X1444161Y894311D01*
X1444192Y894293D01*
G02X1444895Y893036I-772J-1257D01*
G03X1445960Y891137I2226J0D01*
G01X1446008Y891109D01*
X1446043Y891089D01*
G02X1446746Y889832I-772J-1257D01*
G01Y889745D01*
G03X1447857Y887904I2225J87D01*
G01X1447892Y887884D01*
G02X1448594Y886685I-772J-1257D01*
G02X1448595Y886627I-1474J-54D01*
G02X1447892Y885370I-1475J0D01*
G01X1447857Y885350D01*
G03X1446746Y883484I1114J-1927D01*
G01Y883384D01*
G03X1447858Y881496I2225J39D01*
G02X1448595Y880253I-737J-1277D01*
G01Y880163D01*
G03X1449708Y878291I2225J56D01*
G01X1449743Y878271D01*
G02X1450446Y877014I-772J-1257D01*
G01Y876953D01*
G03X1451557Y875087I2225J61D01*
G01X1451592Y875067D01*
G02X1452295Y873810I-772J-1257D01*
G03X1453384Y871897I2225J0D01*
G01X1453405Y871885D01*
X1453408Y871883D01*
X1453435Y871868D01*
X1453443Y871863D01*
G02Y869349I-772J-1257D01*
G01X1453411Y869331D01*
X1453408Y869329D01*
G03X1452295Y867431I1113J-1928D01*
G01Y867401D01*
G03X1453360Y865502I2226J0D01*
G01X1453408Y865474D01*
X1453443Y865454D01*
G02X1454146Y864197I-772J-1257D01*
G01Y864136D01*
G03X1455257Y862270I2225J61D01*
G01X1455292Y862250D01*
G02X1455995Y860993I-772J-1257D01*
G03X1457084Y859080I2225J0D01*
G01X1457097Y859072D01*
X1457108Y859066D01*
X1457114Y859063D01*
X1457143Y859046D01*
G02Y856532I-772J-1257D01*
G01X1457108Y856512D01*
G03X1455995Y854640I1112J-1928D01*
G01Y854584D01*
G03X1457084Y852671I2225J0D01*
G01X1457103Y852660D01*
X1457112Y852654D01*
X1457120Y852649D01*
X1457130Y852644D01*
X1457143Y852636D01*
Y852637D01*
G02X1457846Y851380I-772J-1257D01*
G01Y851319D01*
G03X1458957Y849453I2225J61D01*
G01X1458992Y849433D01*
G02X1459695Y848176I-772J-1257D01*
G01Y848115D01*
G03X1460806Y846249I2225J61D01*
G02X1461111Y846015I-738J-1277D01*
G01X1463398Y843728D01*
Y838812D01*
X1463008Y838422D01*
Y837382D01*
X1463398Y836992D01*
Y835952D01*
X1463008Y835562D01*
Y834522D01*
X1463398Y834132D01*
Y832818D01*
X1463232Y832652D01*
Y832565D01*
G01X1424920Y899445D02*
X1424304Y898378D01*
X1424399Y898028D01*
G02X1424467Y897975I-1334J-1782D01*
G02X1425297Y896240I-1396J-1734D01*
G03X1426000Y894983I1475J0D01*
G01X1426031Y894965D01*
X1426035Y894963D01*
G02X1427146Y893097I-1114J-1927D01*
G01Y893036D01*
G03X1427849Y891779I1475J0D01*
G01X1427884Y891759D01*
G03X1429358I737J1277D01*
G02X1431584I1113J-1927D01*
G03X1433058I737J1277D01*
G02X1435242Y891783I1113J-1927D01*
G01X1435307Y891745D01*
G02X1436396Y889832I-1136J-1913D01*
G03X1436397Y889774I1475J-4D01*
G03X1437099Y888575I1474J58D01*
G01X1437134Y888555D01*
G03X1438608I737J1277D01*
G01X1438666Y888589D01*
G02X1440834Y888555I1053J-1962D01*
G02X1441945Y886714I-1114J-1928D01*
G01Y886566D01*
G02X1440834Y884700I-2225J61D01*
G01X1440799Y884680D01*
G03X1440097Y883463I773J-1257D01*
G03Y883397I1475J-33D01*
G03X1440799Y882166I1475J25D01*
G01X1440834Y882146D01*
G02X1441946Y880258I-1113J-1927D01*
G01Y880185D01*
G03X1442683Y878942I1474J34D01*
G02X1443796Y877070I-1112J-1928D01*
G01Y877014D01*
G03X1444499Y875757I1475J0D01*
G01X1444534Y875737D01*
X1444558Y875723D01*
G02X1445646Y873810I-1138J-1913D01*
G03X1446349Y872553I1475J0D01*
G01X1446384Y872533D01*
G02X1447496Y870645I-1113J-1927D01*
G01Y870533D01*
G02X1446384Y868678I-2225J73D01*
G01X1446349Y868658D01*
G03Y866144I772J-1257D01*
G01X1446381Y866126D01*
X1446384Y866124D01*
G02X1447496Y864236I-1113J-1927D01*
G01Y864197D01*
G03X1448199Y862940I1475J0D01*
G01X1448234Y862920D01*
G02X1449345Y861054I-1114J-1927D01*
G01Y860993D01*
G03X1450048Y859736I1475J0D01*
G01X1450077Y859719D01*
X1450083Y859716D01*
X1450086Y859714D01*
X1450107Y859702D01*
G02X1451196Y857789I-1136J-1913D01*
G01Y857733D01*
G02X1450083Y855861I-2225J56D01*
G03X1449346Y854618I737J-1277D01*
G01Y854550D01*
G03X1450083Y853307I1474J34D01*
G01X1450086Y853305D01*
X1450107Y853293D01*
G02X1451196Y851380I-1136J-1913D01*
G03X1451899Y850123I1475J0D01*
G01X1451934Y850103D01*
G02X1453045Y848237I-1114J-1927D01*
G01Y848176D01*
G03X1453748Y846919I1475J0D01*
G01X1453780Y846898D01*
G02X1454241Y846545I-1110J-1927D01*
G01X1456816Y843970D01*
Y833627D01*
X1456981Y833462D01*
Y833375D01*
G01X1423071Y896240D02*
X1423687Y897307D01*
X1423995Y897389D01*
G02X1424546Y896240I-924J-1150D01*
G03X1425634Y894327I2226J0D01*
G01X1425658Y894313D01*
X1425693Y894293D01*
G02X1426396Y893036I-772J-1257D01*
G01Y892997D01*
G03X1427508Y891109I2225J39D01*
G03X1429734I1113J1927D01*
G02X1431208I737J-1277D01*
G03X1433434I1113J1927D01*
G02X1434908I737J-1277D01*
G01X1434914Y891106D01*
X1434943Y891089D01*
G02X1435646Y889832I-772J-1257D01*
G01Y889745D01*
G03X1436757Y887904I2225J87D01*
G03X1438925Y887870I1115J1928D01*
G01X1438983Y887904D01*
G02X1440457I737J-1277D01*
G01X1440492Y887884D01*
G02X1441194Y886685I-772J-1257D01*
G02X1441195Y886627I-1474J-54D01*
G02X1440492Y885370I-1475J0D01*
G01X1440457Y885350D01*
G03X1439346Y883484I1114J-1927D01*
G01Y883384D01*
G03X1440458Y881496I2225J39D01*
G02X1441195Y880253I-737J-1277D01*
G01Y880163D01*
G03X1442308Y878291I2225J56D01*
G01X1442343Y878271D01*
G02X1443046Y877014I-772J-1257D01*
G01Y876953D01*
G03X1444157Y875087I2225J61D01*
G01X1444161Y875085D01*
X1444192Y875067D01*
G02X1444895Y873810I-772J-1257D01*
G03X1445960Y871911I2226J0D01*
G01X1446008Y871883D01*
G02X1446745Y870640I-737J-1277D01*
G01Y870572D01*
G02X1446008Y869329I-1474J34D01*
G03X1444895Y867431I1113J-1928D01*
G01Y867401D01*
G03X1445960Y865502I2226J0D01*
G01X1446008Y865474D01*
X1446043Y865454D01*
G02X1446746Y864197I-772J-1257D01*
G01Y864136D01*
G03X1447857Y862270I2225J61D01*
G01X1447892Y862250D01*
G02X1448595Y860993I-772J-1257D01*
G03X1449684Y859080I2225J0D01*
G01X1449697Y859072D01*
X1449708Y859066D01*
X1449714Y859063D01*
X1449743Y859046D01*
G02Y856532I-772J-1257D01*
G01X1449708Y856512D01*
G03X1448595Y854640I1112J-1928D01*
G01Y854584D01*
G03X1449684Y852671I2225J0D01*
G01X1449697Y852663D01*
X1449708Y852657D01*
X1449714Y852654D01*
X1449743Y852637D01*
G02X1450446Y851380I-772J-1257D01*
G01Y851319D01*
G03X1451557Y849453I2225J61D01*
G01X1451592Y849433D01*
G02X1452295Y848176I-772J-1257D01*
G01Y848115D01*
G03X1453406Y846249I2225J61D01*
G02X1453711Y846015I-738J-1277D01*
G01X1456067Y843659D01*
Y840288D01*
X1455677Y839898D01*
Y838858D01*
X1456067Y838468D01*
Y837428D01*
X1455677Y837038D01*
Y835998D01*
X1456067Y835608D01*
Y833628D01*
X1455901Y833462D01*
Y833375D01*
G01X1426772Y896240D02*
X1427388Y895173D01*
X1427695Y895091D01*
G03X1428246Y896206I-923J1150D01*
G01Y896327D01*
G02X1429357Y898168I2225J-87D01*
G01X1429392Y898188D01*
G03X1430094Y899387I-772J1257D01*
G03X1430095Y899445I-1474J54D01*
G02X1431184Y901358I2225J0D01*
G01X1431205Y901370D01*
X1431211Y901374D01*
X1431246Y901395D01*
X1431243Y901392D01*
G03X1431946Y902649I-772J1257D01*
G01Y902710D01*
G02X1433057Y904576I2225J-61D01*
G01X1433092Y904596D01*
G03X1433795Y905853I-772J1257D01*
G02X1437134Y907780I2225J0D01*
G03X1438608I737J1277D01*
G01X1438666Y907814D01*
G02X1440834Y907780I1054J-1961D01*
G03X1442308I737J1277D01*
G01X1442366Y907814D01*
G02X1445645Y905914I1054J-1961D01*
G01Y905853D01*
G03X1446348Y904596I1475J0D01*
G01X1446377Y904579D01*
X1446383Y904576D01*
G03X1447857I737J1277D01*
G02X1450025Y904610I1114J-1927D01*
G01X1450083Y904576D01*
X1450092Y904571D01*
X1450100Y904566D01*
X1450107Y904562D01*
G02X1451196Y902649I-1136J-1913D01*
G03X1451899Y901392I1475J0D01*
G01X1451934Y901372D01*
G02X1453045Y899506I-1114J-1927D01*
G01Y899445D01*
G03X1453748Y898188I1475J0D01*
G01X1453783Y898168D01*
G02X1454896Y896296I-1112J-1928D01*
G01Y896206D01*
G03X1455633Y894963I1474J34D01*
G01X1455657Y894949D01*
G02X1456746Y893036I-1136J-1913D01*
G01Y893002D01*
G03X1457483Y891759I1474J34D01*
G01X1457486Y891757D01*
X1457507Y891745D01*
G02X1458596Y889832I-1136J-1913D01*
G03X1458597Y889774I1475J-4D01*
G03X1459299Y888575I1474J58D01*
G01X1459334Y888555D01*
G02X1460445Y886714I-1114J-1928D01*
G01Y886566D01*
G02X1459334Y884700I-2225J61D01*
G01X1459299Y884680D01*
G03Y882166I773J-1257D01*
G01X1459332Y882147D01*
X1459343Y882141D01*
X1459358Y882132D01*
G02X1460446Y880219I-1138J-1913D01*
G03X1461149Y878962I1475J0D01*
G01X1461184Y878942D01*
G02X1462296Y877087I-1113J-1928D01*
G01Y877014D01*
G03X1462999Y875757I1475J0D01*
G01X1463034Y875737D01*
G02X1464145Y873871I-1114J-1927D01*
G01Y873810D01*
G03X1464848Y872553I1475J0D01*
G01X1464877Y872536D01*
X1464883Y872533D01*
X1464886Y872531D01*
X1464907Y872519D01*
G02X1464883Y868678I-1136J-1913D01*
G03X1464146Y867435I737J-1277D01*
G01Y867367D01*
G03X1464883Y866124I1474J34D01*
G01X1464886Y866122D01*
X1464907Y866110D01*
G02X1465996Y864197I-1136J-1913D01*
G03X1466699Y862940I1475J0D01*
G01X1466734Y862920D01*
G02X1467845Y861054I-1114J-1927D01*
G01Y860993D01*
G03X1468548Y859736I1475J0D01*
G01X1468607Y859702D01*
G02X1468584Y855861I-1136J-1914D01*
G01X1468549Y855841D01*
G03Y853327I772J-1257D01*
G01X1468573Y853313D01*
X1468581Y853309D01*
X1468584Y853307D01*
G02X1469696Y851419I-1113J-1927D01*
G01Y851380D01*
G03X1470399Y850123I1475J0D01*
G01X1470434Y850103D01*
G02X1471546Y848215I-1113J-1927D01*
G01Y848172D01*
X1471544Y848176D01*
G03X1472262Y846910I1475J0D01*
G01X1472286Y846896D01*
G02X1472744Y846544I-1115J-1925D01*
G01X1475230Y844058D01*
Y838223D01*
X1475231Y838222D01*
Y835168D01*
X1475230Y835167D01*
Y833947D01*
X1475395Y833782D01*
Y833695D01*
G01X1428621Y893036D02*
X1428005Y894103D01*
X1428100Y894454D01*
G03X1428997Y896240I-1326J1784D01*
G01Y896274D01*
G02X1429734Y897517I1474J-34D01*
G03X1430845Y899358I-1114J1928D01*
G01Y899445D01*
G02X1431548Y900702I1475J0D01*
G01X1431594Y900729D01*
X1431607Y900736D01*
G03X1432696Y902649I-1136J1913D01*
G02X1433399Y903906I1475J0D01*
G01X1433434Y903926D01*
G03X1434545Y905792I-1114J1927D01*
G01Y905853D01*
G02X1435248Y907110I1475J0D01*
G01X1435277Y907127D01*
X1435283Y907130D01*
G02X1436757I737J-1277D01*
G03X1438925Y907096I1114J1927D01*
G01X1438983Y907130D01*
G02X1440457I737J-1277D01*
G03X1442625Y907096I1114J1927D01*
G01X1442683Y907130D01*
G02X1444895Y905853I737J-1277D01*
G03X1448234Y903926I2225J0D01*
G02X1449708I737J-1277D01*
G01X1449714Y903923D01*
X1449743Y903906D01*
G02X1450446Y902649I-772J-1257D01*
G01Y902588D01*
G03X1451557Y900722I2225J61D01*
G01X1451561Y900720D01*
X1451592Y900702D01*
G02X1452295Y899445I-772J-1257D01*
G01Y899389D01*
G03X1453408Y897517I2225J56D01*
G02X1454145Y896274I-737J-1277D01*
G01Y896240D01*
G03X1455234Y894327I2225J0D01*
G01X1455258Y894313D01*
G02X1455995Y893070I-737J-1277D01*
G01Y893036D01*
G03X1457084Y891123I2225J0D01*
G01X1457143Y891089D01*
G02X1457846Y889832I-772J-1257D01*
G01Y889745D01*
G03X1458957Y887904I2225J87D01*
G01X1458992Y887884D01*
G02X1459694Y886685I-772J-1257D01*
G02X1459695Y886587I-1474J-64D01*
G02X1458992Y885370I-1475J40D01*
G01X1458961Y885352D01*
X1458957Y885350D01*
G03X1457846Y883484I1114J-1927D01*
G01Y883362D01*
G03X1458957Y881496I2225J61D01*
G01X1458961Y881494D01*
X1458992Y881476D01*
G02X1459695Y880219I-772J-1257D01*
G01Y880189D01*
G03X1460808Y878291I2226J30D01*
G01X1460843Y878271D01*
G02X1461546Y877014I-772J-1257D01*
G01Y876953D01*
G03X1462657Y875087I2225J61D01*
G01X1462692Y875067D01*
G02X1463395Y873810I-772J-1257D01*
G03X1464484Y871897I2225J0D01*
G01X1464497Y871889D01*
X1464508Y871883D01*
X1464514Y871880D01*
X1464543Y871863D01*
G02Y869349I-772J-1257D01*
G01X1464508Y869329D01*
G03X1463395Y867457I1112J-1928D01*
G01Y867401D01*
G03X1464484Y865488I2225J0D01*
G01X1464543Y865454D01*
G02X1465246Y864197I-772J-1257D01*
G01Y864136D01*
G03X1466357Y862270I2225J61D01*
G01X1466392Y862250D01*
G02X1467095Y860993I-772J-1257D01*
G03X1468184Y859080I2225J0D01*
G01X1468235Y859051D01*
X1468243Y859046D01*
G02Y856532I-772J-1257D01*
G01X1468211Y856514D01*
X1468208Y856512D01*
G03X1468160Y852685I1112J-1928D01*
G01X1468243Y852637D01*
G02X1468946Y851380I-772J-1257D01*
G01Y851341D01*
G03X1470058Y849453I2225J39D01*
G02X1470795Y848210I-737J-1277D01*
G01Y848176D01*
G03X1471884Y846263I2225J0D01*
G01X1471908Y846249D01*
G02X1472214Y846014I-738J-1277D01*
G01X1474481Y843747D01*
Y842707D01*
X1474091Y842317D01*
Y841277D01*
X1474481Y840887D01*
Y839847D01*
X1474091Y839457D01*
Y838417D01*
X1474481Y838027D01*
Y836987D01*
X1474091Y836597D01*
Y835557D01*
X1474481Y835167D01*
Y833948D01*
X1474315Y833782D01*
Y833695D01*
G54D19*
X1879155Y478898D03*
Y582848D03*
X1889155Y478898D03*
Y582848D03*
X1921395Y-9332D03*
X1931395D03*
Y582868D03*
X1921395D03*
X1942395Y603048D03*
Y1195248D03*
X1952395Y603048D03*
Y1195248D03*
G54D29*
G01X199164Y650481D02*
X194403Y655242D01*
X176508D01*
X164560Y667190D01*
Y672343D01*
X157781Y679122D01*
X113935D01*
X110522Y675709D01*
M02*
